# ODB++ job SA45_DaughterCard-RevX1_odb.tgz
### matrix/matrix

STEP {
    COL=1
    NAME=PCB
}


LAYER {
    ROW=1
    CONTEXT=BOARD
    TYPE=COMPONENT
    NAME=COMP_+_TOP
    POLARITY=POSITIVE
    START_NAME=
    END_NAME=
    OLD_NAME=
}

LAYER {
    ROW=2
    CONTEXT=BOARD
    TYPE=SOLDER_PASTE
    NAME=TOP_PASTE
    POLARITY=POSITIVE
    START_NAME=
    END_NAME=
    OLD_NAME=
}

LAYER {
    ROW=3
    CONTEXT=BOARD
    TYPE=SILK_SCREEN
    NAME=TOP_OVERLAY
    POLARITY=POSITIVE
    START_NAME=
    END_NAME=
    OLD_NAME=
}

LAYER {
    ROW=4
    CONTEXT=BOARD
    TYPE=SOLDER_MASK
    NAME=TOP_SOLDER
    POLARITY=POSITIVE
    START_NAME=
    END_NAME=
    OLD_NAME=
}

LAYER {
    ROW=5
    CONTEXT=BOARD
    TYPE=SIGNAL
    NAME=L01-TOP_LAYER
    POLARITY=POSITIVE
    START_NAME=
    END_NAME=
    OLD_NAME=
}

LAYER {
    ROW=6
    CONTEXT=BOARD
    TYPE=DIELECTRIC
    NAME=DIELECTRIC_1
    POLARITY=POSITIVE
    START_NAME=
    END_NAME=
    OLD_NAME=
    DIELECTRIC_TYPE=PREPREG
    DIELECTRIC_NAME=2x106
}

LAYER {
    ROW=7
    CONTEXT=BOARD
    TYPE=SIGNAL
    NAME=L02-INNER_LAYER
    POLARITY=POSITIVE
    START_NAME=
    END_NAME=
    OLD_NAME=
}

LAYER {
    ROW=8
    CONTEXT=BOARD
    TYPE=DIELECTRIC
    NAME=DIELECTRIC_2
    POLARITY=POSITIVE
    START_NAME=
    END_NAME=
    OLD_NAME=
    DIELECTRIC_TYPE=CORE
    DIELECTRIC_NAME=FR4
}

LAYER {
    ROW=9
    CONTEXT=BOARD
    TYPE=SIGNAL
    NAME=L03-INNER_LAYER
    POLARITY=POSITIVE
    START_NAME=
    END_NAME=
    OLD_NAME=
}

LAYER {
    ROW=10
    CONTEXT=BOARD
    TYPE=DIELECTRIC
    NAME=DIELECTRIC_3
    POLARITY=POSITIVE
    START_NAME=
    END_NAME=
    OLD_NAME=
    DIELECTRIC_TYPE=PREPREG
    DIELECTRIC_NAME=2x106
}

LAYER {
    ROW=11
    CONTEXT=BOARD
    TYPE=SIGNAL
    NAME=L04-BOTTOM_LAYER
    POLARITY=POSITIVE
    START_NAME=
    END_NAME=
    OLD_NAME=
}

LAYER {
    ROW=12
    CONTEXT=BOARD
    TYPE=SOLDER_MASK
    NAME=BOTTOM_SOLDER
    POLARITY=POSITIVE
    START_NAME=
    END_NAME=
    OLD_NAME=
}

LAYER {
    ROW=13
    CONTEXT=BOARD
    TYPE=SILK_SCREEN
    NAME=BOTTOM_OVERLAY
    POLARITY=POSITIVE
    START_NAME=
    END_NAME=
    OLD_NAME=
}

LAYER {
    ROW=14
    CONTEXT=BOARD
    TYPE=SOLDER_PASTE
    NAME=BOTTOM_PASTE
    POLARITY=POSITIVE
    START_NAME=
    END_NAME=
    OLD_NAME=
}

LAYER {
    ROW=15
    CONTEXT=BOARD
    TYPE=DRILL
    NAME=DRILL_NON-PLATED_BOTTOM-TOP
    POLARITY=POSITIVE
    START_NAME=L01-TOP_LAYER
    END_NAME=L04-BOTTOM_LAYER
    OLD_NAME=
}

LAYER {
    ROW=16
    CONTEXT=BOARD
    TYPE=DRILL
    NAME=DRILL_PLATED_BOTTOM-TOP
    POLARITY=POSITIVE
    START_NAME=L01-TOP_LAYER
    END_NAME=L04-BOTTOM_LAYER
    OLD_NAME=
}

LAYER {
    ROW=17
    CONTEXT=BOARD
    TYPE=COMPONENT
    NAME=COMP_+_BOT
    POLARITY=POSITIVE
    START_NAME=
    END_NAME=
    OLD_NAME=
}

LAYER {
    ROW=18
    CONTEXT=MISC
    TYPE=DOCUMENT
    NAME=M01_PCB_OUTLINE
    POLARITY=POSITIVE
    START_NAME=
    END_NAME=
    OLD_NAME=
}

### misc/info
UNITS=MM
PRODUCT_MODEL_NAME=odb
ODB_VERSION_MAJOR=8
ODB_VERSION_MINOR=0
ODB_SOURCE=Altium Designer
CREATION_DATE=20220928.133535
SAVE_DATE=20230124.173054
SAVE_APP=Altium Designer 23.1.1.15

### misc/attrlist
UNITS=MM
.customer = 
.comment = 
.technology = 
.global_camtek_aoiset = 
.drc_route_keepin_lyr = 
.drc_comp_keepin_lyr = 
.drc_tp_keepin_lyr = 
.drc_route_keepout_lyr = 
.drc_via_keepout_lyr = 
.drc_trace_keepout_lyr = 
.drc_trace_keepout_lyr = 
.drc_plane_keepout_lyr = 
.drc_pad_keepout_lyr = 
.drc_comp_keepout_lyr = 
.drc_comp_height_lyr = 
.drc_tp_keepout_lyr = 
.variant_list = 
.primary_side = top
.design_origin_x = 0
.design_origin_y = 0
.board_thickness = 1.57074108
_board_material = thermon

### steps/pcb/stephdr
UNITS=MM
X_DATUM=0.0000
Y_DATUM=0.0000

TOP_ACTIVE=0
BOTTOM_ACTIVE=0
RIGHT_ACTIVE=0
LEFT_ACTIVE=0
ONLINE_DRC_NAME=
ONLINE_DRC_MODE=DISABLED
ONLINE_DRC_STAT=RED
ONLINE_DRC_TIME=0
ONLINE_DRC_BEEP_VOL=2
ONLINE_DRC_BEEP_TONE=500
ONLINE_NET_MODE=DISABLED
ONLINE_NET_STAT=RED
ONLINE_NET_TIME=0
ONLINE_NET_BEEP_VOL=2
ONLINE_NET_BEEP_TONE=1000

### steps/pcb/attrlist
UNITS=MM
.out_drill_full = no
.out_drill_optional = no
.out_rout_optional = no
.array_with_rotation = no
.flipped_out_of_date = no
.comment = 
.out_name = 
.assembly_proc_top = 
.assembly_proc_bottom = 
.all_eda_layers = 
.etm_tester = 
.flipped_of = 
.pnl_scheme = 
.pnl_pcb = 
.pnl_class = 
.pnl_place = 
.fs_direction_top = right2left
.fs_direction_bottom = right2left
.smt_direction_top = right2left
.smt_direction_bottom = right2left
.viacap_layer = none
.etm_pin_style = regular
.etm_repear_fmt = none
.out_drill_order = 0
.out_rout_order = 0
.etm_adapter_h = 95250.000000
.gold_plating = no

### steps/pcb/layers/bottom_overlay/attrlist
UNITS=MM
.out_mirror = no
.lpol_done = no
.cu_base = no
.comment =
.inp_file =
.eda_layers = "BottomOverlay"
.out_angle = 0.0
.out_polarity = positive
.layer_hdi_type = buildup
.out_x_scale = 1.000000
.out_y_scale = 1.000000
.out_comp = 0.000000
.et_adjacency = 508.000000
.layer_dielectric = 0.00254

### steps/pcb/layers/bottom_paste/attrlist
UNITS=MM
.out_mirror = no
.lpol_done = no
.cu_base = no
.comment =
.inp_file =
.eda_layers = "BottomPaste"
.out_angle = 0.0
.out_polarity = positive
.layer_hdi_type = buildup
.out_x_scale = 1.000000
.out_y_scale = 1.000000
.out_comp = 0.000000
.et_adjacency = 508.000000
.layer_dielectric = 0.00254

### steps/pcb/layers/bottom_solder/attrlist
UNITS=MM
.out_mirror = no
.lpol_done = no
.cu_base = no
.comment =
.inp_file =
.eda_layers = "BottomSolderMask"
.out_angle = 0.0
.out_polarity = positive
.layer_hdi_type = buildup
.out_x_scale = 1.000000
.out_y_scale = 1.000000
.out_comp = 0.000000
.et_adjacency = 508.000000
.layer_dielectric = 0.01778
.loss_tangent = 0
.dielectric_constant = 3.5
.comment = Solder Resist

### steps/pcb/layers/dielectric_1/attrlist
UNITS=MM
.out_mirror = no
.lpol_done = no
.cu_base = no
.comment =
.inp_file =
.eda_layers = "Dielectric1"
.out_angle = 0.0
.out_polarity = positive
.layer_hdi_type = buildup
.out_x_scale = 1.000000
.out_y_scale = 1.000000
.out_comp = 0.000000
.et_adjacency = 508.000000
.layer_dielectric = 0.11735
.loss_tangent = 0
.dielectric_constant = 4.1
.comment = 2x106

### steps/pcb/layers/dielectric_2/attrlist
UNITS=MM
.out_mirror = no
.lpol_done = no
.cu_base = no
.comment =
.inp_file =
.eda_layers = "Dielectric2"
.out_angle = 0.0
.out_polarity = positive
.layer_hdi_type = buildup
.out_x_scale = 1.000000
.out_y_scale = 1.000000
.out_comp = 0.000000
.et_adjacency = 508.000000
.layer_dielectric = 1.12268
.loss_tangent = 0
.dielectric_constant = 4.2
.comment = FR4

### steps/pcb/layers/dielectric_3/attrlist
UNITS=MM
.out_mirror = no
.lpol_done = no
.cu_base = no
.comment =
.inp_file =
.eda_layers = "Dielectric3"
.out_angle = 0.0
.out_polarity = positive
.layer_hdi_type = buildup
.out_x_scale = 1.000000
.out_y_scale = 1.000000
.out_comp = 0.000000
.et_adjacency = 508.000000
.layer_dielectric = 0.11735
.loss_tangent = 0
.dielectric_constant = 4.1
.comment = 2x106

### steps/pcb/layers/drill_non-plated_bottom-top/attrlist
UNITS=MM
.out_mirror = no
.lpol_done = no
.cu_base = no
.comment =
.inp_file =
.eda_layers = ""
.out_angle = 0.0
.out_polarity = positive
.layer_hdi_type = buildup
.out_x_scale = 1.000000
.out_y_scale = 1.000000
.out_comp = 0.000000
.et_adjacency = 508.000000
.layer_dielectric = 0.00254

### steps/pcb/layers/drill_plated_bottom-top/attrlist
UNITS=MM
.out_mirror = no
.lpol_done = no
.cu_base = no
.comment =
.inp_file =
.eda_layers = ""
.out_angle = 0.0
.out_polarity = positive
.layer_hdi_type = buildup
.out_x_scale = 1.000000
.out_y_scale = 1.000000
.out_comp = 0.000000
.et_adjacency = 508.000000
.layer_dielectric = 0.00254

### steps/pcb/layers/l01-top_layer/attrlist
UNITS=MM
.out_mirror = no
.lpol_done = no
.cu_base = no
.comment =
.inp_file =
.eda_layers = "L01-TopLayer"
.out_angle = 0.0
.out_polarity = positive
.layer_hdi_type = buildup
.out_x_scale = 1.000000
.out_y_scale = 1.000000
.out_comp = 0.000000
.et_adjacency = 508.000000
.layer_dielectric = 0.11735
.copper_weight = 71.12
.dielectric_constant = 1

### steps/pcb/layers/l02-inner_layer/attrlist
UNITS=MM
.out_mirror = no
.lpol_done = no
.cu_base = no
.comment =
.inp_file =
.eda_layers = "L02-InnerLayer"
.out_angle = 0.0
.out_polarity = positive
.layer_hdi_type = buildup
.out_x_scale = 1.000000
.out_y_scale = 1.000000
.out_comp = 0.000000
.et_adjacency = 508.000000
.layer_dielectric = 1.12268
.copper_weight = 35.56
.dielectric_constant = 1

### steps/pcb/layers/l03-inner_layer/attrlist
UNITS=MM
.out_mirror = no
.lpol_done = no
.cu_base = no
.comment =
.inp_file =
.eda_layers = "L03-InnerLayer"
.out_angle = 0.0
.out_polarity = positive
.layer_hdi_type = buildup
.out_x_scale = 1.000000
.out_y_scale = 1.000000
.out_comp = 0.000000
.et_adjacency = 508.000000
.layer_dielectric = 0.11735
.copper_weight = 35.56
.dielectric_constant = 1

### steps/pcb/layers/l04-bottom_layer/attrlist
UNITS=MM
.out_mirror = no
.lpol_done = no
.cu_base = no
.comment =
.inp_file =
.eda_layers = "L04-BottomLayer"
.out_angle = 0.0
.out_polarity = positive
.layer_hdi_type = buildup
.out_x_scale = 1.000000
.out_y_scale = 1.000000
.out_comp = 0.000000
.et_adjacency = 508.000000
.layer_dielectric = 0.01778
.copper_weight = 71.12
.dielectric_constant = 1

### steps/pcb/layers/top_overlay/attrlist
UNITS=MM
.out_mirror = no
.lpol_done = no
.cu_base = no
.comment =
.inp_file =
.eda_layers = "TopOverlay"
.out_angle = 0.0
.out_polarity = positive
.layer_hdi_type = buildup
.out_x_scale = 1.000000
.out_y_scale = 1.000000
.out_comp = 0.000000
.et_adjacency = 508.000000
.layer_dielectric = 0.00254

### steps/pcb/layers/top_paste/attrlist
UNITS=MM
.out_mirror = no
.lpol_done = no
.cu_base = no
.comment =
.inp_file =
.eda_layers = "TopPaste"
.out_angle = 0.0
.out_polarity = positive
.layer_hdi_type = buildup
.out_x_scale = 1.000000
.out_y_scale = 1.000000
.out_comp = 0.000000
.et_adjacency = 508.000000
.layer_dielectric = 0.00254

### steps/pcb/layers/top_solder/attrlist
UNITS=MM
.out_mirror = no
.lpol_done = no
.cu_base = no
.comment =
.inp_file =
.eda_layers = "TopSolderMask"
.out_angle = 0.0
.out_polarity = positive
.layer_hdi_type = buildup
.out_x_scale = 1.000000
.out_y_scale = 1.000000
.out_comp = 0.000000
.et_adjacency = 508.000000
.layer_dielectric = 0.01778
.loss_tangent = 0
.dielectric_constant = 3.5
.comment = Solder Resist

### steps/pcb/profile
UNITS=MM
#
#Layer features
#
S P 0
OB -5.06000004 -2.06000096 I
OS -5.06000766 42.74000088
OS -5.06000004 42.74000088
OS -5.06000004 42.9366299
OS -5.00867172 43.32652498
OS -4.9068863 43.70638706
OS -4.75639384 44.0697112
OS -4.55976228 44.4102871
OS -4.32035966 44.72228038
OS -4.042283 45.00035704
OS -3.73028972 45.23975966
OS -3.38971382 45.43639122
OS -3.02638968 45.58688368
OS -2.6465276 45.6886691
OS -2.25663252 45.73999996
OS -2.06000096 45.73999996
OS -2.06000096 45.73999996
OS -2.16000076 45.74000504
OS 42.74000088 45.73999996
OS 42.9366299 45.73999996
OS 43.32652498 45.6886691
OS 43.70638706 45.58688368
OS 44.0697112 45.43639122
OS 44.4102871 45.23975966
OS 44.72228038 45.00035704
OS 45.00035704 44.72228038
OS 45.23975966 44.4102871
OS 45.43639122 44.0697112
OS 45.58688368 43.70638706
OS 45.6886691 43.32652498
OS 45.73999996 42.9366299
OS 45.73999996 42.74000088
OS 45.73999996 42.74000088
OS 45.73999742 42.74000088
OS 45.73999996 -2.06000096
OS 45.73999996 -2.25663252
OS 45.6886691 -2.6465276
OS 45.58688368 -3.02638968
OS 45.43639122 -3.38971382
OS 45.23975966 -3.73028972
OS 45.00035704 -4.042283
OS 44.72228038 -4.32035966
OS 44.4102871 -4.55976228
OS 44.0697112 -4.75639384
OS 43.70638706 -4.9068863
OS 43.32652498 -5.00867172
OS 42.9366299 -5.06000004
OS 42.74000088 -5.06000004
OS 42.74000088 -5.06000004
OS -2.06000096 -5.06000512
OS -2.06000096 -5.06000004
OS -2.25663252 -5.06000004
OS -2.6465276 -5.00867172
OS -3.02638968 -4.9068863
OS -3.38971382 -4.75639384
OS -3.73028972 -4.55976228
OS -4.042283 -4.32035966
OS -4.32035966 -4.042283
OS -4.55976228 -3.73028972
OS -4.75639384 -3.38971382
OS -4.9068863 -3.02638968
OS -5.00867172 -2.6465276
OS -5.06000004 -2.25663252
OS -5.06000004 -2.06000096
OE
SE

### steps/pcb/eda/data
# 1/24/2023 5:30:53 PM
#
HDR Altium Designer file - Version 1.0.0.30000
UNITS=MM
LYR dielectric_1 dielectric_2 dielectric_3 drill_non-plated_bottom-top drill_plated_bottom-top top_overlay top_paste l02-inner_layer l03-inner_layer bottom_solder m01_pcb_outline top_solder bottom_overlay l04-bottom_layer bottom_paste l01-top_layer 
#
#NET 0
NET $NONE$
SNT PLN S C 0.00
FID C 15 66
SNT PLN S C 0.00
FID C 15 60
SNT PLN S C 0.00
FID C 15 64
SNT PLN S C 0.00
FID C 15 61
SNT PLN S C 0.00
FID C 15 59
SNT PLN S C 0.00
FID C 15 62
SNT PLN S C 0.00
FID C 15 58
SNT PLN S C 0.00
FID C 15 63
SNT VIA
FID C 11 60
FID C 15 57
SNT VIA
FID C 11 24
FID C 15 25
SNT VIA
FID C 11 25
FID C 15 26
SNT TOP B 1 1
FID C 9 92
FID C 13 121
FID C 14 68
SNT TOP B 2 1
FID C 9 90
FID C 13 120
FID C 14 67
SNT TOP B 3 1
FID C 9 29
FID C 13 63
FID C 14 24
SNT VIA
FID C 9 113
FID C 13 142
SNT VIA
FID C 9 112
FID C 13 141
SNT VIA
FID C 9 24
FID C 13 59
SNT TOP B 21 4
FID C 9 74
FID C 13 105
FID C 14 54
SNT TOP B 0 1
FID C 9 31
FID C 13 64
FID C 14 25
SNT TOP B 1 0
FID H 4 18
FID C 9 91
FID C 11 46
SNT TOP B 2 0
FID H 4 17
FID C 9 89
FID C 11 45
SNT TOP B 3 0
FID H 4 3
FID C 9 28
FID C 11 29
SNT TOP B 30 0
FID H 3 1
FID C 9 78
FID C 11 44
FID C 13 109
FID C 15 43
SNT TOP T 0 0
FID H 4 11
FID C 9 39
FID C 11 38
FID C 13 71
FID C 15 36
SNT TOP T 0 1
FID H 4 10
FID C 9 36
FID C 11 35
FID C 13 69
FID C 15 34
SNT TOP B 0 0
FID H 4 4
FID C 9 30
FID C 11 30
SNT TOP T 1 1
FID H 4 9
FID C 9 37
FID C 11 36
FID C 13 70
FID C 15 35
SNT TOP T 1 0
FID H 4 12
FID C 9 38
FID C 11 37
FID C 13 72
FID C 15 37
SNT TOP B 29 0
FID H 3 0
FID C 9 77
FID C 11 43
FID C 13 108
FID C 15 42
#NET 1
NET NetR5_1
SNT TOP B 16 0
FID C 9 62
FID C 13 94
FID C 14 43
SNT TOP B 21 3
FID C 9 58
FID C 13 91
FID C 14 40
SNT TOP B 15 0
FID C 9 50
FID C 13 83
FID C 14 32
SNT TRC
FID C 13 25
SNT TRC
FID C 13 27
SNT TRC
FID C 13 28
SNT TRC
FID C 13 23
#NET 2
NET NetC9_1
SNT TOP B 16 1
FID C 9 63
FID C 13 95
FID C 14 44
SNT TOP B 17 0
FID C 9 64
FID C 13 96
FID C 14 45
SNT TRC
FID C 13 29
#NET 3
NET NetC4_2
SNT TOP B 19 0
FID C 9 46
FID C 13 79
FID C 14 28
SNT TOP B 28 1
FID C 9 48
FID C 13 81
FID C 14 30
SNT TOP B 21 2
FID C 9 57
FID C 13 90
FID C 14 39
SNT TOP B 14 1
FID C 9 47
FID C 13 80
FID C 14 29
SNT TRC
FID C 13 22
SNT TRC
FID C 13 19
SNT TRC
FID C 13 21
SNT TRC
FID C 13 20
SNT TRC
FID C 13 0
SNT TRC
FID C 13 1
#NET 4
NET SW
SNT PLN S C 0.00
FID C 13 144
SNT TOP B 24 1
FID C 9 76
FID C 13 107
FID C 14 56
SNT TOP B 21 6
FID C 9 72
FID C 13 103
FID C 14 52
SNT TOP B 21 8
FID C 9 65
FID C 13 97
FID C 14 46
SNT TOP B 18 0
FID C 9 79
FID C 13 110
FID C 14 57
SNT TRC
FID C 13 30
SNT TRC
FID C 13 31
SNT TRC
FID C 13 32
SNT TRC
FID C 13 34
SNT TRC
FID C 13 33
SNT TRC
FID C 13 38
SNT TRC
FID C 13 39
SNT TRC
FID C 13 40
SNT TRC
FID C 13 6
#NET 5
NET NetC3_1
SNT TOP B 24 0
FID C 9 75
FID C 13 106
FID C 14 55
SNT TOP B 21 5
FID C 9 73
FID C 13 104
FID C 14 53
SNT TRC
FID C 13 36
SNT TRC
FID C 13 37
SNT TRC
FID C 13 35
SNT TRC
FID C 13 4
SNT TRC
FID C 13 5
SNT TRC
FID C 13 3
#NET 6
NET +3.3V_OSC
SNT PLN S C 0.00
FID C 13 146
SNT TOP B 26 0
FID C 9 107
FID C 13 136
FID C 14 73
SNT TOP B 27 0
FID C 9 95
FID C 13 124
FID C 14 69
SNT TOP B 22 1
FID C 9 88
FID C 13 119
FID C 14 66
SNT TOP T 0 4
FID H 4 20
FID C 9 93
FID C 11 47
FID C 13 122
FID C 15 44
SNT TOP T 1 4
FID H 4 19
FID C 9 94
FID C 11 48
FID C 13 123
FID C 15 45
#NET 7
NET TX
SNT TOP B 7 0
FID H 4 13
FID C 7 63
FID C 9 40
FID C 11 39
FID C 13 73
FID C 15 38
SNT TOP T 0 2
FID H 4 8
FID C 7 61
FID C 9 34
FID C 11 33
FID C 13 67
FID C 15 32
SNT TOP T 1 2
FID H 4 7
FID C 7 62
FID C 9 35
FID C 11 34
FID C 13 68
FID C 15 33
SNT TRC
FID C 7 27
SNT TRC
FID C 7 30
SNT TRC
FID C 7 24
SNT TRC
FID C 7 26
SNT TRC
FID C 7 25
SNT TRC
FID C 7 0
SNT TRC
FID C 7 4
SNT TRC
FID C 7 3
SNT TRC
FID C 7 1
#NET 8
NET RX
SNT TOP B 6 0
FID H 4 14
FID C 7 64
FID C 9 41
FID C 11 40
FID C 13 74
FID C 15 39
SNT TOP T 0 3
FID H 4 5
FID C 7 59
FID C 9 32
FID C 11 31
FID C 13 65
FID C 15 30
SNT TOP T 1 3
FID H 4 6
FID C 7 60
FID C 9 33
FID C 11 32
FID C 13 66
FID C 15 31
SNT TRC
FID C 7 28
SNT TRC
FID C 7 23
SNT TRC
FID C 7 31
SNT TRC
FID C 7 33
SNT TRC
FID C 7 32
SNT TRC
FID C 7 29
SNT TRC
FID C 7 2
SNT TRC
FID C 7 5
SNT TRC
FID C 7 6
#NET 9
NET RF_OUTPUT
SNT TOP T 0 8
FID H 4 28
FID C 9 103
FID C 11 56
FID C 13 132
FID C 15 53
SNT TOP T 1 8
FID H 4 27
FID C 9 102
FID C 11 55
FID C 13 131
FID C 15 52
SNT TOP B 11 0
FID H 4 30
FID C 9 110
FID C 11 58
FID C 13 139
FID C 15 55
SNT TRC
FID C 13 51
SNT TRC
FID C 13 47
SNT TRC
FID C 13 8
#NET 10
NET NC
SNT TOP B 13 0
FID H 4 29
FID C 9 109
FID C 11 57
FID C 13 138
FID C 15 54
#NET 11
NET LOCK
SNT TOP B 8 0
FID H 4 2
FID C 9 27
FID C 11 28
FID C 13 62
FID C 15 29
#NET 12
NET 1PPS_OUT
SNT TOP T 0 7
FID H 4 26
FID C 7 72
FID C 9 101
FID C 11 54
FID C 13 130
FID C 15 51
SNT TOP T 1 7
FID H 4 25
FID C 7 71
FID C 9 100
FID C 11 53
FID C 13 129
FID C 15 50
SNT TOP B 4 0
FID H 4 16
FID C 7 66
FID C 9 45
FID C 11 42
FID C 13 78
FID C 15 41
SNT TRC
FID C 7 48
SNT TRC
FID C 7 40
SNT TRC
FID C 7 38
SNT TRC
FID C 7 37
SNT TRC
FID C 7 36
SNT TRC
FID C 7 39
SNT TRC
FID C 7 12
SNT TRC
FID C 7 10
SNT TRC
FID C 7 8
#NET 13
NET 1PPS_IN
SNT TOP B 23 1
FID C 9 106
FID C 13 135
FID C 14 72
SNT TOP B 5 0
FID H 4 15
FID C 7 65
FID C 9 42
FID C 11 41
FID C 13 75
FID C 15 40
SNT TOP T 0 6
FID H 4 23
FID C 7 69
FID C 9 98
FID C 11 51
FID C 13 127
FID C 15 48
SNT TOP T 1 6
FID H 4 24
FID C 7 70
FID C 9 99
FID C 11 52
FID C 13 128
FID C 15 49
SNT TRC
FID C 7 34
SNT TRC
FID C 7 35
SNT TRC
FID C 7 42
SNT TRC
FID C 7 41
SNT TRC
FID C 13 46
SNT TRC
FID C 13 48
SNT TRC
FID C 7 7
SNT TRC
FID C 7 9
SNT TRC
FID C 7 11
SNT TRC
FID C 13 7
#NET 14
NET GND
SNT PLN S C 0.00
FID C 15 65
SNT PLN S C 0.00
FID C 15 67
SNT PLN S C 0.00
FID C 13 147
SNT PLN S C 0.00
FID C 7 74
SNT PLN S C 0.00
FID C 8 28
SNT TOP B 19 1
FID C 9 43
FID C 13 76
FID C 14 26
SNT TOP B 26 1
FID C 9 108
FID C 13 137
FID C 14 74
SNT TOP B 32 1
FID C 9 81
FID C 13 112
FID C 14 59
SNT TOP B 33 1
FID C 9 66
FID C 13 98
FID C 14 47
SNT TOP B 34 1
FID C 9 67
FID C 13 99
FID C 14 48
SNT TOP B 35 1
FID C 9 69
FID C 13 101
FID C 14 50
SNT TOP B 17 1
FID C 9 55
FID C 13 88
FID C 14 37
SNT TOP B 20 1
FID C 9 82
FID C 13 113
FID C 14 60
SNT TOP B 27 1
FID C 9 104
FID C 13 133
FID C 14 70
SNT TOP B 31 1
FID C 9 80
FID C 13 111
FID C 14 58
SNT TOP B 25 1
FID C 9 68
FID C 13 100
FID C 14 49
SNT TOP B 21 7
FID C 9 70
FID C 13 102
FID C 14 51
SNT TOP B 15 1
FID C 9 51
FID C 13 84
FID C 14 33
SNT TOP B 23 0
FID C 9 105
FID C 13 134
FID C 14 71
SNT TOP B 12 0
FID H 4 31
FID C 7 73
FID C 8 27
FID C 9 111
FID C 11 59
FID C 13 140
FID C 15 56
SNT TOP T 0 5
FID H 4 22
FID C 7 67
FID C 8 25
FID C 9 96
FID C 11 49
FID C 13 125
FID C 15 46
SNT TOP T 1 5
FID H 4 21
FID C 7 68
FID C 8 26
FID C 9 97
FID C 11 50
FID C 13 126
FID C 15 47
SNT TOP B 10 0
FID H 4 1
FID C 7 58
FID C 8 24
FID C 9 26
FID C 11 27
FID C 13 61
FID C 15 28
SNT TRC
FID C 15 17
SNT VIA
FID H 4 71
FID C 7 120
FID C 8 74
FID C 13 193
FID C 15 113
SNT VIA
FID H 4 72
FID C 7 121
FID C 8 75
FID C 13 194
FID C 15 114
SNT VIA
FID H 4 73
FID C 7 122
FID C 8 76
FID C 13 195
FID C 15 115
SNT VIA
FID H 4 66
FID C 7 115
FID C 8 69
FID C 13 188
FID C 15 108
SNT VIA
FID H 4 67
FID C 7 116
FID C 8 70
FID C 13 189
FID C 15 109
SNT VIA
FID H 4 76
FID C 7 125
FID C 8 79
FID C 13 198
FID C 15 118
SNT VIA
FID H 4 74
FID C 7 123
FID C 8 77
FID C 13 196
FID C 15 116
SNT VIA
FID H 4 68
FID C 7 117
FID C 8 71
FID C 13 190
FID C 15 110
SNT VIA
FID H 4 69
FID C 7 118
FID C 8 72
FID C 13 191
FID C 15 111
SNT VIA
FID H 4 70
FID C 7 119
FID C 8 73
FID C 13 192
FID C 15 112
SNT VIA
FID H 4 63
FID C 7 112
FID C 8 66
FID C 13 185
FID C 15 105
SNT VIA
FID H 4 64
FID C 7 113
FID C 8 67
FID C 13 186
FID C 15 106
SNT VIA
FID H 4 62
FID C 7 111
FID C 8 65
FID C 13 184
FID C 15 104
SNT VIA
FID H 4 61
FID C 7 110
FID C 8 64
FID C 13 183
FID C 15 103
SNT VIA
FID H 4 65
FID C 7 114
FID C 8 68
FID C 13 187
FID C 15 107
SNT VIA
FID H 4 56
FID C 7 105
FID C 8 59
FID C 13 178
FID C 15 98
SNT VIA
FID H 4 75
FID C 7 124
FID C 8 78
FID C 13 197
FID C 15 117
SNT VIA
FID H 4 58
FID C 7 107
FID C 8 61
FID C 13 180
FID C 15 100
SNT VIA
FID H 4 59
FID C 7 108
FID C 8 62
FID C 13 181
FID C 15 101
SNT VIA
FID H 4 81
FID C 7 130
FID C 8 84
FID C 13 203
FID C 15 123
SNT VIA
FID H 4 80
FID C 7 129
FID C 8 83
FID C 13 202
FID C 15 122
SNT VIA
FID H 4 77
FID C 7 126
FID C 8 80
FID C 13 199
FID C 15 119
SNT VIA
FID H 4 94
FID C 7 143
FID C 8 97
FID C 13 216
FID C 15 136
SNT VIA
FID H 4 93
FID C 7 142
FID C 8 96
FID C 13 215
FID C 15 135
SNT VIA
FID H 4 55
FID C 7 104
FID C 8 58
FID C 13 177
FID C 15 97
SNT VIA
FID H 4 53
FID C 7 102
FID C 8 56
FID C 13 175
FID C 15 95
SNT VIA
FID H 4 54
FID C 7 103
FID C 8 57
FID C 13 176
FID C 15 96
SNT VIA
FID H 4 52
FID C 7 101
FID C 8 55
FID C 13 174
FID C 15 94
SNT VIA
FID H 4 91
FID C 7 140
FID C 8 94
FID C 13 213
FID C 15 133
SNT VIA
FID H 4 88
FID C 7 137
FID C 8 91
FID C 13 210
FID C 15 130
SNT VIA
FID H 4 89
FID C 7 138
FID C 8 92
FID C 13 211
FID C 15 131
SNT VIA
FID H 4 83
FID C 7 132
FID C 8 86
FID C 13 205
FID C 15 125
SNT VIA
FID H 4 78
FID C 7 127
FID C 8 81
FID C 13 200
FID C 15 120
SNT VIA
FID H 4 79
FID C 7 128
FID C 8 82
FID C 13 201
FID C 15 121
SNT VIA
FID H 4 32
FID C 7 81
FID C 8 35
FID C 13 154
FID C 15 74
SNT VIA
FID H 4 33
FID C 7 82
FID C 8 36
FID C 13 155
FID C 15 75
SNT VIA
FID H 4 34
FID C 7 83
FID C 8 37
FID C 13 156
FID C 15 76
SNT VIA
FID H 4 35
FID C 7 84
FID C 8 38
FID C 13 157
FID C 15 77
SNT VIA
FID H 4 36
FID C 7 85
FID C 8 39
FID C 13 158
FID C 15 78
SNT VIA
FID H 4 37
FID C 7 86
FID C 8 40
FID C 13 159
FID C 15 79
SNT VIA
FID H 4 38
FID C 7 87
FID C 8 41
FID C 13 160
FID C 15 80
SNT VIA
FID H 4 39
FID C 7 88
FID C 8 42
FID C 13 161
FID C 15 81
SNT VIA
FID H 4 40
FID C 7 89
FID C 8 43
FID C 13 162
FID C 15 82
SNT VIA
FID H 4 41
FID C 7 90
FID C 8 44
FID C 13 163
FID C 15 83
SNT VIA
FID H 4 42
FID C 7 91
FID C 8 45
FID C 13 164
FID C 15 84
SNT VIA
FID H 4 43
FID C 7 92
FID C 8 46
FID C 13 165
FID C 15 85
SNT VIA
FID H 4 44
FID C 7 93
FID C 8 47
FID C 13 166
FID C 15 86
SNT VIA
FID H 4 115
FID C 7 164
FID C 8 118
FID C 13 237
FID C 15 157
SNT VIA
FID H 4 114
FID C 7 163
FID C 8 117
FID C 13 236
FID C 15 156
SNT VIA
FID H 4 113
FID C 7 162
FID C 8 116
FID C 13 235
FID C 15 155
SNT VIA
FID H 4 112
FID C 7 161
FID C 8 115
FID C 13 234
FID C 15 154
SNT VIA
FID H 4 111
FID C 7 160
FID C 8 114
FID C 13 233
FID C 15 153
SNT VIA
FID H 4 110
FID C 7 159
FID C 8 113
FID C 13 232
FID C 15 152
SNT VIA
FID H 4 109
FID C 7 158
FID C 8 112
FID C 13 231
FID C 15 151
SNT VIA
FID H 4 108
FID C 7 157
FID C 8 111
FID C 13 230
FID C 15 150
SNT VIA
FID H 4 107
FID C 7 156
FID C 8 110
FID C 13 229
FID C 15 149
SNT VIA
FID H 4 106
FID C 7 155
FID C 8 109
FID C 13 228
FID C 15 148
SNT VIA
FID H 4 105
FID C 7 154
FID C 8 108
FID C 13 227
FID C 15 147
SNT VIA
FID H 4 104
FID C 7 153
FID C 8 107
FID C 13 226
FID C 15 146
SNT VIA
FID H 4 103
FID C 7 152
FID C 8 106
FID C 13 225
FID C 15 145
SNT VIA
FID H 4 102
FID C 7 151
FID C 8 105
FID C 13 224
FID C 15 144
SNT VIA
FID H 4 101
FID C 7 150
FID C 8 104
FID C 13 223
FID C 15 143
SNT VIA
FID H 4 100
FID C 7 149
FID C 8 103
FID C 13 222
FID C 15 142
SNT VIA
FID H 4 99
FID C 7 148
FID C 8 102
FID C 13 221
FID C 15 141
SNT VIA
FID H 4 98
FID C 7 147
FID C 8 101
FID C 13 220
FID C 15 140
SNT VIA
FID H 4 97
FID C 7 146
FID C 8 100
FID C 13 219
FID C 15 139
SNT VIA
FID H 4 96
FID C 7 145
FID C 8 99
FID C 13 218
FID C 15 138
SNT VIA
FID H 4 95
FID C 7 144
FID C 8 98
FID C 13 217
FID C 15 137
SNT VIA
FID H 4 45
FID C 7 94
FID C 8 48
FID C 13 167
FID C 15 87
SNT VIA
FID H 4 46
FID C 7 95
FID C 8 49
FID C 13 168
FID C 15 88
SNT VIA
FID H 4 47
FID C 7 96
FID C 8 50
FID C 13 169
FID C 15 89
SNT VIA
FID H 4 48
FID C 7 97
FID C 8 51
FID C 13 170
FID C 15 90
SNT VIA
FID H 4 49
FID C 7 98
FID C 8 52
FID C 13 171
FID C 15 91
SNT VIA
FID H 4 50
FID C 7 99
FID C 8 53
FID C 13 172
FID C 15 92
SNT VIA
FID H 4 51
FID C 7 100
FID C 8 54
FID C 13 173
FID C 15 93
SNT VIA
FID H 4 57
FID C 7 106
FID C 8 60
FID C 13 179
FID C 15 99
SNT VIA
FID H 4 60
FID C 7 109
FID C 8 63
FID C 13 182
FID C 15 102
SNT VIA
FID H 4 82
FID C 7 131
FID C 8 85
FID C 13 204
FID C 15 124
SNT VIA
FID H 4 84
FID C 7 133
FID C 8 87
FID C 13 206
FID C 15 126
SNT VIA
FID H 4 85
FID C 7 134
FID C 8 88
FID C 13 207
FID C 15 127
SNT VIA
FID H 4 86
FID C 7 135
FID C 8 89
FID C 13 208
FID C 15 128
SNT VIA
FID H 4 87
FID C 7 136
FID C 8 90
FID C 13 209
FID C 15 129
SNT VIA
FID H 4 90
FID C 7 139
FID C 8 93
FID C 13 212
FID C 15 132
SNT VIA
FID H 4 92
FID C 7 141
FID C 8 95
FID C 13 214
FID C 15 134
#NET 15
NET +5V
SNT PLN S C 0.00
FID C 13 143
SNT TOP B 33 0
FID C 9 61
FID C 13 93
FID C 14 42
SNT TOP B 34 0
FID C 9 52
FID C 13 85
FID C 14 34
SNT TOP B 35 0
FID C 9 54
FID C 13 87
FID C 14 36
SNT TOP B 25 0
FID C 9 53
FID C 13 86
FID C 14 35
SNT TOP B 21 0
FID C 9 60
FID C 13 92
FID C 14 41
SNT TOP B 21 1
FID C 9 56
FID C 13 89
FID C 14 38
SNT TOP B 9 0
FID H 4 0
FID C 9 25
FID C 11 26
FID C 13 60
FID C 15 27
SNT TRC
FID C 13 26
SNT TRC
FID C 13 24
SNT TRC
FID C 13 2
#NET 16
NET +3.3V
SNT PLN S C 0.00
FID C 13 145
SNT TOP B 28 0
FID C 9 49
FID C 13 82
FID C 14 31
SNT TOP B 32 0
FID C 9 85
FID C 13 116
FID C 14 63
SNT TOP B 20 0
FID C 9 83
FID C 13 114
FID C 14 61
SNT TOP B 31 0
FID C 9 84
FID C 13 115
FID C 14 62
SNT TOP B 18 1
FID C 9 86
FID C 13 117
FID C 14 64
SNT TOP B 14 0
FID C 9 44
FID C 13 77
FID C 14 27
SNT TOP B 22 0
FID C 9 87
FID C 13 118
FID C 14 65
# PKG 0
PKG CAPC0603X033N 0.65999868 -0.55999888 -0.20999958 0.55999888 0.20999958
CT
OB 0.30008068 -0.14988032 I
OS -0.29991812 -0.14988032
OS -0.29991812 0.15011908
OS 0.30008068 0.15011908
OS 0.30008068 -0.14988032
OE
CE
PIN 1 S -0.32999934 0 0 U U
CT
OB -0.55999888 0.20999958 I
OS -0.0999998 0.20999958
OS -0.0999998 -0.20999958
OS -0.55999888 -0.20999958
OS -0.55999888 0.20999958
OE
CE
PIN 2 S 0.32999934 0 0 U U
CT
OB 0.0999998 0.20999958 I
OS 0.55999888 0.20999958
OS 0.55999888 -0.20999958
OS 0.0999998 -0.20999958
OS 0.0999998 0.20999958
OE
CE
#
# PKG 1
PKG CAPC1005X055N 0.91999816 -0.75999848 -0.30999938 0.75999848 0.30999938
CT
OB 0.50008028 -0.24989282 I
OS -0.49991772 -0.24989282
OS -0.49991772 0.25010618
OS 0.50008028 0.25010618
OS 0.50008028 -0.24989282
OE
CE
PIN 1 S -0.45999908 0 0 U U
CT
OB -0.75999848 0.30999938 I
OS -0.15999968 0.30999938
OS -0.15999968 -0.30999938
OS -0.75999848 -0.30999938
OS -0.75999848 0.30999938
OE
CE
PIN 2 S 0.45999908 0 0 U U
CT
OB 0.15999968 0.30999938 I
OS 0.75999848 0.30999938
OS 0.75999848 -0.30999938
OS 0.15999968 -0.30999938
OS 0.15999968 0.30999938
OE
CE
#
# PKG 2
PKG CAPC1005X061N 0.91999816 -0.75999848 -0.30999938 0.75999848 0.30999938
CT
OB 0.49995328 -0.24991822 I
OS -0.50004472 -0.24991822
OS -0.50004472 0.25008078
OS 0.49995328 0.25008078
OS 0.49995328 -0.24991822
OE
CE
PIN 1 S -0.45999908 0 0 U U
CT
OB -0.75999848 0.30999938 I
OS -0.15999968 0.30999938
OS -0.15999968 -0.30999938
OS -0.75999848 -0.30999938
OS -0.75999848 0.30999938
OE
CE
PIN 2 S 0.45999908 0 0 U U
CT
OB 0.15999968 0.30999938 I
OS 0.75999848 0.30999938
OS 0.75999848 -0.30999938
OS 0.15999968 -0.30999938
OS 0.15999968 0.30999938
OE
CE
#
# PKG 3
PKG CAPC2013X140N 1.80000148 -1.54999944 -0.82499708 1.54999944 0.82500216
CT
OB 0.99991926 -0.6249543 I
OS -1.00008182 -0.6249543
OS -1.00008182 0.62504574
OS 0.99991926 0.62504574
OS 0.99991926 -0.6249543
OE
CE
PIN 1 S -0.90000074 0.00000254 0 U U
CT
OB -1.55000071 0.82500216 I
OS -0.25000077 0.82500216
OS -0.25000077 -0.82499708
OS -1.55000071 -0.82499708
OS -1.55000071 0.82500216
OE
CE
PIN 2 S 0.90000074 0.00000254 0 U U
CT
OB 0.25000077 0.82500216 I
OS 1.55000071 0.82500216
OS 1.55000071 -0.82499708
OS 0.25000077 -0.82499708
OS 0.25000077 0.82500216
OE
CE
#
# PKG 4
PKG CAPC2013X145N 1.80000148 -1.54999944 -0.82499708 1.54999944 0.82500216
CT
OB 1.00005642 -0.62491874 I
OS -0.99994466 -0.62491874
OS -0.99994466 0.6250813
OS 1.00005642 0.6250813
OS 1.00005642 -0.62491874
OE
CE
PIN 1 S -0.90000074 0.00000254 0 U U
CT
OB -1.55000071 0.82500216 I
OS -0.25000077 0.82500216
OS -0.25000077 -0.82499708
OS -1.55000071 -0.82499708
OS -1.55000071 0.82500216
OE
CE
PIN 2 S 0.90000074 0.00000254 0 U U
CT
OB 0.25000077 0.82500216 I
OS 1.55000071 0.82500216
OS 1.55000071 -0.82499708
OS 0.25000077 -0.82499708
OS 0.25000077 0.82500216
OE
CE
#
# PKG 5
PKG DiodesInc_AP63356QZV-7 0.4499991 -1.1499977 -1.13124996 1.15000024 1.9750024
CT
OB 1.00000308 -1.13124996 I
OS -0.999998 -1.13124996
OS -0.999998 1.86875166
OS 1.00000308 1.86875166
OS 1.00000308 -1.13124996
OE
CE
PIN 1 S -0.7499985 0.97500186 0 U U
CT
OB -1.14999897 1.70000168 I
OS -0.34999803 1.70000168
OS -0.34999803 0.25000204
OS -1.14999897 0.25000204
OS -1.14999897 1.70000168
OE
CE
PIN 2 S -0.8499983 -0.07499858 0 U U
CT
OB -1.1499977 0.07500112 I
OS -0.5499989 0.07500112
OS -0.5499989 -0.22499828
OS -1.1499977 -0.22499828
OS -1.1499977 0.07500112
OE
CE
PIN 3 S -0.8499983 -0.52499768 0 U U
CT
OB -1.1499977 -0.37499798 I
OS -0.5499989 -0.37499798
OS -0.5499989 -0.67499738
OS -1.1499977 -0.67499738
OS -1.1499977 -0.37499798
OE
CE
PIN 4 S -0.8499983 -0.97499932 0 U U
CT
OB -1.1499977 -0.82499962 I
OS -0.5499989 -0.82499962
OS -0.5499989 -1.12499902
OS -1.1499977 -1.12499902
OS -1.1499977 -0.82499962
OE
CE
PIN 5 S 0.85000084 -0.97499932 0 U U
CT
OB 0.55000144 -0.82499962 I
OS 1.15000024 -0.82499962
OS 1.15000024 -1.12499902
OS 0.55000144 -1.12499902
OS 0.55000144 -0.82499962
OE
CE
PIN 6 S 0.85000084 -0.52499768 0 U U
CT
OB 0.55000144 -0.37499798 I
OS 1.15000024 -0.37499798
OS 1.15000024 -0.67499738
OS 0.55000144 -0.67499738
OS 0.55000144 -0.37499798
OE
CE
PIN 7 S 0.85000084 -0.07499858 0 U U
CT
OB 0.55000144 0.07500112 I
OS 1.15000024 0.07500112
OS 1.15000024 -0.22499828
OS 0.55000144 -0.22499828
OS 0.55000144 0.07500112
OE
CE
PIN 8 S 0.75000104 0.97500186 0 U U
CT
OB 0.35000057 1.70000168 I
OS 1.15000151 1.70000168
OS 1.15000151 0.25000204
OS 0.35000057 0.25000204
OS 0.35000057 1.70000168
OE
CE
PIN 9 S 0.00000254 1.11250222 0 U U
CT
OB -0.14999716 1.9750024 I
OS 0.15000224 1.9750024
OS 0.15000224 0.25000204
OS -0.14999716 0.25000204
OS -0.14999716 1.9750024
OE
CE
#
# PKG 6
PKG Eaton_HCM0703-4R7-R 5.29999956 -3.80000002 -3.30000102 3.80000002 3.30000102
CT
OB 3.55000052 -3.30000102 I
OS -3.55000052 -3.30000102
OS -3.55000052 3.30000102
OS 3.55000052 3.30000102
OS 3.55000052 -3.30000102
OE
CE
PIN 1 S -2.64999978 0 0 U U
CT
OB -3.80000002 1.65000051 I
OS -1.49999954 1.65000051
OS -1.49999954 -1.65000051
OS -3.80000002 -1.65000051
OS -3.80000002 1.65000051
OE
CE
PIN 2 S 2.64999978 0 0 U U
CT
OB 1.49999954 1.65000051 I
OS 3.80000002 1.65000051
OS 3.80000002 -1.65000051
OS 1.49999954 -1.65000051
OS 1.49999954 1.65000051
OE
CE
#
# PKG 7
PKG IQD_ICPT-1 5.08 -22.50001596 -18.00000972 22.49998548 17.99999448
CT
OB 22.49998548 -18.00000972 I
OS -22.50001596 -18.00000972
OS -22.50001596 17.99999448
OS 22.49998548 17.99999448
OS 22.49998548 -18.00000972
OE
CE
PIN 1 T 16.51 -12.7 0 U U
CR 16.51 -12.7 0.89999947
PIN 2 T 16.51 2.54 0 U U
CR 16.51 2.54 0.89999947
PIN 3 T 16.51 7.62 0 U U
CR 16.51 7.62 0.89999947
PIN 4 T 16.51 12.7 0 U U
CR 16.51 12.7 0.89999947
PIN 5 T -16.51 12.7 0 U U
CR -16.51 12.7 0.89999947
PIN 6 T -16.51 7.62 0 U U
CR -16.51 7.62 0.89999947
PIN 7 T -16.51 2.54 0 U U
CR -16.51 2.54 0.89999947
PIN 8 T -16.51 -2.54 0 U U
CR -16.51 -2.54 0.89999947
PIN 9 T -16.51 -12.7 0 U U
CR -16.51 -12.7 0.89999947
#
# PKG 8
PKG Keystone_4871 0 -3.09999888 -3.09999888 3.09999888 3.09999888
CT
OB 2.7813 -2.76943566 I
OS -2.7813 -2.76943566
OS -2.7813 2.76943566
OS 2.7813 2.76943566
OS 2.7813 -2.76943566
OE
CE
PIN Hole T 0 0 0 U U
CR 0 0 1.85000011
PIN MT S 0 0 0 U U
CR 0 0 3.10000015
#
# PKG 9
PKG Microchip_SA45 5.08 -20.32000254 -17.653 20.32 17.653
CT
OB 20.32 -17.653 I
OS -20.32000254 -17.653
OS -20.32000254 17.653
OS 20.32 17.653
OS 20.32 -17.653
OE
CE
PIN 1 T 16.51 -12.7 0 U U
CR 16.51 -12.7 0.762
PIN 4 T 16.51 2.54 0 U U
CR 16.51 2.54 0.762
PIN 5 T 16.51 7.62 0 U U
CR 16.51 7.62 0.762
PIN 6 T 16.51 12.7 0 U U
CR 16.51 12.7 0.762
PIN 7 T -16.51 12.7 0 U U
CR -16.51 12.7 0.78100047
PIN 8 T -16.51 7.62 0 U U
CR -16.51 7.62 0.78100047
PIN 9 T -16.51 2.54 0 U U
CR -16.51 2.54 0.78100047
PIN 10 T -16.51 -2.54 0 U U
CR -16.51 -2.54 0.78100047
PIN 12 T -16.51 -12.7 0 U U
CR -16.51 -12.7 0.78100047
#
# PKG 10
PKG RESC0603X026N 0.67999864 -0.55999888 -0.20999958 0.55999888 0.20999958
CT
OB 0.30011624 -0.14991588 I
OS -0.29988256 -0.14991588
OS -0.29988256 0.15008352
OS 0.30011624 0.15008352
OS 0.30011624 -0.14991588
OE
CE
PIN 1 S -0.33999932 0 0 U U
CT
OB -0.55999888 0.20999958 I
OS -0.11999976 0.20999958
OS -0.11999976 -0.20999958
OS -0.55999888 -0.20999958
OS -0.55999888 0.20999958
OE
CE
PIN 2 S 0.33999932 0 0 U U
CT
OB 0.11999976 0.20999958 I
OS 0.55999888 0.20999958
OS 0.55999888 -0.20999958
OS 0.11999976 -0.20999958
OS 0.11999976 0.20999958
OE
CE
#
# PKG 11
PKG RESC1005X040N 0.95999808 -0.7649972 -0.30999938 0.7649972 0.30999938
CT
OB 0.50008536 -0.24993346 I
OS -0.49991264 -0.24993346
OS -0.49991264 0.25006554
OS 0.50008536 0.25006554
OS 0.50008536 -0.24993346
OE
CE
PIN 1 S -0.47999904 0 0 U U
CT
OB -0.76499847 0.30999938 I
OS -0.19499961 0.30999938
OS -0.19499961 -0.30999938
OS -0.76499847 -0.30999938
OS -0.76499847 0.30999938
OE
CE
PIN 2 S 0.47999904 0 0 U U
CT
OB 0.19499961 0.30999938 I
OS 0.76499847 0.30999938
OS 0.76499847 -0.30999938
OS 0.19499961 -0.30999938
OS 0.19499961 0.30999938
OE
CE
#
# PKG 12
PKG RESC1608X55X30ML15T15 1.44999964 -1.17499892 -0.52500022 1.17499892 0.52500022
CT
OB 0.87499952 -0.47500032 I
OS -0.87499952 -0.47500032
OS -0.87499952 0.47500032
OS 0.87499952 0.47500032
OS 0.87499952 -0.47500032
OE
CE
PIN 1 S -0.72499982 0 0 U U
CT
OB -1.17457982 -0.52324 I
OS -1.17457982 0.52324
OS -0.27541982 0.52324
OS -0.27541982 -0.52324
OS -1.17457982 -0.52324
OE
CE
PIN 2 S 0.72499982 0 0 U U
CT
OB 0.27541982 -0.52324 I
OS 0.27541982 0.52324
OS 1.17457982 0.52324
OS 1.17457982 -0.52324
OS 0.27541982 -0.52324
OE
CE
#
# PKG 13
PKG RESC3216X070N 2.99999908 -2.02499976 -0.87499698 2.02499976 0.87500206
CT
OB 1.60006284 -0.79993236 I
OS -1.59993584 -0.79993236
OS -1.59993584 0.80006952
OS 1.60006284 0.80006952
OS 1.60006284 -0.79993236
OE
CE
PIN 1 S -1.49999954 0.00000254 0 U U
CT
OB -2.02499976 0.87500206 I
OS -0.97499932 0.87500206
OS -0.97499932 -0.87499698
OS -2.02499976 -0.87499698
OS -2.02499976 0.87500206
OE
CE
PIN 2 S 1.49999954 0.00000254 0 U U
CT
OB 0.97499932 0.87500206 I
OS 2.02499976 0.87500206
OS 2.02499976 -0.87499698
OS 0.97499932 -0.87499698
OS 0.97499932 0.87500206
OE
CE
#
# PKG 14
PKG TH000V_300DIAx400_001mt_9774040243R 0 -2.64999978 -2.64999978 2.64999978 2.64999978
CT
OB 2.17499946 -2.16308432 I
OS -2.17499946 -2.16308432
OS -2.17499946 2.16308432
OS 2.17499946 2.16308432
OS 2.17499946 -2.16308432
OE
CE
PIN MT1 T 0 0 0 U U
CR 0 0 2.64999978
#
# PKG 15
PKG TH001V_109DIA_000mt_8600-0 0 -1.04499918 -1.06499914 1.04499918 1.02499922
CT
OB 0.9144 -0.91428824 I
OS -0.9144 -0.91428824
OS -0.9144 0.91428824
OS 0.9144 0.91428824
OS 0.9144 -0.91428824
OE
CE
PIN 1 T 0 -0.01999996 0 U U
CR 0 -0.01999996 1.04500045
#
# PKG 16
PKG TH001V_109DIA_000mt_8600-0_1 0 -1.04499918 -1.04499918 1.04499918 1.04499918
CT
OB 0.9144 -0.91428824 I
OS -0.9144 -0.91428824
OS -0.9144 0.91428824
OS 0.9144 0.91428824
OS 0.9144 -0.91428824
OE
CE
PIN 1 T 0 0 0 U U
CR 0 0 1.04500045
#
# PKG 17
PKG TH001V_109DIA_000mt_8600-0_1_2 0 -1.04499918 -1.0849991 1.04499918 1.00499926
CT
OB 0.9144 -0.91428824 I
OS -0.9144 -0.91428824
OS -0.9144 0.91428824
OS 0.9144 0.91428824
OS 0.9144 -0.91428824
OE
CE
PIN 1 T 0 -0.03999992 0 U U
CR 0 -0.03999992 1.04500045
#
# PKG 18
PKG TH001V_109DIA_000mt_8600-0_1_2_3 0 -1.00499926 -1.0849991 1.0849991 1.00499926
CT
OB 0.9144 -0.91428824 I
OS -0.9144 -0.91428824
OS -0.9144 0.91428824
OS 0.9144 0.91428824
OS 0.9144 -0.91428824
OE
CE
PIN 1 T 0.03999992 -0.03999992 0 U U
CR 0.03999992 -0.03999992 1.04500045
#
# PKG 19
PKG TH001V_109DIA_000mt_8600-0_1_2_3_4 0 -1.00499926 -1.04499918 1.0849991 1.04499918
CT
OB 0.9144 -0.91428824 I
OS -0.9144 -0.91428824
OS -0.9144 0.91428824
OS 0.9144 0.91428824
OS 0.9144 -0.91428824
OE
CE
PIN 1 T 0.03999992 0 0 U U
CR 0.03999992 0 1.04500045
#

### steps/pcb/netlists/cadnet/netlist
UNITS=MM
H optimize n staggered n
$0 $NONE$
$1 +3.3V
$2 +3.3V_OSC
$3 +5V
$4 1PPS_IN
$5 1PPS_OUT
$6 GND
$7 LOCK
$8 NC
$9 NetC3_1
$10 NetC4_2
$11 NetC9_1
$12 NetR5_1
$13 RF_OUTPUT
$14 RX
$15 SW
$16 TX
#
#Netlist points
#
0 1.49999954 20.24000016 42.13999954 B e e staggered 0 0 0
0 0.381 4.8300005 33.03999996 B e e staggered 0 0 0
0 0.381 4.8300005 17.79999996 B e e staggered 0 0 0
0 1.84999884 4.39999882 38.599999 B e e staggered 0 0 0
0 0.5999988 4.8300005 17.79999996 B e e staggered 0 0 0
0 0.5999988 4.8300005 33.03999996 B e e staggered 0 0 0
0 1.49999954 20.43999976 -1.26000002 B e e staggered 0 0 0
0 1.84999884 4.39999882 2.00000108 B e e staggered 0 0 0
0 1.84999884 35.50000012 -1.00000054 B e e staggered 0 0 0
0 1.84999884 36.20000126 40.10000108 B e e staggered 0 0 0
0 0 4.39999882 38.599999 D 6.2000003 6.2000003 e p
0 0 18.0150008 18.94000276 D 0.5999988 0.2999994 e p
0 0 -2.38499904 43.5150006 D 1.00000054 1.00000054 e p
0 0 43.11499886 43.5150006 D 1.00000054 1.00000054 e p
0 0 43.18999998 -2.80999946 D 1.00000054 1.00000054 e p
0 0 4.39999882 2.00000108 D 6.2000003 6.2000003 e p
0 0 35.50000012 -1.00000054 D 6.2000003 6.2000003 e p
0 0 36.20000126 40.10000108 D 6.2000003 6.2000003 e p
0 0 -2.37499906 43.52500058 T 1.00000054 1.00000054 e s
0 0 -2.20000068 -2.69999968 T 1.00000054 1.00000054 e s
0 0 43.12499884 43.52500058 T 1.00000054 1.00000054 e s
1 0 32.24000156 7.63999996 D 1.05000044 1.74999904 e p
1 0 13.9050014 19.16500104 D 0.56999886 0.61999876 e p
1 0 26.06499994 16.85250122 D 2.30000048 3.30000102 e p
1 0 24.21500364 7.7900022 D 1.29999994 1.64999924 e p
1 0 23.87500178 12.29000082 D 0.5999988 0.61999876 e p
1 0 24.21500364 10.29000228 D 1.29999994 1.64999924 e p
1 0 14.86499948 20.87500016 D 0.41999916 0.45999908 e p
2 0.4809998 37.8500005 7.63999996 B e e staggered 0 0 0
2 0.5999988 37.8500005 7.63999996 B e e staggered 0 0 0
2 0 35.24000064 7.63999996 D 1.05000044 1.74999904 e p
2 0 37.8500005 9.94000044 D 0.5999988 0.61999876 e p
2 0 40.0900011 7.63999996 D 0.61999876 0.5999988 e p
3 0.54500018 0 0 B e e staggered 0 0 0
3 0 16.31500166 18.04000202 D 0.5999988 0.2999994 e p
3 0 16.41500146 16.99000158 D 0.80000094 1.44999964 e p
3 0 15.91499992 9.7899982 D 1.29999994 1.64999924 e p
3 0 15.91499992 12.39000062 D 1.29999994 1.64999924 e p
3 0 15.91499992 7.38999792 D 1.29999994 1.64999924 e p
3 0 16.65500352 14.7900009 D 0.5999988 0.61999876 e p
4 0.4809998 37.8500005 17.79999996 B e e staggered 0 0 0
4 0.5999988 37.8500005 17.79999996 B e e staggered 0 0 0
4 0.54500018 11.2219994 43.3299997 B e e staggered 0 0 0
4 0 39.78999916 15.96499982 D 1.05000044 0.90000074 e p
5 0.54500018 14.2699994 43.3299997 B e e staggered 0 0 0
5 0.4809998 37.8500005 22.87999996 B e e staggered 0 0 0
5 0.5999988 37.8500005 22.87999996 B e e staggered 0 0 0
6 0.54500018 0 40.64 B e e staggered 0 0 0
6 0.4809998 37.8500005 12.71999996 B e e staggered 0 0 0
6 0.5999988 37.8500005 12.71999996 B e e staggered 0 0 0
6 0.54500018 40.67999992 20.33999996 B e e staggered 0 0 0
6 0 39.78999916 14.51500018 D 1.05000044 0.90000074 e p
6 0 15.86500002 20.89500012 D 0.41999916 0.43999912 e p
6 0 17.915001 16.99000158 D 0.80000094 1.44999964 e p
6 0 17.7150014 9.7899982 D 1.29999994 1.64999924 e p
6 0 22.41500216 7.7900022 D 1.29999994 1.64999924 e p
6 0 38.76999866 9.94000044 D 0.5999988 0.61999876 e p
6 0 22.95500362 12.29000082 D 0.5999988 0.61999876 e p
6 0 16.29499916 22.29000114 D 0.45999908 0.41999916 e p
6 0 17.7150014 12.39000062 D 1.29999994 1.64999924 e p
6 0 17.7150014 7.38999792 D 1.29999994 1.64999924 e p
6 0 17.57500168 14.7900009 D 0.5999988 0.61999876 e p
6 0 22.41500216 10.29000228 D 1.29999994 1.64999924 e p
6 0 40.0900011 8.55999812 D 0.61999876 0.5999988 e p
6 0 13.9050014 18.0150008 D 0.56999886 0.61999876 e p
6 0.1499997 40.50000028 -3.50000062 B e c staggered 0 0 0 v
6 0.1499997 38.4999992 -3.50000062 B e c staggered 0 0 0 v
6 0.1499997 32.50000104 -3.50000062 B e c staggered 0 0 0 v
6 0.1499997 30.49999996 -3.50000062 B e c staggered 0 0 0 v
6 0.1499997 28.50000142 -3.50000062 B e c staggered 0 0 0 v
6 0.1499997 26.50000034 -3.50000062 B e c staggered 0 0 0 v
6 0.1499997 24.49999926 -3.50000062 B e c staggered 0 0 0 v
6 0.1499997 16.50000002 -3.99999962 B e c staggered 0 0 0 v
6 0.1499997 14.50000148 -3.99999962 B e c staggered 0 0 0 v
6 0.1499997 12.5000004 -3.99999962 B e c staggered 0 0 0 v
6 0.1499997 10.49999932 -3.99999962 B e c staggered 0 0 0 v
6 0.1499997 8.50000078 -3.99999962 B e c staggered 0 0 0 v
6 0.1499997 6.4999997 -3.99999962 B e c staggered 0 0 0 v
6 0.1499997 4.50000116 -3.99999962 B e c staggered 0 0 0 v
6 0.1499997 2.50000008 -3.99999962 B e c staggered 0 0 0 v
6 0.1499997 0.50000154 -3.99999962 B e c staggered 0 0 0 v
6 0.1499997 44.4999999 0.499999 B e c staggered 0 0 0 v
6 0.1499997 44.4999999 2.50000008 B e c staggered 0 0 0 v
6 0.1499997 44.4999999 4.49999862 B e c staggered 0 0 0 v
6 0.1499997 44.4999999 6.4999997 B e c staggered 0 0 0 v
6 0.1499997 44.4999999 8.49999824 B e c staggered 0 0 0 v
6 0.1499997 44.4999999 10.49999932 B e c staggered 0 0 0 v
6 0.1499997 44.4999999 12.49999786 B e c staggered 0 0 0 v
6 0.1499997 44.4999999 14.49999894 B e c staggered 0 0 0 v
6 0.1499997 44.4999999 16.50000002 B e c staggered 0 0 0 v
6 0.1499997 44.4999999 18.49999856 B e c staggered 0 0 0 v
6 0.1499997 44.4999999 20.49999964 B e c staggered 0 0 0 v
6 0.1499997 44.4999999 22.49999818 B e c staggered 0 0 0 v
6 0.1499997 44.4999999 24.49999926 B e c staggered 0 0 0 v
6 0.1499997 44.4999999 26.4999978 B e c staggered 0 0 0 v
6 0.1499997 44.4999999 28.49999888 B e c staggered 0 0 0 v
6 0.1499997 44.4999999 30.49999996 B e c staggered 0 0 0 v
6 0.1499997 44.4999999 32.4999985 B e c staggered 0 0 0 v
6 0.1499997 44.4999999 34.49999958 B e c staggered 0 0 0 v
6 0.1499997 44.4999999 36.49999812 B e c staggered 0 0 0 v
6 0.1499997 44.4999999 38.4999992 B e c staggered 0 0 0 v
6 0.1499997 44.4999999 40.49999774 B e c staggered 0 0 0 v
6 0.1499997 -2.99999908 39.99999874 B e c staggered 0 0 0 v
6 0.1499997 -2.99999908 38.0000002 B e c staggered 0 0 0 v
6 0.1499997 -2.99999908 35.99999912 B e c staggered 0 0 0 v
6 0.1499997 -2.99999908 34.00000058 B e c staggered 0 0 0 v
6 0.1499997 -2.99999908 31.9999995 B e c staggered 0 0 0 v
6 0.1499997 -2.99999908 30.00000096 B e c staggered 0 0 0 v
6 0.1499997 -2.99999908 27.99999988 B e c staggered 0 0 0 v
6 0.1499997 -2.99999908 25.9999988 B e c staggered 0 0 0 v
6 0.1499997 -2.99999908 24.00000026 B e c staggered 0 0 0 v
6 0.1499997 -2.99999908 21.99999918 B e c staggered 0 0 0 v
6 0.1499997 -2.99999908 20.00000064 B e c staggered 0 0 0 v
6 0.1499997 -2.99999908 17.99999956 B e c staggered 0 0 0 v
6 0.1499997 -2.99999908 16.00000102 B e c staggered 0 0 0 v
6 0.1499997 23.33999904 44.0138312 B e c staggered 0 0 0 v
6 0.1499997 23.29999912 38.90000094 B e c staggered 0 0 0 v
6 0.1499997 25.7999992 38.90000094 B e c staggered 0 0 0 v
6 0.1499997 35.30000052 44.0000009 B e c staggered 0 0 0 v
6 0.1499997 32.80000044 38.90000094 B e c staggered 0 0 0 v
6 0.1499997 39.60000208 38.91499964 B e c staggered 0 0 0 v
6 0.1499997 12.74500118 40.26499948 B e c staggered 0 0 0 v
6 0.1499997 12.74500118 44.63999962 B e c staggered 0 0 0 v
6 0.1499997 12.74500118 41.21500012 B e c staggered 0 0 0 v
6 0.1499997 12.75500116 42.16500076 B e c staggered 0 0 0 v
6 0.1499997 40.67999992 42.76499956 B e c staggered 0 0 0 v
6 0.1499997 42.2249981 38.91499964 B e c staggered 0 0 0 v
6 0.1499997 22.45970616 20.01499934 B e c staggered 0 0 0 v
6 0.1499997 23.4097068 20.04000056 B e c staggered 0 0 0 v
6 0.1499997 24.35970744 20.04000056 B e c staggered 0 0 0 v
6 0.1499997 16.30970576 23.03999964 B e c staggered 0 0 0 v
6 0.1499997 15.88470534 21.56499878 B e c staggered 0 0 0 v
6 0.1499997 21.11499968 11.38590052 B e c staggered 0 0 0 v
6 0.1499997 12.98999942 18.0150008 B e c staggered 0 0 0 v
6 0.1499997 18.8149992 16.85250122 B e c staggered 0 0 0 v
6 0.1499997 17.57500168 13.89000016 B e c staggered 0 0 0 v
6 0.1499997 17.915001 15.69625258 B e c staggered 0 0 0 v
6 0.1499997 18.8149992 15.98270108 B e c staggered 0 0 0 v
6 0.1499997 18.8149992 15.10000028 B e c staggered 0 0 0 v
6 0.1499997 19.01500134 12.39000062 B e c staggered 0 0 0 v
6 0.1499997 19.01500134 11.09000068 B e c staggered 0 0 0 v
6 0.1499997 19.01500134 9.7899982 B e c staggered 0 0 0 v
6 0.1499997 21.11499968 10.28999974 B e c staggered 0 0 0 v
6 0.1499997 22.05919388 12.29000082 B e c staggered 0 0 0 v
6 0.1499997 19.01500134 8.5900006 B e c staggered 0 0 0 v
6 0.1499997 19.01500134 7.39000046 B e c staggered 0 0 0 v
6 0.1499997 21.11499968 8.9899998 B e c staggered 0 0 0 v
6 0.1499997 21.11499968 7.78999966 B e c staggered 0 0 0 v
6 0.1499997 21.11499968 6.76500044 B e c staggered 0 0 0 v
7 0.54500018 2.0779994 43.3299997 B e e staggered 0 0 0
8 0.54500018 40.64 0 B e e staggered 0 0 0
9 0 18.0150008 18.49000112 D 0.5999988 0.2999994 e p
9 0 18.22000166 21.17499956 D 0.5999988 0.61999876 e p
10 0 14.86499948 19.16500104 D 0.56999886 0.61999876 e p
10 0 16.31500166 18.49000112 D 0.5999988 0.2999994 e p
10 0 14.86499948 20.21500148 D 0.41999916 0.45999908 e p
10 0 14.86499948 18.0150008 D 0.56999886 0.61999876 e p
11 0 16.95499784 22.29000114 D 0.45999908 0.41999916 e p
11 0 16.95499784 21.17499956 D 0.61999876 0.56999886 e p
12 0 15.86500002 20.21500148 D 0.41999916 0.43999912 e p
12 0 16.31500166 18.94000276 D 0.5999988 0.2999994 e p
12 0 16.95499784 20.21500148 D 0.61999876 0.56999886 e p
13 0.54500018 40.64 40.64 B e e staggered 0 0 0
13 0.4809998 37.8500005 33.03999996 B e e staggered 0 0 0
13 0.5999988 37.8500005 33.03999996 B e e staggered 0 0 0
14 0.381 4.8300005 7.63999996 B e e staggered 0 0 0
14 0.5999988 4.8300005 7.63999996 B e e staggered 0 0 0
14 0.54500018 8.1739994 43.3299997 B e e staggered 0 0 0
15 0 20.76500038 16.85250122 D 2.30000048 3.30000102 e p
15 0 17.1650025 16.85250122 D 0.2999994 1.72500036 e p
15 0 18.0150008 18.04000202 D 0.5999988 0.2999994 e p
15 0 19.13999982 21.17499956 D 0.5999988 0.61999876 e p
16 0.381 4.8300005 12.71999996 B e e staggered 0 0 0
16 0.5999988 4.8300005 12.71999996 B e e staggered 0 0 0
16 0.54500018 5.1259994 43.3299997 B e e staggered 0 0 0

### steps/pcb/layers/bottom_overlay/features
UNITS=MM
#Layer_Color=32896
#
#Feature symbol names
#
$0 r99.9998

#
#Feature attribute names
#
@0 .nomenclature
@1 .string
@2 .string_angle

#
#Feature attribute text strings
#

#
#Layer features
#
L -9.5600012 -24.45999934 40.4400004 -24.45999934 0 P 0
L -9.5600012 -35.9599992 -9.5600012 -24.45999934 0 P 0
L -9.5600012 -35.9599992 28.439999 -35.9599992 0 P 0
L -9.5600012 -39.45999982 -9.5600012 -35.9599992 0 P 0
L -9.5600012 -39.45999982 28.439999 -39.45999982 0 P 0
L -9.5600012 -42.96000044 -9.5600012 -39.45999982 0 P 0
L -9.5600012 -42.96000044 28.439999 -42.96000044 0 P 0
L -10.0600002 -23.96000034 62.93999858 -23.96000034 0 P 0
L -10.0600002 -43.45999944 -10.0600002 -23.96000034 0 P 0
L -10.0600002 -43.45999944 62.93999858 -43.45999944 0 P 0
L 28.439999 -35.96000174 45.44000056 -35.9599992 0 P 0
L 28.439999 -39.45999982 28.439999 -35.9599992 0 P 0
L 28.439999 -39.46000236 45.44000056 -39.45999982 0 P 0
L 28.439999 -42.96000044 28.439999 -39.45999982 0 P 0
L 28.439999 -42.96000298 45.44000056 -42.96000044 0 P 0
L 33.03999996 6.74000176 34.44000224 6.74000176 0 P 0
L 33.03999996 8.54000324 34.44000224 8.54000324 0 P 0
L 40.4400004 -24.45999934 62.43999958 -24.45999934 0 P 0
L 40.4400004 -35.9599992 40.4400004 -24.45999934 0 P 0
L 45.44000056 -35.9599992 62.43999958 -35.9599992 0 P 0
L 45.44000056 -39.45999982 62.43999958 -39.45999982 0 P 0
L 45.44000056 -42.96000044 45.44000056 -35.9599992 0 P 0
L 45.44000056 -42.96000044 62.43999958 -42.96000044 0 P 0
L 62.43999958 -35.9599992 62.43999958 -24.45999934 0 P 0
L 62.43999958 -42.96000044 62.43999958 -35.9599992 0 P 0
L 62.93999858 -43.45999944 62.93999858 -23.96000034 0 P 0
S P 0
OB -1.93923666 -38.95999828 I
OS -2.01412602 -38.95999828
OS -2.18886786 -38.49586916
OS -2.10565746 -38.49586916
OS -2.00580498 -38.77416172
OS -2.00580498 -38.77508628
OS -2.00488042 -38.77601084
OS -2.00395586 -38.77878452
OS -2.0030313 -38.7815582
OS -2.00025762 -38.7908038
OS -1.99655938 -38.80282308
OS -1.99193658 -38.81669148
OS -1.98638922 -38.832409
OS -1.98176642 -38.84997564
OS -1.97621906 -38.86754228
OS -1.9752945 -38.86569316
OS -1.97436994 -38.86107036
OS -1.97159626 -38.85367388
OS -1.96882258 -38.84257916
OS -1.96419978 -38.83055988
OS -1.95957698 -38.81484236
OS -1.95310506 -38.79820028
OS -1.94663314 -38.77970908
OS -1.84400698 -38.49586916
OS -1.7626457 -38.49586916
OS -1.93923666 -38.95999828
OE
OB -1.48712682 -38.48662356 I
OS -1.47973034 -38.48754812
OS -1.47048474 -38.48939724
OS -1.46031458 -38.49124636
OS -1.4482953 -38.49402004
OS -1.43720058 -38.49679372
OS -1.42425674 -38.50141652
OS -1.41223746 -38.50603932
OS -1.39929362 -38.51251124
OS -1.38634978 -38.51990772
OS -1.37340594 -38.52822876
OS -1.36138666 -38.53839892
OS -1.35029194 -38.54949364
OS -1.34936738 -38.5504182
OS -1.34751826 -38.55226732
OS -1.34474458 -38.55596556
OS -1.34104634 -38.56151292
OS -1.33642354 -38.56798484
OS -1.33180074 -38.57538132
OS -1.32625338 -38.58462692
OS -1.32070602 -38.59572164
OS -1.31515866 -38.60774092
OS -1.3096113 -38.62068476
OS -1.3049885 -38.63547772
OS -1.3003657 -38.65119524
OS -1.29666746 -38.66876188
OS -1.29389378 -38.68725308
OS -1.29204466 -38.70666884
OS -1.2911201 -38.72793372
OS -1.2911201 -38.72885828
OS -1.2911201 -38.73255652
OS -1.2911201 -38.73902844
OS -1.29204466 -38.74827404
OS -1.63875466 -38.74827404
OS -1.63875466 -38.7491986
OS -1.63875466 -38.75197228
OS -1.6378301 -38.75567052
OS -1.6378301 -38.76121788
OS -1.63690554 -38.7676898
OS -1.63505642 -38.77508628
OS -1.63228274 -38.79172836
OS -1.62673538 -38.81021956
OS -1.6193389 -38.83055988
OS -1.60916874 -38.84905108
OS -1.5962249 -38.86569316
OS -1.59530034 -38.86569316
OS -1.59437578 -38.86754228
OS -1.58882842 -38.87216508
OS -1.58050738 -38.878637
OS -1.56941266 -38.88510892
OS -1.5546197 -38.8925054
OS -1.53797762 -38.89897732
OS -1.51948642 -38.90360012
OS -1.50931626 -38.90452468
OS -1.49822154 -38.90544924
OS -1.49082506 -38.90544924
OS -1.48250402 -38.90452468
OS -1.47233386 -38.90267556
OS -1.46123914 -38.89990188
OS -1.4482953 -38.89620364
OS -1.43627602 -38.89065628
OS -1.42425674 -38.8832598
OS -1.42333218 -38.88233524
OS -1.41870938 -38.878637
OS -1.41316202 -38.87308964
OS -1.4066901 -38.86569316
OS -1.39929362 -38.855523
OS -1.39097258 -38.84257916
OS -1.38265154 -38.8277862
OS -1.37525506 -38.81021956
OS -1.29389378 -38.82038972
OS -1.29389378 -38.82131428
OS -1.29481834 -38.8231634
OS -1.2957429 -38.82686164
OS -1.29759202 -38.832409
OS -1.3003657 -38.83795636
OS -1.30313938 -38.84535284
OS -1.31053586 -38.86107036
OS -1.31978146 -38.878637
OS -1.3327253 -38.8971282
OS -1.34751826 -38.91469484
OS -1.36600946 -38.93133692
OS -1.36693402 -38.93133692
OS -1.36878314 -38.93318604
OS -1.37155682 -38.93503516
OS -1.37525506 -38.93780884
OS -1.38080242 -38.94058252
OS -1.38634978 -38.9433562
OS -1.39374626 -38.94705444
OS -1.4020673 -38.95075268
OS -1.4113129 -38.95445092
OS -1.4205585 -38.95814916
OS -1.4436725 -38.96369652
OS -1.46956018 -38.96831932
OS -1.49822154 -38.97016844
OS -1.5083917 -38.97016844
OS -1.51486362 -38.96924388
OS -1.52318466 -38.96831932
OS -1.53335482 -38.9664702
OS -1.54444954 -38.96462108
OS -1.55646882 -38.96277196
OS -1.5823565 -38.95537548
OS -1.5962249 -38.94982812
OS -1.60916874 -38.94428076
OS -1.62303714 -38.93688428
OS -1.63598098 -38.92856324
OS -1.64800026 -38.91931764
OS -1.66001954 -38.90822292
OS -1.6609441 -38.90729836
OS -1.66279322 -38.90544924
OS -1.6655669 -38.901751
OS -1.66926514 -38.89620364
OS -1.67388794 -38.88973172
OS -1.67851074 -38.88233524
OS -1.6840581 -38.87308964
OS -1.68960546 -38.86291948
OS -1.69515282 -38.8509002
OS -1.70070018 -38.83795636
OS -1.70532298 -38.8231634
OS -1.70994578 -38.80744588
OS -1.71364402 -38.7908038
OS -1.7164177 -38.7723126
OS -1.71826682 -38.75289684
OS -1.71919138 -38.73255652
OS -1.71919138 -38.73163196
OS -1.71919138 -38.72700916
OS -1.71919138 -38.7214618
OS -1.71826682 -38.71314076
OS -1.71734226 -38.7029706
OS -1.7164177 -38.69187588
OS -1.71456858 -38.67893204
OS -1.7117949 -38.6659882
OS -1.70439842 -38.63640228
OS -1.69977562 -38.62160932
OS -1.69422826 -38.6058918
OS -1.68683178 -38.59109884
OS -1.67851074 -38.57723044
OS -1.66926514 -38.56336204
OS -1.65909498 -38.5504182
OS -1.65817042 -38.54949364
OS -1.6563213 -38.54764452
OS -1.65262306 -38.54487084
OS -1.64800026 -38.54024804
OS -1.6424529 -38.53562524
OS -1.63505642 -38.53007788
OS -1.62673538 -38.52360596
OS -1.61656522 -38.5180586
OS -1.60639506 -38.51158668
OS -1.59437578 -38.50603932
OS -1.58143194 -38.50049196
OS -1.56756354 -38.49586916
OS -1.55277058 -38.49124636
OS -1.53705306 -38.48847268
OS -1.52041098 -38.48662356
OS -1.50284434 -38.485699
OS -1.49359874 -38.485699
OS -1.48712682 -38.48662356
OE
OB -2.6872057 -39.1375138 I
OS -3.20773298 -39.1375138
OS -3.20773298 -39.08111564
OS -2.6872057 -39.08111564
OS -2.6872057 -39.1375138
OE
OB -2.43387626 -38.48662356 I
OS -2.42555522 -38.48754812
OS -2.41630962 -38.48939724
OS -2.40613946 -38.49124636
OS -2.39412018 -38.49309548
OS -2.36915706 -38.50141652
OS -2.35621322 -38.50603932
OS -2.34326938 -38.51251124
OS -2.33032554 -38.51898316
OS -2.3173817 -38.52822876
OS -2.30536242 -38.53747436
OS -2.29334314 -38.54856908
OS -2.29241858 -38.54949364
OS -2.29056946 -38.55134276
OS -2.28779578 -38.555041
OS -2.28409754 -38.5596638
OS -2.27947474 -38.56613572
OS -2.27392738 -38.57445676
OS -2.26838002 -38.58370236
OS -2.26283266 -38.59387252
OS -2.2572853 -38.60496724
OS -2.25173794 -38.61883564
OS -2.24619058 -38.63270404
OS -2.24156778 -38.64842156
OS -2.23786954 -38.66506364
OS -2.23509586 -38.68263028
OS -2.23324674 -38.70112148
OS -2.23232218 -38.7214618
OS -2.23232218 -38.72238636
OS -2.23232218 -38.72516004
OS -2.23232218 -38.72978284
OS -2.23232218 -38.73625476
OS -2.23324674 -38.74365124
OS -2.2341713 -38.75289684
OS -2.2341713 -38.76214244
OS -2.23602042 -38.7723126
OS -2.2387941 -38.7954266
OS -2.24434146 -38.8185406
OS -2.25081338 -38.8416546
OS -2.26005898 -38.86291948
OS -2.26005898 -38.86384404
OS -2.26098354 -38.8647686
OS -2.26283266 -38.86754228
OS -2.26468178 -38.87124052
OS -2.2711537 -38.88048612
OS -2.27947474 -38.89158084
OS -2.29056946 -38.90452468
OS -2.30443786 -38.91746852
OS -2.32015538 -38.93041236
OS -2.33864658 -38.94243164
OS -2.33957114 -38.94243164
OS -2.3404957 -38.9433562
OS -2.34326938 -38.94520532
OS -2.34789218 -38.94705444
OS -2.35251498 -38.94890356
OS -2.35806234 -38.95075268
OS -2.37193074 -38.95630004
OS -2.38764826 -38.96092284
OS -2.40706402 -38.96554564
OS -2.42740434 -38.96924388
OS -2.44959378 -38.97016844
OS -2.45883938 -38.97016844
OS -2.46623586 -38.96924388
OS -2.4745569 -38.96831932
OS -2.4838025 -38.9664702
OS -2.49489722 -38.96462108
OS -2.50599194 -38.96277196
OS -2.53095506 -38.95537548
OS -2.54482346 -38.94982812
OS -2.5577673 -38.94428076
OS -2.57071114 -38.93688428
OS -2.58365498 -38.92856324
OS -2.59567426 -38.91931764
OS -2.60769354 -38.90822292
OS -2.6086181 -38.90729836
OS -2.61046722 -38.90544924
OS -2.6132409 -38.901751
OS -2.61693914 -38.89620364
OS -2.62156194 -38.88973172
OS -2.62618474 -38.88233524
OS -2.6317321 -38.87308964
OS -2.63727946 -38.86199492
OS -2.64282682 -38.84997564
OS -2.64837418 -38.83610724
OS -2.65299698 -38.82131428
OS -2.65761978 -38.80559676
OS -2.66131802 -38.78803012
OS -2.6640917 -38.76953892
OS -2.66594082 -38.7491986
OS -2.66686538 -38.72793372
OS -2.66686538 -38.7260846
OS -2.66686538 -38.72238636
OS -2.66594082 -38.71591444
OS -2.66594082 -38.70666884
OS -2.66501626 -38.69649868
OS -2.66316714 -38.68355484
OS -2.66131802 -38.670611
OS -2.65761978 -38.65581804
OS -2.65392154 -38.64102508
OS -2.64929874 -38.62530756
OS -2.64375138 -38.60866548
OS -2.6363549 -38.59294796
OS -2.62895842 -38.578155
OS -2.61878826 -38.56336204
OS -2.6086181 -38.54949364
OS -2.59567426 -38.53747436
OS -2.5947497 -38.5365498
OS -2.59290058 -38.53562524
OS -2.58920234 -38.53285156
OS -2.58457954 -38.52915332
OS -2.57903218 -38.52545508
OS -2.5716357 -38.52083228
OS -2.56423922 -38.51620948
OS -2.55499362 -38.51158668
OS -2.54482346 -38.50696388
OS -2.53372874 -38.50234108
OS -2.50876562 -38.49402004
OS -2.48010426 -38.48754812
OS -2.4653113 -38.48662356
OS -2.44959378 -38.485699
OS -2.44034818 -38.485699
OS -2.43387626 -38.48662356
OE
OB -1.01005386 -38.48662356 I
OS -0.9998837 -38.48847268
OS -0.98786442 -38.49217092
OS -0.97492058 -38.49679372
OS -0.96012762 -38.50326564
OS -0.9444101 -38.51158668
OS -0.97307146 -38.58370236
OS -0.97399602 -38.5827778
OS -0.97769426 -38.58092868
OS -0.98324162 -38.578155
OS -0.9906381 -38.57538132
OS -0.99895914 -38.57260764
OS -1.0091293 -38.56983396
OS -1.01929946 -38.56798484
OS -1.02946962 -38.56706028
OS -1.03409242 -38.56706028
OS -1.03871522 -38.56798484
OS -1.04518714 -38.5689094
OS -1.05165906 -38.57075852
OS -1.0599801 -38.5735322
OS -1.06830114 -38.57723044
OS -1.07569762 -38.5827778
OS -1.07662218 -38.58370236
OS -1.07939586 -38.58555148
OS -1.08216954 -38.58924972
OS -1.08679234 -38.59387252
OS -1.09141514 -38.60034444
OS -1.09603794 -38.60774092
OS -1.10066074 -38.61606196
OS -1.10435898 -38.62623212
OS -1.10528354 -38.62808124
OS -1.1062081 -38.6336286
OS -1.10805722 -38.64194964
OS -1.1108309 -38.65304436
OS -1.11360458 -38.66691276
OS -1.1154537 -38.68263028
OS -1.11637826 -38.69927236
OS -1.11730282 -38.71776356
OS -1.11730282 -38.95999828
OS -1.19589042 -38.95999828
OS -1.19589042 -38.49586916
OS -1.1246993 -38.49586916
OS -1.1246993 -38.56613572
OS -1.12377474 -38.56521116
OS -1.1200765 -38.55873924
OS -1.1154537 -38.5504182
OS -1.10805722 -38.54024804
OS -1.10066074 -38.53007788
OS -1.0923397 -38.51898316
OS -1.08401866 -38.50973756
OS -1.07569762 -38.50234108
OS -1.07477306 -38.50141652
OS -1.07199938 -38.4995674
OS -1.06645202 -38.49679372
OS -1.06090466 -38.49402004
OS -1.05350818 -38.49124636
OS -1.04426258 -38.48847268
OS -1.03501698 -38.48662356
OS -1.02484682 -38.485699
OS -1.0183749 -38.485699
OS -1.01005386 -38.48662356
OE
OB 0.00233934 -38.96739476 I
OS 0.00233934 -38.96831932
OS 0.00141478 -38.971093
OS -0.00043434 -38.97479124
OS -0.00228346 -38.97941404
OS -0.00505714 -38.98588596
OS -0.00783082 -38.99328244
OS -0.01430274 -39.00899996
OS -0.02077466 -39.0265666
OS -0.02817114 -39.04413324
OS -0.03556762 -39.05985076
OS -0.03926586 -39.06632268
OS -0.04203954 -39.0727946
OS -0.0429641 -39.07464372
OS -0.04573778 -39.07926652
OS -0.05036058 -39.08573844
OS -0.05590794 -39.09405948
OS -0.06330442 -39.10330508
OS -0.07162546 -39.11255068
OS -0.0799465 -39.12179628
OS -0.09011666 -39.12919276
OS -0.09104122 -39.13011732
OS -0.09473946 -39.13196644
OS -0.10028682 -39.13474012
OS -0.10860786 -39.13843836
OS -0.11785346 -39.1421366
OS -0.12894818 -39.14491028
OS -0.14096746 -39.1467594
OS -0.15483586 -39.14768396
OS -0.1585341 -39.14768396
OS -0.1631569 -39.1467594
OS -0.16962882 -39.1467594
OS -0.1770253 -39.14491028
OS -0.18534634 -39.14306116
OS -0.19459194 -39.14121204
OS -0.2047621 -39.1375138
OS -0.21308314 -39.06447356
OS -0.21215858 -39.06447356
OS -0.20846034 -39.06539812
OS -0.20383754 -39.06632268
OS -0.19829018 -39.0681718
OS -0.18349722 -39.07094548
OS -0.16870426 -39.07187004
OS -0.16408146 -39.07187004
OS -0.15945866 -39.07094548
OS -0.1539113 -39.07094548
OS -0.1400429 -39.0681718
OS -0.13357098 -39.06539812
OS -0.12709906 -39.06262444
OS -0.1261745 -39.06262444
OS -0.12432538 -39.06077532
OS -0.1215517 -39.0589262
OS -0.11785346 -39.05615252
OS -0.10953242 -39.04875604
OS -0.10213594 -39.03858588
OS -0.10213594 -39.03766132
OS -0.10028682 -39.0358122
OS -0.0984377 -39.03211396
OS -0.09658858 -39.0265666
OS -0.09289034 -39.01917012
OS -0.0891921 -39.0080754
OS -0.08364474 -38.99513156
OS -0.07809738 -38.97941404
OS -0.07809738 -38.97848948
OS -0.07624826 -38.97479124
OS -0.07439914 -38.96831932
OS -0.0707009 -38.95999828
OS -0.2463673 -38.49586916
OS -0.1631569 -38.49586916
OS -0.0660781 -38.76491612
OS -0.0660781 -38.76584068
OS -0.06515354 -38.76676524
OS -0.06422898 -38.76953892
OS -0.06330442 -38.77416172
OS -0.0614553 -38.77878452
OS -0.05960618 -38.78433188
OS -0.05498338 -38.79727572
OS -0.04943602 -38.81299324
OS -0.04388866 -38.83148444
OS -0.0383413 -38.8509002
OS -0.03279394 -38.87216508
OS -0.03279394 -38.87124052
OS -0.03186938 -38.8693914
OS -0.03094482 -38.86661772
OS -0.03002026 -38.86291948
OS -0.0290957 -38.85829668
OS -0.02724658 -38.85274932
OS -0.02354834 -38.83888092
OS -0.01892554 -38.8231634
OS -0.01245362 -38.8046722
OS -0.00690626 -38.786181
OS 0.00049022 -38.76676524
OS 0.1003427 -38.49586916
OS 0.1789303 -38.49586916
OS 0.00233934 -38.96739476
OE
OB 0.31668974 -38.42745172 I
OS 0.29542486 -38.54671996
OS 0.24642318 -38.54671996
OS 0.22700742 -38.42745172
OS 0.22700742 -38.32020276
OS 0.31668974 -38.32020276
OS 0.31668974 -38.42745172
OE
OB -0.4821301 -38.48662356 I
OS -0.4682617 -38.48754812
OS -0.45254418 -38.48939724
OS -0.43682666 -38.49217092
OS -0.42110914 -38.49586916
OS -0.40631618 -38.50049196
OS -0.40446706 -38.50141652
OS -0.39984426 -38.50326564
OS -0.39337234 -38.50603932
OS -0.3850513 -38.50973756
OS -0.3758057 -38.51528492
OS -0.3665601 -38.52083228
OS -0.35823906 -38.52822876
OS -0.35084258 -38.53562524
OS -0.34991802 -38.5365498
OS -0.3480689 -38.53932348
OS -0.34529522 -38.54394628
OS -0.34159698 -38.54949364
OS -0.33697418 -38.55781468
OS -0.33327594 -38.56613572
OS -0.3295777 -38.57630588
OS -0.32680402 -38.58832516
OS -0.32680402 -38.58924972
OS -0.32587946 -38.5920234
OS -0.3249549 -38.59757076
OS -0.32403034 -38.60496724
OS -0.32403034 -38.6151374
OS -0.32310578 -38.62715668
OS -0.32218122 -38.6428742
OS -0.32218122 -38.66044084
OS -0.32218122 -38.76584068
OS -0.32218122 -38.76676524
OS -0.32218122 -38.77046348
OS -0.32218122 -38.77601084
OS -0.32218122 -38.78340732
OS -0.32218122 -38.79172836
OS -0.32218122 -38.80189852
OS -0.32125666 -38.82408796
OS -0.32125666 -38.84720196
OS -0.3203321 -38.87031596
OS -0.31940754 -38.88048612
OS -0.31940754 -38.88973172
OS -0.31848298 -38.89805276
OS -0.31755842 -38.90452468
OS -0.31755842 -38.90544924
OS -0.31663386 -38.90914748
OS -0.3157093 -38.91469484
OS -0.31293562 -38.92209132
OS -0.3110865 -38.93041236
OS -0.30738826 -38.93965796
OS -0.30276546 -38.94982812
OS -0.29814266 -38.95999828
OS -0.3804285 -38.95999828
OS -0.38135306 -38.95907372
OS -0.38227762 -38.95537548
OS -0.38412674 -38.95075268
OS -0.38690042 -38.9433562
OS -0.3896741 -38.93503516
OS -0.39152322 -38.924865
OS -0.39337234 -38.91377028
OS -0.39522146 -38.901751
OS -0.39614602 -38.901751
OS -0.39707058 -38.90360012
OS -0.40261794 -38.90822292
OS -0.41093898 -38.91469484
OS -0.4220337 -38.92301588
OS -0.4359021 -38.93133692
OS -0.4497705 -38.94058252
OS -0.46456346 -38.94890356
OS -0.48028098 -38.95537548
OS -0.4821301 -38.95630004
OS -0.48767746 -38.9572246
OS -0.4959985 -38.95999828
OS -0.50616866 -38.96277196
OS -0.5191125 -38.96554564
OS -0.53390546 -38.96739476
OS -0.55054754 -38.96924388
OS -0.56718962 -38.97016844
OS -0.5745861 -38.97016844
OS -0.58013346 -38.96924388
OS -0.58660538 -38.96924388
OS -0.59400186 -38.96831932
OS -0.61064394 -38.96554564
OS -0.62913514 -38.96092284
OS -0.64947546 -38.95445092
OS -0.66796666 -38.94520532
OS -0.68460874 -38.93318604
OS -0.68645786 -38.93133692
OS -0.69108066 -38.92671412
OS -0.69755258 -38.91839308
OS -0.70494906 -38.90729836
OS -0.71234554 -38.89342996
OS -0.71881746 -38.87771244
OS -0.72344026 -38.85829668
OS -0.72436482 -38.84905108
OS -0.72528938 -38.83795636
OS -0.72528938 -38.83610724
OS -0.72528938 -38.832409
OS -0.72436482 -38.82593708
OS -0.72344026 -38.81761604
OS -0.72159114 -38.80744588
OS -0.71881746 -38.79727572
OS -0.71511922 -38.786181
OS -0.71049642 -38.77601084
OS -0.70957186 -38.77508628
OS -0.70772274 -38.77138804
OS -0.7040245 -38.76584068
OS -0.6994017 -38.75936876
OS -0.69385434 -38.75197228
OS -0.68645786 -38.7445758
OS -0.67906138 -38.73717932
OS -0.66981578 -38.7307074
OS -0.66889122 -38.72978284
OS -0.66519298 -38.72793372
OS -0.66057018 -38.72423548
OS -0.6531737 -38.72053724
OS -0.64485266 -38.716839
OS -0.6346825 -38.7122162
OS -0.62451234 -38.70851796
OS -0.61249306 -38.70481972
OS -0.6115685 -38.70481972
OS -0.60787026 -38.70389516
OS -0.6023229 -38.70204604
OS -0.59492642 -38.70112148
OS -0.58568082 -38.69927236
OS -0.57366154 -38.69742324
OS -0.55979314 -38.69464956
OS -0.54315106 -38.69280044
OS -0.5422265 -38.69280044
OS -0.53852826 -38.69187588
OS -0.53390546 -38.69187588
OS -0.52743354 -38.69095132
OS -0.52003706 -38.69002676
OS -0.51079146 -38.68817764
OS -0.5006213 -38.68725308
OS -0.48952658 -38.68540396
OS -0.46733714 -38.68078116
OS -0.44329858 -38.67615836
OS -0.4220337 -38.670611
OS -0.41186354 -38.66783732
OS -0.40261794 -38.66506364
OS -0.40261794 -38.66413908
OS -0.40261794 -38.66228996
OS -0.40169338 -38.6567426
OS -0.40169338 -38.65027068
OS -0.40169338 -38.64657244
OS -0.40169338 -38.64472332
OS -0.40169338 -38.64379876
OS -0.40169338 -38.6428742
OS -0.40169338 -38.63732684
OS -0.40261794 -38.62808124
OS -0.40446706 -38.61791108
OS -0.40724074 -38.60681636
OS -0.41186354 -38.59572164
OS -0.4174109 -38.58555148
OS -0.42480738 -38.57723044
OS -0.42573194 -38.57630588
OS -0.43035474 -38.57260764
OS -0.43775122 -38.5689094
OS -0.44699682 -38.56336204
OS -0.45994066 -38.55873924
OS -0.47473362 -38.55411644
OS -0.49322482 -38.55134276
OS -0.5144897 -38.5504182
OS -0.5237353 -38.5504182
OS -0.5329809 -38.55134276
OS -0.54592474 -38.55319188
OS -0.55886858 -38.555041
OS -0.57273698 -38.55873924
OS -0.58568082 -38.56336204
OS -0.59677554 -38.56983396
OS -0.5977001 -38.57075852
OS -0.60139834 -38.5735322
OS -0.60602114 -38.578155
OS -0.6115685 -38.58555148
OS -0.61711586 -38.59479708
OS -0.62358778 -38.60681636
OS -0.62913514 -38.62160932
OS -0.6346825 -38.6382514
OS -0.71142098 -38.62808124
OS -0.71142098 -38.62715668
OS -0.71049642 -38.62623212
OS -0.71049642 -38.62345844
OS -0.70957186 -38.6197602
OS -0.70679818 -38.61143916
OS -0.70309994 -38.59941988
OS -0.69847714 -38.5874006
OS -0.69292978 -38.57445676
OS -0.6855333 -38.56151292
OS -0.67721226 -38.54949364
OS -0.6762877 -38.54856908
OS -0.67258946 -38.54487084
OS -0.6670421 -38.53932348
OS -0.65964562 -38.531927
OS -0.64947546 -38.52453052
OS -0.63745618 -38.51713404
OS -0.62358778 -38.508813
OS -0.60787026 -38.50234108
OS -0.6069457 -38.50234108
OS -0.60602114 -38.50141652
OS -0.60324746 -38.50049196
OS -0.59954922 -38.4995674
OS -0.59030362 -38.49679372
OS -0.57735978 -38.49402004
OS -0.56256682 -38.49124636
OS -0.54407562 -38.48847268
OS -0.52465986 -38.48662356
OS -0.50247042 -38.485699
OS -0.49230026 -38.485699
OS -0.4821301 -38.48662356
OE
OB -0.82051906 -38.95999828 I
OS -0.89910666 -38.95999828
OS -0.89910666 -38.32020276
OS -0.82051906 -38.32020276
OS -0.82051906 -38.95999828
OE
OB -3.38339938 -38.48662356 I
OS -3.37692746 -38.48662356
OS -3.37045554 -38.48754812
OS -3.35473802 -38.4903218
OS -3.33809594 -38.4949446
OS -3.3205293 -38.50234108
OS -3.30296266 -38.51158668
OS -3.2881697 -38.52453052
OS -3.28632058 -38.52637964
OS -3.28262234 -38.531927
OS -3.27615042 -38.54024804
OS -3.27337674 -38.54671996
OS -3.2696785 -38.55319188
OS -3.26598026 -38.56151292
OS -3.26320658 -38.56983396
OS -3.25950834 -38.57907956
OS -3.25673466 -38.59017428
OS -3.25488554 -38.601269
OS -3.25303642 -38.61421284
OS -3.2511873 -38.62715668
OS -3.2511873 -38.64194964
OS -3.2511873 -38.95999828
OS -3.3297749 -38.95999828
OS -3.3297749 -38.66876188
OS -3.3297749 -38.66783732
OS -3.3297749 -38.66691276
OS -3.3297749 -38.6613654
OS -3.3297749 -38.65304436
OS -3.33069946 -38.6428742
OS -3.33162402 -38.63177948
OS -3.33254858 -38.62068476
OS -3.3343977 -38.60959004
OS -3.33717138 -38.601269
OS -3.33717138 -38.60034444
OS -3.3390205 -38.59757076
OS -3.34086962 -38.59387252
OS -3.3436433 -38.58924972
OS -3.34734154 -38.58370236
OS -3.35196434 -38.578155
OS -3.3575117 -38.57260764
OS -3.36490818 -38.56706028
OS -3.36583274 -38.56613572
OS -3.36860642 -38.56521116
OS -3.37230466 -38.56336204
OS -3.37877658 -38.56058836
OS -3.3852485 -38.55781468
OS -3.39356954 -38.55596556
OS -3.40189058 -38.555041
OS -3.41206074 -38.55411644
OS -3.41668354 -38.55411644
OS -3.42038178 -38.555041
OS -3.42962738 -38.55596556
OS -3.4407221 -38.55781468
OS -3.45366594 -38.56243748
OS -3.46753434 -38.56798484
OS -3.48140274 -38.57630588
OS -3.49434658 -38.5874006
OS -3.49527114 -38.58924972
OS -3.49896938 -38.59387252
OS -3.50451674 -38.601269
OS -3.5100641 -38.61236372
OS -3.51653602 -38.62715668
OS -3.52115882 -38.64472332
OS -3.52485706 -38.6659882
OS -3.52670618 -38.69095132
OS -3.52670618 -38.95999828
OS -3.60529378 -38.95999828
OS -3.60529378 -38.65951628
OS -3.60529378 -38.65859172
OS -3.60529378 -38.6567426
OS -3.60529378 -38.65489348
OS -3.60529378 -38.65119524
OS -3.60621834 -38.64102508
OS -3.60806746 -38.62993036
OS -3.60991658 -38.61698652
OS -3.61361482 -38.60404268
OS -3.61823762 -38.5920234
OS -3.62470954 -38.58092868
OS -3.6256341 -38.58000412
OS -3.62840778 -38.57630588
OS -3.63303058 -38.57260764
OS -3.6395025 -38.56706028
OS -3.64782354 -38.56243748
OS -3.65891826 -38.55781468
OS -3.6718621 -38.555041
OS -3.68757962 -38.55411644
OS -3.69312698 -38.55411644
OS -3.6995989 -38.555041
OS -3.70699538 -38.55596556
OS -3.71624098 -38.55873924
OS -3.7273357 -38.56151292
OS -3.73750586 -38.56613572
OS -3.74860058 -38.57168308
OS -3.74952514 -38.57260764
OS -3.75322338 -38.57538132
OS -3.75784618 -38.57907956
OS -3.7643181 -38.58462692
OS -3.77079002 -38.5920234
OS -3.77726194 -38.601269
OS -3.78373386 -38.61143916
OS -3.78928122 -38.62345844
OS -3.79020578 -38.62530756
OS -3.79113034 -38.62993036
OS -3.79297946 -38.63732684
OS -3.79575314 -38.647497
OS -3.79852682 -38.6613654
OS -3.80037594 -38.67800748
OS -3.8013005 -38.69742324
OS -3.80222506 -38.71961268
OS -3.80222506 -38.95999828
OS -3.88081266 -38.95999828
OS -3.88081266 -38.49586916
OS -3.8105461 -38.49586916
OS -3.8105461 -38.56243748
OS -3.80962154 -38.56058836
OS -3.80684786 -38.55689012
OS -3.8013005 -38.5504182
OS -3.79482858 -38.54302172
OS -3.78650754 -38.53377612
OS -3.77633738 -38.52453052
OS -3.76524266 -38.51528492
OS -3.75229882 -38.50696388
OS -3.7504497 -38.50603932
OS -3.7458269 -38.50326564
OS -3.73843042 -38.50049196
OS -3.72826026 -38.49586916
OS -3.71624098 -38.49217092
OS -3.70237258 -38.48939724
OS -3.68665506 -38.48662356
OS -3.67001298 -38.485699
OS -3.66169194 -38.485699
OS -3.65152178 -38.48662356
OS -3.64042706 -38.48847268
OS -3.62655866 -38.49124636
OS -3.61269026 -38.4949446
OS -3.59882186 -38.50049196
OS -3.58587802 -38.50788844
OS -3.5840289 -38.508813
OS -3.58033066 -38.51158668
OS -3.5747833 -38.51620948
OS -3.56738682 -38.52360596
OS -3.55999034 -38.531927
OS -3.5516693 -38.54209716
OS -3.54427282 -38.55411644
OS -3.53872546 -38.56798484
OS -3.5378009 -38.56706028
OS -3.53595178 -38.5642866
OS -3.5331781 -38.56058836
OS -3.5285553 -38.555041
OS -3.52300794 -38.54856908
OS -3.51653602 -38.54209716
OS -3.50913954 -38.53470068
OS -3.49989394 -38.52637964
OS -3.48972378 -38.51898316
OS -3.47955362 -38.51158668
OS -3.46753434 -38.50511476
OS -3.4545905 -38.49864284
OS -3.4407221 -38.49309548
OS -3.42592914 -38.48939724
OS -3.41113618 -38.48662356
OS -3.3944941 -38.485699
OS -3.38802218 -38.485699
OS -3.38339938 -38.48662356
OE
OB -5.16872474 -38.48662356 I
OS -5.1604037 -38.48754812
OS -5.1511581 -38.48939724
OS -5.14098794 -38.49124636
OS -5.12896866 -38.49309548
OS -5.10400554 -38.50141652
OS -5.0910617 -38.50603932
OS -5.07811786 -38.51251124
OS -5.06517402 -38.51898316
OS -5.05223018 -38.52822876
OS -5.0402109 -38.53747436
OS -5.02819162 -38.54856908
OS -5.02726706 -38.54949364
OS -5.02541794 -38.55134276
OS -5.02264426 -38.555041
OS -5.01894602 -38.5596638
OS -5.01432322 -38.56613572
OS -5.00877586 -38.57445676
OS -5.0032285 -38.58370236
OS -4.99768114 -38.59387252
OS -4.99213378 -38.60496724
OS -4.98658642 -38.61883564
OS -4.98103906 -38.63270404
OS -4.97641626 -38.64842156
OS -4.97271802 -38.66506364
OS -4.96994434 -38.68263028
OS -4.96809522 -38.70112148
OS -4.96717066 -38.7214618
OS -4.96717066 -38.72238636
OS -4.96717066 -38.72516004
OS -4.96717066 -38.72978284
OS -4.96717066 -38.73625476
OS -4.96809522 -38.74365124
OS -4.96901978 -38.75289684
OS -4.96901978 -38.76214244
OS -4.9708689 -38.7723126
OS -4.97364258 -38.7954266
OS -4.97918994 -38.8185406
OS -4.98566186 -38.8416546
OS -4.99490746 -38.86291948
OS -4.99490746 -38.86384404
OS -4.99583202 -38.8647686
OS -4.99768114 -38.86754228
OS -4.99953026 -38.87124052
OS -5.00600218 -38.88048612
OS -5.01432322 -38.89158084
OS -5.02541794 -38.90452468
OS -5.03928634 -38.91746852
OS -5.05500386 -38.93041236
OS -5.07349506 -38.94243164
OS -5.07441962 -38.94243164
OS -5.07534418 -38.9433562
OS -5.07811786 -38.94520532
OS -5.08274066 -38.94705444
OS -5.08736346 -38.94890356
OS -5.09291082 -38.95075268
OS -5.10677922 -38.95630004
OS -5.12249674 -38.96092284
OS -5.1419125 -38.96554564
OS -5.16225282 -38.96924388
OS -5.18444226 -38.97016844
OS -5.19368786 -38.97016844
OS -5.20108434 -38.96924388
OS -5.20940538 -38.96831932
OS -5.21865098 -38.9664702
OS -5.2297457 -38.96462108
OS -5.24084042 -38.96277196
OS -5.26580354 -38.95537548
OS -5.27967194 -38.94982812
OS -5.29261578 -38.94428076
OS -5.30555962 -38.93688428
OS -5.31850346 -38.92856324
OS -5.33052274 -38.91931764
OS -5.34254202 -38.90822292
OS -5.34346658 -38.90729836
OS -5.3453157 -38.90544924
OS -5.34808938 -38.901751
OS -5.35178762 -38.89620364
OS -5.35641042 -38.88973172
OS -5.36103322 -38.88233524
OS -5.36658058 -38.87308964
OS -5.37212794 -38.86199492
OS -5.3776753 -38.84997564
OS -5.38322266 -38.83610724
OS -5.38784546 -38.82131428
OS -5.39246826 -38.80559676
OS -5.3961665 -38.78803012
OS -5.39894018 -38.76953892
OS -5.4007893 -38.7491986
OS -5.40171386 -38.72793372
OS -5.40171386 -38.7260846
OS -5.40171386 -38.72238636
OS -5.4007893 -38.71591444
OS -5.4007893 -38.70666884
OS -5.39986474 -38.69649868
OS -5.39801562 -38.68355484
OS -5.3961665 -38.670611
OS -5.39246826 -38.65581804
OS -5.38877002 -38.64102508
OS -5.38414722 -38.62530756
OS -5.37859986 -38.60866548
OS -5.37120338 -38.59294796
OS -5.3638069 -38.578155
OS -5.35363674 -38.56336204
OS -5.34346658 -38.54949364
OS -5.33052274 -38.53747436
OS -5.32959818 -38.5365498
OS -5.32774906 -38.53562524
OS -5.32405082 -38.53285156
OS -5.31942802 -38.52915332
OS -5.31388066 -38.52545508
OS -5.30648418 -38.52083228
OS -5.2990877 -38.51620948
OS -5.2898421 -38.51158668
OS -5.27967194 -38.50696388
OS -5.26857722 -38.50234108
OS -5.2436141 -38.49402004
OS -5.21495274 -38.48754812
OS -5.20015978 -38.48662356
OS -5.18444226 -38.485699
OS -5.17519666 -38.485699
OS -5.16872474 -38.48662356
OE
OB -4.78318322 -38.49586916 I
OS -4.70367106 -38.49586916
OS -4.70367106 -38.55689012
OS -4.78318322 -38.55689012
OS -4.78318322 -38.82963532
OS -4.78318322 -38.83148444
OS -4.78318322 -38.83518268
OS -4.78318322 -38.84073004
OS -4.78225866 -38.84720196
OS -4.7813341 -38.86199492
OS -4.78040954 -38.86846684
OS -4.77948498 -38.87308964
OS -4.77856042 -38.87493876
OS -4.77578674 -38.878637
OS -4.7720885 -38.8832598
OS -4.76561658 -38.8878826
OS -4.76376746 -38.88880716
OS -4.75914466 -38.89065628
OS -4.75082362 -38.8925054
OS -4.73880434 -38.89342996
OS -4.72955874 -38.89342996
OS -4.72493594 -38.8925054
OS -4.71846402 -38.8925054
OS -4.71106754 -38.89158084
OS -4.70367106 -38.89065628
OS -4.6935009 -38.95999828
OS -4.69535002 -38.95999828
OS -4.69904826 -38.96092284
OS -4.70552018 -38.9618474
OS -4.71384122 -38.96277196
OS -4.72308682 -38.96462108
OS -4.73325698 -38.96554564
OS -4.7535973 -38.9664702
OS -4.76099378 -38.9664702
OS -4.76839026 -38.96554564
OS -4.77763586 -38.96462108
OS -4.78873058 -38.96369652
OS -4.7998253 -38.96092284
OS -4.80999546 -38.95814916
OS -4.82016562 -38.95352636
OS -4.82109018 -38.9526018
OS -4.82386386 -38.95075268
OS -4.8275621 -38.947979
OS -4.83310946 -38.9433562
OS -4.83773226 -38.9387334
OS -4.84327962 -38.93226148
OS -4.84882698 -38.92578956
OS -4.85252522 -38.91746852
OS -4.85252522 -38.91654396
OS -4.85437434 -38.91284572
OS -4.8552989 -38.9063738
OS -4.85714802 -38.8971282
OS -4.85899714 -38.88510892
OS -4.8599217 -38.87771244
OS -4.8599217 -38.8693914
OS -4.86084626 -38.85922124
OS -4.86177082 -38.84905108
OS -4.86177082 -38.83795636
OS -4.86177082 -38.82501252
OS -4.86177082 -38.55689012
OS -4.9200181 -38.55689012
OS -4.9200181 -38.49586916
OS -4.86177082 -38.49586916
OS -4.86177082 -38.38122372
OS -4.78318322 -38.33407116
OS -4.78318322 -38.49586916
OE
OB -5.79280274 -38.54856908 I
OS -5.79187818 -38.54764452
OS -5.79095362 -38.5457954
OS -5.78817994 -38.54302172
OS -5.78355714 -38.53839892
OS -5.77893434 -38.53377612
OS -5.77338698 -38.52822876
OS -5.7659905 -38.5226814
OS -5.75859402 -38.51713404
OS -5.74010282 -38.50511476
OS -5.71883794 -38.49586916
OS -5.70681866 -38.49124636
OS -5.69387482 -38.48847268
OS -5.68000642 -38.48662356
OS -5.66613802 -38.485699
OS -5.65874154 -38.485699
OS -5.6504205 -38.48662356
OS -5.64025034 -38.48754812
OS -5.62823106 -38.4903218
OS -5.61436266 -38.49309548
OS -5.5995697 -38.49771828
OS -5.5857013 -38.50326564
OS -5.58385218 -38.5041902
OS -5.57922938 -38.50603932
OS -5.5718329 -38.51066212
OS -5.56351186 -38.51620948
OS -5.5533417 -38.5226814
OS -5.54317154 -38.53100244
OS -5.53207682 -38.5411726
OS -5.52283122 -38.55226732
OS -5.52190666 -38.55319188
OS -5.51913298 -38.55781468
OS -5.51451018 -38.5642866
OS -5.50896282 -38.57260764
OS -5.5024909 -38.58370236
OS -5.49601898 -38.5966462
OS -5.48954706 -38.61143916
OS -5.4839997 -38.62715668
OS -5.4839997 -38.62808124
OS -5.48307514 -38.6290058
OS -5.48215058 -38.63177948
OS -5.48122602 -38.63455316
OS -5.4793769 -38.64379876
OS -5.47660322 -38.65581804
OS -5.47382954 -38.66968644
OS -5.47105586 -38.68540396
OS -5.4701313 -38.7029706
OS -5.46920674 -38.7214618
OS -5.46920674 -38.72238636
OS -5.46920674 -38.72700916
OS -5.46920674 -38.73255652
OS -5.4701313 -38.74087756
OS -5.47105586 -38.75104772
OS -5.47198042 -38.76214244
OS -5.47382954 -38.77508628
OS -5.47660322 -38.78895468
OS -5.4839997 -38.8185406
OS -5.4886225 -38.83425812
OS -5.49416986 -38.84905108
OS -5.50064178 -38.8647686
OS -5.50896282 -38.878637
OS -5.51820842 -38.8925054
OS -5.52837858 -38.90544924
OS -5.52930314 -38.9063738
OS -5.53115226 -38.90822292
OS -5.53392594 -38.9109966
OS -5.53854874 -38.9156194
OS -5.54502066 -38.9202422
OS -5.55149258 -38.92578956
OS -5.55888906 -38.93133692
OS -5.56813466 -38.93780884
OS -5.57830482 -38.9433562
OS -5.58847498 -38.94982812
OS -5.6134381 -38.95999828
OS -5.62638194 -38.96462108
OS -5.64025034 -38.96739476
OS -5.6550433 -38.96924388
OS -5.66983626 -38.97016844
OS -5.6735345 -38.97016844
OS -5.6781573 -38.96924388
OS -5.68370466 -38.96924388
OS -5.69017658 -38.96831932
OS -5.69849762 -38.9664702
OS -5.71698882 -38.9618474
OS -5.72715898 -38.95814916
OS -5.73732914 -38.95352636
OS -5.74842386 -38.947979
OS -5.75859402 -38.94150708
OS -5.76968874 -38.93318604
OS -5.7798589 -38.92394044
OS -5.7891045 -38.91377028
OS -5.7983501 -38.901751
OS -5.7983501 -38.95999828
OS -5.87139034 -38.95999828
OS -5.87139034 -38.32020276
OS -5.79280274 -38.32020276
OS -5.79280274 -38.54856908
OE
OB -5.97031826 -38.42745172 I
OS -5.99158314 -38.54671996
OS -6.04058482 -38.54671996
OS -6.06000058 -38.42745172
OS -6.06000058 -38.32020276
OS -5.97031826 -38.32020276
OS -5.97031826 -38.42745172
OE
OB -4.17389818 -38.48662356 I
OS -4.16557714 -38.48754812
OS -4.15633154 -38.48939724
OS -4.14616138 -38.49124636
OS -4.1341421 -38.49309548
OS -4.10917898 -38.50141652
OS -4.09623514 -38.50603932
OS -4.0832913 -38.51251124
OS -4.07034746 -38.51898316
OS -4.05740362 -38.52822876
OS -4.04538434 -38.53747436
OS -4.03336506 -38.54856908
OS -4.0324405 -38.54949364
OS -4.03059138 -38.55134276
OS -4.0278177 -38.555041
OS -4.02411946 -38.5596638
OS -4.01949666 -38.56613572
OS -4.0139493 -38.57445676
OS -4.00840194 -38.58370236
OS -4.00285458 -38.59387252
OS -3.99730722 -38.60496724
OS -3.99175986 -38.61883564
OS -3.9862125 -38.63270404
OS -3.9815897 -38.64842156
OS -3.97789146 -38.66506364
OS -3.97511778 -38.68263028
OS -3.97326866 -38.70112148
OS -3.9723441 -38.7214618
OS -3.9723441 -38.72238636
OS -3.9723441 -38.72516004
OS -3.9723441 -38.72978284
OS -3.9723441 -38.73625476
OS -3.97326866 -38.74365124
OS -3.97419322 -38.75289684
OS -3.97419322 -38.76214244
OS -3.97604234 -38.7723126
OS -3.97881602 -38.7954266
OS -3.98436338 -38.8185406
OS -3.9908353 -38.8416546
OS -4.0000809 -38.86291948
OS -4.0000809 -38.86384404
OS -4.00100546 -38.8647686
OS -4.00285458 -38.86754228
OS -4.0047037 -38.87124052
OS -4.01117562 -38.88048612
OS -4.01949666 -38.89158084
OS -4.03059138 -38.90452468
OS -4.04445978 -38.91746852
OS -4.0601773 -38.93041236
OS -4.0786685 -38.94243164
OS -4.07959306 -38.94243164
OS -4.08051762 -38.9433562
OS -4.0832913 -38.94520532
OS -4.0879141 -38.94705444
OS -4.0925369 -38.94890356
OS -4.09808426 -38.95075268
OS -4.11195266 -38.95630004
OS -4.12767018 -38.96092284
OS -4.14708594 -38.96554564
OS -4.16742626 -38.96924388
OS -4.1896157 -38.97016844
OS -4.1988613 -38.97016844
OS -4.20625778 -38.96924388
OS -4.21457882 -38.96831932
OS -4.22382442 -38.9664702
OS -4.23491914 -38.96462108
OS -4.24601386 -38.96277196
OS -4.27097698 -38.95537548
OS -4.28484538 -38.94982812
OS -4.29778922 -38.94428076
OS -4.31073306 -38.93688428
OS -4.3236769 -38.92856324
OS -4.33569618 -38.91931764
OS -4.34771546 -38.90822292
OS -4.34864002 -38.90729836
OS -4.35048914 -38.90544924
OS -4.35326282 -38.901751
OS -4.35696106 -38.89620364
OS -4.36158386 -38.88973172
OS -4.36620666 -38.88233524
OS -4.37175402 -38.87308964
OS -4.37730138 -38.86199492
OS -4.38284874 -38.84997564
OS -4.3883961 -38.83610724
OS -4.3930189 -38.82131428
OS -4.3976417 -38.80559676
OS -4.40133994 -38.78803012
OS -4.40411362 -38.76953892
OS -4.40596274 -38.7491986
OS -4.4068873 -38.72793372
OS -4.4068873 -38.7260846
OS -4.4068873 -38.72238636
OS -4.40596274 -38.71591444
OS -4.40596274 -38.70666884
OS -4.40503818 -38.69649868
OS -4.40318906 -38.68355484
OS -4.40133994 -38.670611
OS -4.3976417 -38.65581804
OS -4.39394346 -38.64102508
OS -4.38932066 -38.62530756
OS -4.3837733 -38.60866548
OS -4.37637682 -38.59294796
OS -4.36898034 -38.578155
OS -4.35881018 -38.56336204
OS -4.34864002 -38.54949364
OS -4.33569618 -38.53747436
OS -4.33477162 -38.5365498
OS -4.3329225 -38.53562524
OS -4.32922426 -38.53285156
OS -4.32460146 -38.52915332
OS -4.3190541 -38.52545508
OS -4.31165762 -38.52083228
OS -4.30426114 -38.51620948
OS -4.29501554 -38.51158668
OS -4.28484538 -38.50696388
OS -4.27375066 -38.50234108
OS -4.24878754 -38.49402004
OS -4.22012618 -38.48754812
OS -4.20533322 -38.48662356
OS -4.1896157 -38.485699
OS -4.1803701 -38.485699
OS -4.17389818 -38.48662356
OE
OB -4.53447658 -38.49586916 I
OS -4.45496442 -38.49586916
OS -4.45496442 -38.55689012
OS -4.53447658 -38.55689012
OS -4.53447658 -38.82963532
OS -4.53447658 -38.83148444
OS -4.53447658 -38.83518268
OS -4.53447658 -38.84073004
OS -4.53355202 -38.84720196
OS -4.53262746 -38.86199492
OS -4.5317029 -38.86846684
OS -4.53077834 -38.87308964
OS -4.52985378 -38.87493876
OS -4.5270801 -38.878637
OS -4.52338186 -38.8832598
OS -4.51690994 -38.8878826
OS -4.51506082 -38.88880716
OS -4.51043802 -38.89065628
OS -4.50211698 -38.8925054
OS -4.4900977 -38.89342996
OS -4.4808521 -38.89342996
OS -4.4762293 -38.8925054
OS -4.46975738 -38.8925054
OS -4.4623609 -38.89158084
OS -4.45496442 -38.89065628
OS -4.44479426 -38.95999828
OS -4.44664338 -38.95999828
OS -4.45034162 -38.96092284
OS -4.45681354 -38.9618474
OS -4.46513458 -38.96277196
OS -4.47438018 -38.96462108
OS -4.48455034 -38.96554564
OS -4.50489066 -38.9664702
OS -4.51228714 -38.9664702
OS -4.51968362 -38.96554564
OS -4.52892922 -38.96462108
OS -4.54002394 -38.96369652
OS -4.55111866 -38.96092284
OS -4.56128882 -38.95814916
OS -4.57145898 -38.95352636
OS -4.57238354 -38.9526018
OS -4.57515722 -38.95075268
OS -4.57885546 -38.947979
OS -4.58440282 -38.9433562
OS -4.58902562 -38.9387334
OS -4.59457298 -38.93226148
OS -4.60012034 -38.92578956
OS -4.60381858 -38.91746852
OS -4.60381858 -38.91654396
OS -4.6056677 -38.91284572
OS -4.60659226 -38.9063738
OS -4.60844138 -38.8971282
OS -4.6102905 -38.88510892
OS -4.61121506 -38.87771244
OS -4.61121506 -38.8693914
OS -4.61213962 -38.85922124
OS -4.61306418 -38.84905108
OS -4.61306418 -38.83795636
OS -4.61306418 -38.82501252
OS -4.61306418 -38.55689012
OS -4.67131146 -38.55689012
OS -4.67131146 -38.49586916
OS -4.61306418 -38.49586916
OS -4.61306418 -38.38122372
OS -4.53447658 -38.33407116
OS -4.53447658 -38.49586916
OE
OB -2.44959378 -38.5504182 H
OS -2.45514114 -38.5504182
OS -2.45976394 -38.55134276
OS -2.4699341 -38.55226732
OS -2.4838025 -38.55596556
OS -2.49952002 -38.56151292
OS -2.5161621 -38.5689094
OS -2.53187962 -38.58000412
OS -2.54020066 -38.5874006
OS -2.54759714 -38.59479708
OS -2.54759714 -38.59572164
OS -2.54944626 -38.5966462
OS -2.55129538 -38.59941988
OS -2.55406906 -38.60311812
OS -2.55684274 -38.60774092
OS -2.55961642 -38.61328828
OS -2.56331466 -38.62068476
OS -2.5670129 -38.62808124
OS -2.57071114 -38.63732684
OS -2.57440938 -38.64657244
OS -2.57718306 -38.65766716
OS -2.57995674 -38.66968644
OS -2.58273042 -38.68263028
OS -2.58457954 -38.69649868
OS -2.5855041 -38.7122162
OS -2.58642866 -38.72793372
OS -2.58642866 -38.72885828
OS -2.58642866 -38.73163196
OS -2.58642866 -38.73625476
OS -2.5855041 -38.74272668
OS -2.5855041 -38.75012316
OS -2.58457954 -38.7584442
OS -2.58180586 -38.77785996
OS -2.57718306 -38.8000494
OS -2.56978658 -38.82223884
OS -2.56054098 -38.84350372
OS -2.55406906 -38.85274932
OS -2.54759714 -38.86199492
OS -2.54667258 -38.86199492
OS -2.54574802 -38.86384404
OS -2.54020066 -38.86846684
OS -2.53187962 -38.87586332
OS -2.5207849 -38.8832598
OS -2.5069165 -38.89158084
OS -2.49027442 -38.89897732
OS -2.47085866 -38.90360012
OS -2.4606885 -38.90452468
OS -2.44959378 -38.90544924
OS -2.44404642 -38.90544924
OS -2.43942362 -38.90452468
OS -2.42925346 -38.90267556
OS -2.41538506 -38.89990188
OS -2.4005921 -38.89435452
OS -2.38395002 -38.88695804
OS -2.3682325 -38.87586332
OS -2.35991146 -38.86846684
OS -2.35251498 -38.86107036
OS -2.35159042 -38.8601458
OS -2.35066586 -38.85922124
OS -2.34881674 -38.85644756
OS -2.34604306 -38.85274932
OS -2.34326938 -38.84812652
OS -2.33957114 -38.84257916
OS -2.3358729 -38.83518268
OS -2.33217466 -38.8277862
OS -2.32847642 -38.8185406
OS -2.32570274 -38.80837044
OS -2.3220045 -38.79727572
OS -2.31923082 -38.78525644
OS -2.31645714 -38.77138804
OS -2.31460802 -38.75751964
OS -2.3127589 -38.74180212
OS -2.3127589 -38.72516004
OS -2.3127589 -38.72423548
OS -2.3127589 -38.7214618
OS -2.3127589 -38.716839
OS -2.31368346 -38.71129164
OS -2.31368346 -38.70389516
OS -2.31460802 -38.69557412
OS -2.3173817 -38.67615836
OS -2.3220045 -38.65581804
OS -2.32940098 -38.6336286
OS -2.33957114 -38.61328828
OS -2.3451185 -38.60311812
OS -2.35251498 -38.59479708
OS -2.35251498 -38.59387252
OS -2.3543641 -38.59294796
OS -2.35991146 -38.5874006
OS -2.3682325 -38.58092868
OS -2.37932722 -38.57260764
OS -2.39319562 -38.5642866
OS -2.4098377 -38.55689012
OS -2.4283289 -38.55226732
OS -2.43849906 -38.55134276
OS -2.44959378 -38.5504182
OE
OB -5.6642889 -38.5504182 H
OS -5.6781573 -38.5504182
OS -5.68185554 -38.55134276
OS -5.6920257 -38.55319188
OS -5.70404498 -38.55596556
OS -5.71791338 -38.56151292
OS -5.73270634 -38.56983396
OS -5.74010282 -38.57445676
OS -5.7474993 -38.58092868
OS -5.75489578 -38.5874006
OS -5.76229226 -38.59572164
OS -5.76229226 -38.5966462
OS -5.76414138 -38.59757076
OS -5.7659905 -38.60034444
OS -5.76783962 -38.60404268
OS -5.7706133 -38.60866548
OS -5.77431154 -38.61421284
OS -5.77708522 -38.62068476
OS -5.78078346 -38.62808124
OS -5.7844817 -38.63732684
OS -5.78725538 -38.64657244
OS -5.79095362 -38.65766716
OS -5.7937273 -38.66876188
OS -5.79557642 -38.68170572
OS -5.79742554 -38.69557412
OS -5.79927466 -38.70944252
OS -5.79927466 -38.72516004
OS -5.79927466 -38.7260846
OS -5.79927466 -38.72885828
OS -5.79927466 -38.73348108
OS -5.79927466 -38.73902844
OS -5.7983501 -38.74550036
OS -5.7983501 -38.7538214
OS -5.79650098 -38.77138804
OS -5.7937273 -38.7908038
OS -5.79002906 -38.81114412
OS -5.7844817 -38.82963532
OS -5.78078346 -38.83795636
OS -5.77708522 -38.84535284
OS -5.77708522 -38.8462774
OS -5.7752361 -38.84812652
OS -5.77338698 -38.8509002
OS -5.7706133 -38.85459844
OS -5.76229226 -38.8647686
OS -5.75027298 -38.87493876
OS -5.73640458 -38.88603348
OS -5.71883794 -38.89620364
OS -5.70959234 -38.89990188
OS -5.69849762 -38.90267556
OS -5.68832746 -38.90452468
OS -5.67630818 -38.90544924
OS -5.67168538 -38.90544924
OS -5.66798714 -38.90452468
OS -5.65781698 -38.90267556
OS -5.6457977 -38.89990188
OS -5.6319293 -38.89435452
OS -5.61713634 -38.88695804
OS -5.60234338 -38.87586332
OS -5.5949469 -38.86846684
OS -5.58755042 -38.86107036
OS -5.58755042 -38.8601458
OS -5.5857013 -38.85922124
OS -5.58385218 -38.85644756
OS -5.58200306 -38.85274932
OS -5.57830482 -38.84812652
OS -5.57553114 -38.84257916
OS -5.5718329 -38.83518268
OS -5.56813466 -38.8277862
OS -5.56536098 -38.8185406
OS -5.56166274 -38.809295
OS -5.5579645 -38.79820028
OS -5.55519082 -38.786181
OS -5.5533417 -38.77323716
OS -5.55149258 -38.75936876
OS -5.54964346 -38.74365124
OS -5.54964346 -38.72793372
OS -5.54964346 -38.72700916
OS -5.54964346 -38.72423548
OS -5.54964346 -38.71961268
OS -5.55056802 -38.71314076
OS -5.55056802 -38.70574428
OS -5.55149258 -38.69649868
OS -5.55426626 -38.67708292
OS -5.5579645 -38.65581804
OS -5.56443642 -38.63270404
OS -5.57368202 -38.61236372
OS -5.57922938 -38.60219356
OS -5.5857013 -38.59387252
OS -5.5857013 -38.59294796
OS -5.58755042 -38.5920234
OS -5.59217322 -38.5874006
OS -5.5995697 -38.58000412
OS -5.60973986 -38.57168308
OS -5.6226837 -38.5642866
OS -5.63747666 -38.55689012
OS -5.6550433 -38.55226732
OS -5.6642889 -38.5504182
OE
OB -5.18444226 -38.5504182 H
OS -5.18998962 -38.5504182
OS -5.19461242 -38.55134276
OS -5.20478258 -38.55226732
OS -5.21865098 -38.55596556
OS -5.2343685 -38.56151292
OS -5.25101058 -38.5689094
OS -5.2667281 -38.58000412
OS -5.27504914 -38.5874006
OS -5.28244562 -38.59479708
OS -5.28244562 -38.59572164
OS -5.28429474 -38.5966462
OS -5.28614386 -38.59941988
OS -5.28891754 -38.60311812
OS -5.29169122 -38.60774092
OS -5.2944649 -38.61328828
OS -5.29816314 -38.62068476
OS -5.30186138 -38.62808124
OS -5.30555962 -38.63732684
OS -5.30925786 -38.64657244
OS -5.31203154 -38.65766716
OS -5.31480522 -38.66968644
OS -5.3175789 -38.68263028
OS -5.31942802 -38.69649868
OS -5.32035258 -38.7122162
OS -5.32127714 -38.72793372
OS -5.32127714 -38.72885828
OS -5.32127714 -38.73163196
OS -5.32127714 -38.73625476
OS -5.32035258 -38.74272668
OS -5.32035258 -38.75012316
OS -5.31942802 -38.7584442
OS -5.31665434 -38.77785996
OS -5.31203154 -38.8000494
OS -5.30463506 -38.82223884
OS -5.29538946 -38.84350372
OS -5.28891754 -38.85274932
OS -5.28244562 -38.86199492
OS -5.28152106 -38.86199492
OS -5.2805965 -38.86384404
OS -5.27504914 -38.86846684
OS -5.2667281 -38.87586332
OS -5.25563338 -38.8832598
OS -5.24176498 -38.89158084
OS -5.2251229 -38.89897732
OS -5.20570714 -38.90360012
OS -5.19553698 -38.90452468
OS -5.18444226 -38.90544924
OS -5.1788949 -38.90544924
OS -5.1742721 -38.90452468
OS -5.16410194 -38.90267556
OS -5.15023354 -38.89990188
OS -5.13544058 -38.89435452
OS -5.1187985 -38.88695804
OS -5.10308098 -38.87586332
OS -5.09475994 -38.86846684
OS -5.08736346 -38.86107036
OS -5.0864389 -38.8601458
OS -5.08551434 -38.85922124
OS -5.08366522 -38.85644756
OS -5.08089154 -38.85274932
OS -5.07811786 -38.84812652
OS -5.07441962 -38.84257916
OS -5.07072138 -38.83518268
OS -5.06702314 -38.8277862
OS -5.0633249 -38.8185406
OS -5.06055122 -38.80837044
OS -5.05685298 -38.79727572
OS -5.0540793 -38.78525644
OS -5.05130562 -38.77138804
OS -5.0494565 -38.75751964
OS -5.04760738 -38.74180212
OS -5.04760738 -38.72516004
OS -5.04760738 -38.72423548
OS -5.04760738 -38.7214618
OS -5.04760738 -38.716839
OS -5.04853194 -38.71129164
OS -5.04853194 -38.70389516
OS -5.0494565 -38.69557412
OS -5.05223018 -38.67615836
OS -5.05685298 -38.65581804
OS -5.06424946 -38.6336286
OS -5.07441962 -38.61328828
OS -5.07996698 -38.60311812
OS -5.08736346 -38.59479708
OS -5.08736346 -38.59387252
OS -5.08921258 -38.59294796
OS -5.09475994 -38.5874006
OS -5.10308098 -38.58092868
OS -5.1141757 -38.57260764
OS -5.1280441 -38.5642866
OS -5.14468618 -38.55689012
OS -5.16317738 -38.55226732
OS -5.17334754 -38.55134276
OS -5.18444226 -38.5504182
OE
OB -1.50191978 -38.5504182 H
OS -1.50746714 -38.5504182
OS -1.51116538 -38.55134276
OS -1.52133554 -38.55226732
OS -1.53335482 -38.555041
OS -1.54814778 -38.5596638
OS -1.5638653 -38.56613572
OS -1.57865826 -38.57538132
OS -1.59345122 -38.5874006
OS -1.59530034 -38.58924972
OS -1.59899858 -38.59387252
OS -1.6054705 -38.60219356
OS -1.61194242 -38.61328828
OS -1.6193389 -38.62623212
OS -1.62581082 -38.6428742
OS -1.63135818 -38.66228996
OS -1.63413186 -38.68355484
OS -1.3743305 -38.68355484
OS -1.3743305 -38.68263028
OS -1.3743305 -38.68078116
OS -1.37525506 -38.67800748
OS -1.37525506 -38.67430924
OS -1.37710418 -38.66321452
OS -1.37987786 -38.65119524
OS -1.38450066 -38.63640228
OS -1.38912346 -38.62253388
OS -1.39651994 -38.60866548
OS -1.40484098 -38.5966462
OS -1.40484098 -38.59572164
OS -1.4066901 -38.59479708
OS -1.4113129 -38.58924972
OS -1.41963394 -38.58185324
OS -1.43072866 -38.5735322
OS -1.44459706 -38.56521116
OS -1.46123914 -38.55781468
OS -1.4806549 -38.55226732
OS -1.49082506 -38.55134276
OS -1.50191978 -38.5504182
OE
OB -4.1896157 -38.5504182 H
OS -4.19516306 -38.5504182
OS -4.19978586 -38.55134276
OS -4.20995602 -38.55226732
OS -4.22382442 -38.55596556
OS -4.23954194 -38.56151292
OS -4.25618402 -38.5689094
OS -4.27190154 -38.58000412
OS -4.28022258 -38.5874006
OS -4.28761906 -38.59479708
OS -4.28761906 -38.59572164
OS -4.28946818 -38.5966462
OS -4.2913173 -38.59941988
OS -4.29409098 -38.60311812
OS -4.29686466 -38.60774092
OS -4.29963834 -38.61328828
OS -4.30333658 -38.62068476
OS -4.30703482 -38.62808124
OS -4.31073306 -38.63732684
OS -4.3144313 -38.64657244
OS -4.31720498 -38.65766716
OS -4.31997866 -38.66968644
OS -4.32275234 -38.68263028
OS -4.32460146 -38.69649868
OS -4.32552602 -38.7122162
OS -4.32645058 -38.72793372
OS -4.32645058 -38.72885828
OS -4.32645058 -38.73163196
OS -4.32645058 -38.73625476
OS -4.32552602 -38.74272668
OS -4.32552602 -38.75012316
OS -4.32460146 -38.7584442
OS -4.32182778 -38.77785996
OS -4.31720498 -38.8000494
OS -4.3098085 -38.82223884
OS -4.3005629 -38.84350372
OS -4.29409098 -38.85274932
OS -4.28761906 -38.86199492
OS -4.2866945 -38.86199492
OS -4.28576994 -38.86384404
OS -4.28022258 -38.86846684
OS -4.27190154 -38.87586332
OS -4.26080682 -38.8832598
OS -4.24693842 -38.89158084
OS -4.23029634 -38.89897732
OS -4.21088058 -38.90360012
OS -4.20071042 -38.90452468
OS -4.1896157 -38.90544924
OS -4.18406834 -38.90544924
OS -4.17944554 -38.90452468
OS -4.16927538 -38.90267556
OS -4.15540698 -38.89990188
OS -4.14061402 -38.89435452
OS -4.12397194 -38.88695804
OS -4.10825442 -38.87586332
OS -4.09993338 -38.86846684
OS -4.0925369 -38.86107036
OS -4.09161234 -38.8601458
OS -4.09068778 -38.85922124
OS -4.08883866 -38.85644756
OS -4.08606498 -38.85274932
OS -4.0832913 -38.84812652
OS -4.07959306 -38.84257916
OS -4.07589482 -38.83518268
OS -4.07219658 -38.8277862
OS -4.06849834 -38.8185406
OS -4.06572466 -38.80837044
OS -4.06202642 -38.79727572
OS -4.05925274 -38.78525644
OS -4.05647906 -38.77138804
OS -4.05462994 -38.75751964
OS -4.05278082 -38.74180212
OS -4.05278082 -38.72516004
OS -4.05278082 -38.72423548
OS -4.05278082 -38.7214618
OS -4.05278082 -38.716839
OS -4.05370538 -38.71129164
OS -4.05370538 -38.70389516
OS -4.05462994 -38.69557412
OS -4.05740362 -38.67615836
OS -4.06202642 -38.65581804
OS -4.0694229 -38.6336286
OS -4.07959306 -38.61328828
OS -4.08514042 -38.60311812
OS -4.0925369 -38.59479708
OS -4.0925369 -38.59387252
OS -4.09438602 -38.59294796
OS -4.09993338 -38.5874006
OS -4.10825442 -38.58092868
OS -4.11934914 -38.57260764
OS -4.13321754 -38.5642866
OS -4.14985962 -38.55689012
OS -4.16835082 -38.55226732
OS -4.17852098 -38.55134276
OS -4.1896157 -38.5504182
OE
OB -0.40169338 -38.72700916 H
OS -0.40261794 -38.72700916
OS -0.4035425 -38.72793372
OS -0.40631618 -38.72885828
OS -0.41001442 -38.72978284
OS -0.41463722 -38.73163196
OS -0.42018458 -38.73348108
OS -0.4266565 -38.7353302
OS -0.43405298 -38.73717932
OS -0.44237402 -38.739953
OS -0.45254418 -38.74180212
OS -0.46271434 -38.7445758
OS -0.47473362 -38.74734948
OS -0.48767746 -38.75012316
OS -0.5006213 -38.75289684
OS -0.51541426 -38.75474596
OS -0.53113178 -38.75751964
OS -0.5329809 -38.75751964
OS -0.53852826 -38.7584442
OS -0.54777386 -38.76029332
OS -0.55794402 -38.76214244
OS -0.56903874 -38.76399156
OS -0.58013346 -38.76676524
OS -0.59030362 -38.76953892
OS -0.59954922 -38.77323716
OS -0.60047378 -38.77323716
OS -0.60324746 -38.77508628
OS -0.6069457 -38.7769354
OS -0.61064394 -38.77970908
OS -0.62173866 -38.78710556
OS -0.63098426 -38.79820028
OS -0.63098426 -38.79912484
OS -0.63283338 -38.80097396
OS -0.63375794 -38.8046722
OS -0.63560706 -38.809295
OS -0.63745618 -38.81484236
OS -0.6393053 -38.82038972
OS -0.64022986 -38.8277862
OS -0.64115442 -38.83518268
OS -0.64115442 -38.83610724
OS -0.64115442 -38.84073004
OS -0.64022986 -38.8462774
OS -0.63838074 -38.85367388
OS -0.63560706 -38.86199492
OS -0.63098426 -38.87031596
OS -0.6254369 -38.87956156
OS -0.61804042 -38.8878826
OS -0.61711586 -38.88880716
OS -0.61341762 -38.89065628
OS -0.60787026 -38.89435452
OS -0.60047378 -38.89805276
OS -0.59030362 -38.901751
OS -0.57828434 -38.90544924
OS -0.56441594 -38.90729836
OS -0.54777386 -38.90822292
OS -0.54037738 -38.90822292
OS -0.53113178 -38.90729836
OS -0.52096162 -38.90544924
OS -0.50801778 -38.90360012
OS -0.49507394 -38.89990188
OS -0.48120554 -38.89527908
OS -0.46733714 -38.88880716
OS -0.46548802 -38.8878826
OS -0.46178978 -38.88510892
OS -0.45531786 -38.88048612
OS -0.44792138 -38.8740142
OS -0.43960034 -38.86661772
OS -0.43035474 -38.85737212
OS -0.42295826 -38.8462774
OS -0.41556178 -38.83425812
OS -0.41463722 -38.83333356
OS -0.41371266 -38.82963532
OS -0.41186354 -38.8231634
OS -0.40908986 -38.81484236
OS -0.40631618 -38.80374764
OS -0.40446706 -38.7908038
OS -0.4035425 -38.77508628
OS -0.40261794 -38.75659508
OS -0.40169338 -38.72700916
OE
SE
S P 0
OB -4.66714078 -36.5016923 I
OS -4.65465922 -36.5016923
OS -4.62553558 -36.50307914
OS -4.5950251 -36.50723966
OS -4.56174094 -36.51140018
OS -4.53123046 -36.51833438
OS -4.51597522 -36.5224949
OS -4.50349366 -36.52665542
OS -4.50210682 -36.52665542
OS -4.50071998 -36.52804226
OS -4.49239894 -36.53220278
OS -4.47991738 -36.53775014
OS -4.46466214 -36.54745802
OS -4.44802006 -36.55993958
OS -4.42999114 -36.57658166
OS -4.41334906 -36.59599742
OS -4.39670698 -36.61818686
OS -4.39670698 -36.6195737
OS -4.39532014 -36.62096054
OS -4.38977278 -36.62928158
OS -4.38422542 -36.64314998
OS -4.37590438 -36.6611789
OS -4.36897018 -36.6819815
OS -4.36203598 -36.70694462
OS -4.35787546 -36.73329458
OS -4.35648862 -36.76241822
OS -4.35648862 -36.76380506
OS -4.35648862 -36.76657874
OS -4.35648862 -36.7721261
OS -4.35787546 -36.7790603
OS -4.35787546 -36.78876818
OS -4.3592623 -36.79847606
OS -4.36480966 -36.82205234
OS -4.3731307 -36.84978914
OS -4.38422542 -36.87891278
OS -4.4008675 -36.90803642
OS -4.41196222 -36.92190482
OS -4.42305694 -36.93577322
OS -4.42444378 -36.93716006
OS -4.42583062 -36.9385469
OS -4.42999114 -36.94270742
OS -4.4355385 -36.94686794
OS -4.4424727 -36.9524153
OS -4.45079374 -36.95796266
OS -4.46188846 -36.96489686
OS -4.47298318 -36.9732179
OS -4.48685158 -36.9801521
OS -4.50210682 -36.9870863
OS -4.5187489 -36.99540734
OS -4.53677782 -37.00234154
OS -4.55758042 -37.0078889
OS -4.57838302 -37.0148231
OS -4.6019593 -37.01898362
OS -4.62692242 -37.02314414
OS -4.62414874 -37.02453098
OS -4.61860138 -37.02730466
OS -4.61028034 -37.03285202
OS -4.59918562 -37.03839938
OS -4.5742225 -37.05365462
OS -4.56174094 -37.0633625
OS -4.55064622 -37.07168354
OS -4.54787254 -37.07445722
OS -4.54093834 -37.08139142
OS -4.52984362 -37.09248614
OS -4.51597522 -37.10635454
OS -4.50071998 -37.1257703
OS -4.48269106 -37.1465729
OS -4.46466214 -37.17153602
OS -4.44524638 -37.19927282
OS -4.28021242 -37.45999874
OS -4.43831218 -37.45999874
OS -4.56451462 -37.26029378
OS -4.56451462 -37.25890694
OS -4.5672883 -37.25613326
OS -4.57006198 -37.25197274
OS -4.5742225 -37.24642538
OS -4.58393038 -37.23117014
OS -4.59641194 -37.21175438
OS -4.61166718 -37.19095178
OS -4.62692242 -37.16876234
OS -4.64217766 -37.14795974
OS -4.65604606 -37.12854398
OS -4.6574329 -37.12715714
OS -4.66159342 -37.12160978
OS -4.66852762 -37.11328874
OS -4.6782355 -37.10358086
OS -4.6990381 -37.08277826
OS -4.71013282 -37.07307038
OS -4.72122754 -37.06474934
OS -4.72261438 -37.0633625
OS -4.72538806 -37.06197566
OS -4.73093542 -37.05920198
OS -4.73925646 -37.05504146
OS -4.7475775 -37.05088094
OS -4.75728538 -37.04672042
OS -4.77947482 -37.03978622
OS -4.78086166 -37.03978622
OS -4.78363534 -37.03839938
OS -4.7891827 -37.03839938
OS -4.7961169 -37.03701254
OS -4.80582478 -37.0356257
OS -4.8169195 -37.0356257
OS -4.83217474 -37.03423886
OS -4.99582186 -37.03423886
OS -4.99582186 -37.45999874
OS -5.12341114 -37.45999874
OS -5.12341114 -36.50030546
OS -4.6782355 -36.50030546
OS -4.66714078 -36.5016923
OE
OB -1.0100437 -37.45999874 I
OS -1.13208562 -37.45999874
OS -1.13208562 -36.65701838
OS -1.4122273 -37.45999874
OS -1.52594818 -37.45999874
OS -1.80331618 -36.64314998
OS -1.80331618 -37.45999874
OS -1.9253581 -37.45999874
OS -1.9253581 -36.50030546
OS -1.73536102 -36.50030546
OS -1.50791926 -37.1812439
OS -1.50791926 -37.18263074
OS -1.50653242 -37.18540442
OS -1.50514558 -37.18956494
OS -1.5023719 -37.19649914
OS -1.49682454 -37.21314122
OS -1.48989034 -37.23394382
OS -1.48295614 -37.2575201
OS -1.4746351 -37.28109638
OS -1.4677009 -37.30328582
OS -1.46215354 -37.32270158
OS -1.4607667 -37.3199279
OS -1.45937986 -37.3129937
OS -1.45521934 -37.30051214
OS -1.44967198 -37.28387006
OS -1.44273778 -37.26168062
OS -1.4330299 -37.23533066
OS -1.42332202 -37.20482018
OS -1.41084046 -37.16876234
OS -1.18062502 -36.50030546
OS -1.0100437 -36.50030546
OS -1.0100437 -37.45999874
OE
OB -2.02382374 -37.45999874 I
OS -2.1680551 -37.45999874
OS -2.28038914 -37.16876234
OS -2.68257274 -37.16876234
OS -2.78658574 -37.45999874
OS -2.92110922 -37.45999874
OS -2.55498346 -36.50030546
OS -2.41629946 -36.50030546
OS -2.02382374 -37.45999874
OE
OB -3.02928274 -37.45999874 I
OS -3.16103254 -37.45999874
OS -3.66306862 -36.70694462
OS -3.66306862 -37.45999874
OS -3.78511054 -37.45999874
OS -3.78511054 -36.50030546
OS -3.65474758 -36.50030546
OS -3.15132466 -37.25474642
OS -3.15132466 -36.50030546
OS -3.02928274 -36.50030546
OS -3.02928274 -37.45999874
OE
OB -5.3231161 -36.61402634 I
OS -5.89033366 -36.61402634
OS -5.89033366 -36.90664958
OS -5.35917394 -36.90664958
OS -5.35917394 -37.02037046
OS -5.89033366 -37.02037046
OS -5.89033366 -37.34627786
OS -5.30092666 -37.34627786
OS -5.30092666 -37.45999874
OS -6.01792294 -37.45999874
OS -6.01792294 -36.50030546
OS -5.3231161 -36.50030546
OS -5.3231161 -36.61402634
OE
OB -0.10721086 -36.61402634 I
OS -0.67442842 -36.61402634
OS -0.67442842 -36.90664958
OS -0.1432687 -36.90664958
OS -0.1432687 -37.02037046
OS -0.67442842 -37.02037046
OS -0.67442842 -37.34627786
OS -0.08502142 -37.34627786
OS -0.08502142 -37.45999874
OS -0.8020177 -37.45999874
OS -0.8020177 -36.50030546
OS -0.10721086 -36.50030546
OS -0.10721086 -36.61402634
OE
OB -8.43241138 -37.34627786 I
OS -7.95949894 -37.34627786
OS -7.95949894 -37.45999874
OS -8.56000066 -37.45999874
OS -8.56000066 -36.50030546
OS -8.43241138 -36.50030546
OS -8.43241138 -37.34627786
OE
OB -6.51718534 -37.05365462 I
OS -6.51718534 -37.45999874
OS -6.64477462 -37.45999874
OS -6.64477462 -37.05365462
OS -7.0150609 -36.50030546
OS -6.86112166 -36.50030546
OS -6.67251142 -36.79154186
OS -6.67251142 -36.7929287
OS -6.66973774 -36.79570238
OS -6.66696406 -36.7998629
OS -6.66419038 -36.80541026
OS -6.65864302 -36.81234446
OS -6.65309566 -36.8206655
OS -6.6406141 -36.8414681
OS -6.62535886 -36.86643122
OS -6.60871678 -36.89416802
OS -6.59068786 -36.92329166
OS -6.57404578 -36.95380214
OS -6.57404578 -36.9524153
OS -6.57265894 -36.94964162
OS -6.56988526 -36.9454811
OS -6.56572474 -36.93993374
OS -6.56156422 -36.93299954
OS -6.55601686 -36.9246785
OS -6.5435353 -36.9038759
OS -6.52828006 -36.87891278
OS -6.51025114 -36.84978914
OS -6.48944854 -36.81789182
OS -6.4672591 -36.78322082
OS -6.28280938 -36.50030546
OS -6.1344175 -36.50030546
OS -6.51718534 -37.05365462
OE
OB -7.01644774 -37.45999874 I
OS -7.1606791 -37.45999874
OS -7.27301314 -37.16876234
OS -7.67519674 -37.16876234
OS -7.77920974 -37.45999874
OS -7.91373322 -37.45999874
OS -7.54760746 -36.50030546
OS -7.40892346 -36.50030546
OS -7.01644774 -37.45999874
OE
OB -7.48103914 -36.60015794 H
OS -7.48103914 -36.60154478
OS -7.48242598 -36.60431846
OS -7.48242598 -36.60986582
OS -7.48519966 -36.61541318
OS -7.4865865 -36.62512106
OS -7.48936018 -36.63482894
OS -7.49490754 -36.65840522
OS -7.50184174 -36.68614202
OS -7.51154962 -36.7166525
OS -7.5212575 -36.74993666
OS -7.53373906 -36.78460766
OS -7.63775206 -37.06474934
OS -7.3132315 -37.06474934
OS -7.41308398 -36.80124974
OS -7.41308398 -36.7998629
OS -7.41447082 -36.79570238
OS -7.4172445 -36.78876818
OS -7.42001818 -36.78044714
OS -7.4241787 -36.77073926
OS -7.42833922 -36.7582577
OS -7.43249974 -36.7443893
OS -7.4380471 -36.7305209
OS -7.44914182 -36.69862358
OS -7.46023654 -36.66533942
OS -7.47133126 -36.63205526
OS -7.48103914 -36.60015794
OE
OB -4.69349074 -36.60709214 H
OS -4.99582186 -36.60709214
OS -4.99582186 -36.9246785
OS -4.71013282 -36.9246785
OS -4.69349074 -36.92329166
OS -4.67407498 -36.92190482
OS -4.65188554 -36.92051798
OS -4.6296961 -36.9177443
OS -4.60750666 -36.91358378
OS -4.5880909 -36.90803642
OS -4.58531722 -36.90664958
OS -4.57976986 -36.9038759
OS -4.57144882 -36.89971538
OS -4.5603541 -36.89416802
OS -4.54787254 -36.88584698
OS -4.53539098 -36.8761391
OS -4.52290942 -36.86365754
OS -4.51320154 -36.84978914
OS -4.5118147 -36.8484023
OS -4.50904102 -36.84285494
OS -4.5048805 -36.8345339
OS -4.49933314 -36.82343918
OS -4.49517262 -36.81095762
OS -4.4910121 -36.79708922
OS -4.48823842 -36.78044714
OS -4.48685158 -36.76380506
OS -4.48685158 -36.76241822
OS -4.48685158 -36.76103138
OS -4.48823842 -36.75271034
OS -4.48962526 -36.74022878
OS -4.49239894 -36.7235867
OS -4.49933314 -36.70694462
OS -4.50765418 -36.68752886
OS -4.52013574 -36.66949994
OS -4.53677782 -36.65147102
OS -4.5395515 -36.65008418
OS -4.5464857 -36.64453682
OS -4.55758042 -36.63760262
OS -4.57560934 -36.62928158
OS -4.59641194 -36.62096054
OS -4.62414874 -36.61402634
OS -4.65604606 -36.60847898
OS -4.69349074 -36.60709214
OE
OB -2.48841514 -36.60015794 H
OS -2.48841514 -36.60154478
OS -2.48980198 -36.60431846
OS -2.48980198 -36.60986582
OS -2.49257566 -36.61541318
OS -2.4939625 -36.62512106
OS -2.49673618 -36.63482894
OS -2.50228354 -36.65840522
OS -2.50921774 -36.68614202
OS -2.51892562 -36.7166525
OS -2.5286335 -36.74993666
OS -2.54111506 -36.78460766
OS -2.64512806 -37.06474934
OS -2.3206075 -37.06474934
OS -2.42045998 -36.80124974
OS -2.42045998 -36.7998629
OS -2.42184682 -36.79570238
OS -2.4246205 -36.78876818
OS -2.42739418 -36.78044714
OS -2.4315547 -36.77073926
OS -2.43571522 -36.7582577
OS -2.43987574 -36.7443893
OS -2.4454231 -36.7305209
OS -2.45651782 -36.69862358
OS -2.46761254 -36.66533942
OS -2.47870726 -36.63205526
OS -2.48841514 -36.60015794
OE
SE
S P 0
OB 0.21403564 39.15890568 I
OS 0.22790404 39.15983024
OS 0.49047908 39.15983024
OS 0.49047908 38.52003472
OS 0.40541956 38.52003472
OS 0.40541956 38.77983608
OS 0.24177244 38.77983608
OS 0.21773388 38.78076064
OS 0.19461988 38.78260976
OS 0.17427956 38.78538344
OS 0.15578836 38.78908168
OS 0.13822172 38.79277992
OS 0.12342876 38.79740272
OS 0.10956036 38.80295008
OS 0.09754108 38.80849744
OS 0.08737092 38.81312024
OS 0.07812532 38.8186676
OS 0.07072884 38.8232904
OS 0.06518148 38.8279132
OS 0.06055868 38.83068688
OS 0.057785 38.83346056
OS 0.05593588 38.83530968
OS 0.05501132 38.83623424
OS 0.04576572 38.84732896
OS 0.03744468 38.85842368
OS 0.03097276 38.8695184
OS 0.02450084 38.88153768
OS 0.01895348 38.89355696
OS 0.01525524 38.90465168
OS 0.00878332 38.92591656
OS 0.0069342 38.93608672
OS 0.00508508 38.94533232
OS 0.00416052 38.95365336
OS 0.00323596 38.96012528
OS 0.0023114 38.9665972
OS 0.0023114 38.97029544
OS 0.0023114 38.97306912
OS 0.0023114 38.97399368
OS 0.00323596 38.99156032
OS 0.00508508 39.0082024
OS 0.00878332 39.02299536
OS 0.011557 39.0359392
OS 0.01525524 39.04703392
OS 0.01895348 39.05535496
OS 0.0208026 39.05997776
OS 0.02172716 39.06182688
OS 0.02912364 39.07569528
OS 0.03836924 39.08771456
OS 0.04669028 39.09880928
OS 0.05501132 39.10713032
OS 0.0624078 39.11360224
OS 0.06795516 39.1191496
OS 0.0716534 39.12192328
OS 0.07350252 39.12284784
OS 0.0855218 39.13024432
OS 0.0993902 39.13671624
OS 0.11233404 39.1422636
OS 0.12435332 39.1468864
OS 0.13544804 39.14966008
OS 0.14376908 39.1515092
OS 0.150241 39.15335832
OS 0.15209012 39.15335832
OS 0.16595852 39.15520744
OS 0.18167604 39.15705656
OS 0.19831812 39.15798112
OS 0.21403564 39.15890568
OE
OB -0.40357044 38.74562736 I
OS -0.40357044 39.15983024
OS -0.3397758 39.15983024
OS -0.04669028 38.74562736
OS -0.04669028 38.67351168
OS -0.32498284 38.67351168
OS -0.32498284 38.52003472
OS -0.40357044 38.52003472
OS -0.40357044 38.67351168
OS -0.49047908 38.67351168
OS -0.49047908 38.74562736
OS -0.40357044 38.74562736
OE
OB -0.32498284 39.03224096 H
OS -0.32498284 38.74562736
OS -0.12342876 38.74562736
OS -0.32498284 39.03224096
OE
OB 0.22235668 39.08401632 H
OS 0.2057146 39.08309176
OS 0.1918462 39.0821672
OS 0.18075148 39.08124264
OS 0.173355 39.07939352
OS 0.16780764 39.07846896
OS 0.1641094 39.0775444
OS 0.16318484 39.0775444
OS 0.15116556 39.0729216
OS 0.1409954 39.06737424
OS 0.1317498 39.06182688
OS 0.12342876 39.05535496
OS 0.1178814 39.04888304
OS 0.1132586 39.04426024
OS 0.11048492 39.040562
OS 0.10956036 39.03963744
OS 0.10308844 39.02854272
OS 0.09754108 39.017448
OS 0.09384284 39.00542872
OS 0.09199372 38.99525856
OS 0.0901446 38.98601296
OS 0.08922004 38.97769192
OS 0.08922004 38.97306912
OS 0.08922004 38.97214456
OS 0.08922004 38.97122
OS 0.09106916 38.95180424
OS 0.0947674 38.93516216
OS 0.10031476 38.9203692
OS 0.10678668 38.90834992
OS 0.1132586 38.89910432
OS 0.11880596 38.89170784
OS 0.1225042 38.8880096
OS 0.12435332 38.88616048
OS 0.13082524 38.88061312
OS 0.13914628 38.87599032
OS 0.15671292 38.86859384
OS 0.17612868 38.86304648
OS 0.19554444 38.85934824
OS 0.21311108 38.85749912
OS 0.22050756 38.85657456
OS 0.22697948 38.85657456
OS 0.2334514 38.85565
OS 0.40541956 38.85565
OS 0.40541956 39.08401632
OS 0.22235668 39.08401632
OE
SE
S P 0
OB 0.21773388 2.33952034 I
OS 0.23160228 2.3404449
OS 0.49417732 2.3404449
OS 0.49417732 1.70064938
OS 0.4091178 1.70064938
OS 0.4091178 1.96045074
OS 0.24547068 1.96045074
OS 0.22143212 1.9613753
OS 0.19831812 1.96322442
OS 0.1779778 1.9659981
OS 0.1594866 1.96969634
OS 0.14191996 1.97339458
OS 0.127127 1.97801738
OS 0.1132586 1.98356474
OS 0.10123932 1.9891121
OS 0.09106916 1.9937349
OS 0.08182356 1.99928226
OS 0.07442708 2.00390506
OS 0.06887972 2.00852786
OS 0.06425692 2.01130154
OS 0.06148324 2.01407522
OS 0.05963412 2.01592434
OS 0.05870956 2.0168489
OS 0.04946396 2.02794362
OS 0.04114292 2.03903834
OS 0.034671 2.05013306
OS 0.02819908 2.06215234
OS 0.02265172 2.07417162
OS 0.01895348 2.08526634
OS 0.01248156 2.10653122
OS 0.01063244 2.11670138
OS 0.00878332 2.12594698
OS 0.00785876 2.13426802
OS 0.0069342 2.14073994
OS 0.00600964 2.14721186
OS 0.00600964 2.1509101
OS 0.00600964 2.15368378
OS 0.00600964 2.15460834
OS 0.0069342 2.17217498
OS 0.00878332 2.18881706
OS 0.01248156 2.20361002
OS 0.01525524 2.21655386
OS 0.01895348 2.22764858
OS 0.02265172 2.23596962
OS 0.02450084 2.24059242
OS 0.0254254 2.24244154
OS 0.03282188 2.25630994
OS 0.04206748 2.26832922
OS 0.05038852 2.27942394
OS 0.05870956 2.28774498
OS 0.06610604 2.2942169
OS 0.0716534 2.29976426
OS 0.07535164 2.30253794
OS 0.07720076 2.3034625
OS 0.08922004 2.31085898
OS 0.10308844 2.3173309
OS 0.11603228 2.32287826
OS 0.12805156 2.32750106
OS 0.13914628 2.33027474
OS 0.14746732 2.33212386
OS 0.15393924 2.33397298
OS 0.15578836 2.33397298
OS 0.16965676 2.3358221
OS 0.18537428 2.33767122
OS 0.20201636 2.33859578
OS 0.21773388 2.33952034
OE
OB -0.46366684 2.2572345 I
OS -0.46366684 2.33212386
OS -0.1456182 2.33212386
OS -0.08367268 2.0029805
OS -0.15763748 1.99281034
OS -0.1641094 2.0029805
OS -0.17243044 2.01130154
OS -0.17982692 2.01962258
OS -0.1872234 2.0260945
OS -0.19461988 2.0307173
OS -0.20016724 2.0353401
OS -0.20386548 2.03718922
OS -0.20479004 2.03811378
OS -0.21680932 2.04366114
OS -0.2288286 2.04828394
OS -0.23992332 2.05105762
OS -0.25101804 2.0538313
OS -0.26026364 2.05475586
OS -0.26766012 2.05568042
OS -0.28522676 2.05568042
OS -0.29632148 2.0538313
OS -0.31573724 2.0492085
OS -0.33237932 2.04273658
OS -0.34717228 2.03626466
OS -0.358267 2.02886818
OS -0.36658804 2.02239626
OS -0.37121084 2.01777346
OS -0.37305996 2.0168489
OS -0.37305996 2.01592434
OS -0.3860038 2.00020682
OS -0.3952494 1.98356474
OS -0.40172132 1.9659981
OS -0.40634412 1.94843146
OS -0.4091178 1.9336385
OS -0.41004236 1.92716658
OS -0.41004236 1.92161922
OS -0.41096692 1.91699642
OS -0.41096692 1.91329818
OS -0.41096692 1.91144906
OS -0.41096692 1.9105245
OS -0.41096692 1.89758066
OS -0.4091178 1.88556138
OS -0.404495 1.86244738
OS -0.39802308 1.84303162
OS -0.39155116 1.8273141
OS -0.38415468 1.81437026
OS -0.37768276 1.8042001
OS -0.37490908 1.80142642
OS -0.37305996 1.79865274
OS -0.3721354 1.79772818
OS -0.37121084 1.79680362
OS -0.36381436 1.78940714
OS -0.35641788 1.78293522
OS -0.3397758 1.7718405
OS -0.32405828 1.76444402
OS -0.30834076 1.75982122
OS -0.29539692 1.75612298
OS -0.2843022 1.75519842
OS -0.28060396 1.75427386
OS -0.2750566 1.75427386
OS -0.25748996 1.75519842
OS -0.24177244 1.75889666
OS -0.22790404 1.76351946
OS -0.21680932 1.76906682
OS -0.20663916 1.77461418
OS -0.19924268 1.77923698
OS -0.19554444 1.78293522
OS -0.19369532 1.78385978
OS -0.1826006 1.79680362
OS -0.173355 1.81067202
OS -0.16595852 1.82638954
OS -0.16041116 1.84025794
OS -0.15671292 1.85412634
OS -0.15393924 1.8642965
OS -0.15301468 1.8689193
OS -0.15209012 1.87169298
OS -0.15209012 1.8735421
OS -0.15209012 1.87446666
OS -0.06980428 1.86799474
OS -0.0716534 1.85320178
OS -0.07442708 1.83933338
OS -0.08274812 1.8134457
OS -0.09291828 1.79125626
OS -0.09846564 1.7810861
OS -0.104013 1.77276506
OS -0.1086358 1.76444402
OS -0.11418316 1.75704754
OS -0.11880596 1.75150018
OS -0.12342876 1.74687738
OS -0.127127 1.74317914
OS -0.12897612 1.7394809
OS -0.13082524 1.73855634
OS -0.1317498 1.73763178
OS -0.14284452 1.72931074
OS -0.15393924 1.72191426
OS -0.16595852 1.71544234
OS -0.1779778 1.70989498
OS -0.2010918 1.70157394
OS -0.2242058 1.69602658
OS -0.23437596 1.6932529
OS -0.24454612 1.69232834
OS -0.25286716 1.69140378
OS -0.26026364 1.69047922
OS -0.26673556 1.68955466
OS -0.2750566 1.68955466
OS -0.29447236 1.69047922
OS -0.31296356 1.6932529
OS -0.3305302 1.69695114
OS -0.34624772 1.70157394
OS -0.36104068 1.70804586
OS -0.37490908 1.71451778
OS -0.38785292 1.7209897
OS -0.39894764 1.72838618
OS -0.4091178 1.73578266
OS -0.4183634 1.74225458
OS -0.42575988 1.74965106
OS -0.4322318 1.75519842
OS -0.4368546 1.75982122
OS -0.44055284 1.76351946
OS -0.44240196 1.76629314
OS -0.44332652 1.7672177
OS -0.45257212 1.77923698
OS -0.4599686 1.79218082
OS -0.46736508 1.8042001
OS -0.47291244 1.81714394
OS -0.48215804 1.84210706
OS -0.4877054 1.86614562
OS -0.48955452 1.87631578
OS -0.49140364 1.88648594
OS -0.4923282 1.89480698
OS -0.49325276 1.90220346
OS -0.49417732 1.90867538
OS -0.49417732 1.91329818
OS -0.49417732 1.91607186
OS -0.49417732 1.91699642
OS -0.49325276 1.9336385
OS -0.49140364 1.94935602
OS -0.48862996 1.96507354
OS -0.48493172 1.97894194
OS -0.48030892 1.99188578
OS -0.47568612 2.00482962
OS -0.47013876 2.01592434
OS -0.46551596 2.0260945
OS -0.4599686 2.0353401
OS -0.45442124 2.04366114
OS -0.44979844 2.05013306
OS -0.44517564 2.05660498
OS -0.4414774 2.06122778
OS -0.43870372 2.06400146
OS -0.4368546 2.06585058
OS -0.43593004 2.06677514
OS -0.42483532 2.0769453
OS -0.4137406 2.0861909
OS -0.40172132 2.09358738
OS -0.38970204 2.1000593
OS -0.37768276 2.10653122
OS -0.36566348 2.11115402
OS -0.34347404 2.11762594
OS -0.33330388 2.12039962
OS -0.32405828 2.12224874
OS -0.31573724 2.1231733
OS -0.30834076 2.12409786
OS -0.3027934 2.12502242
OS -0.28245308 2.12502242
OS -0.27135836 2.1231733
OS -0.24916892 2.1185505
OS -0.2288286 2.11207858
OS -0.2103374 2.1046821
OS -0.19554444 2.09728562
OS -0.18907252 2.09358738
OS -0.18352516 2.0908137
OS -0.17890236 2.08804002
OS -0.17612868 2.0861909
OS -0.17427956 2.08526634
OS -0.173355 2.08434178
OS -0.20756372 2.2572345
OS -0.46366684 2.2572345
OE
OB 0.22605492 2.26463098 H
OS 0.20941284 2.26370642
OS 0.19554444 2.26278186
OS 0.18444972 2.2618573
OS 0.17705324 2.26000818
OS 0.17150588 2.25908362
OS 0.16780764 2.25815906
OS 0.16688308 2.25815906
OS 0.1548638 2.25353626
OS 0.14469364 2.2479889
OS 0.13544804 2.24244154
OS 0.127127 2.23596962
OS 0.12157964 2.2294977
OS 0.11695684 2.2248749
OS 0.11418316 2.22117666
OS 0.1132586 2.2202521
OS 0.10678668 2.20915738
OS 0.10123932 2.19806266
OS 0.09754108 2.18604338
OS 0.09569196 2.17587322
OS 0.09384284 2.16662762
OS 0.09291828 2.15830658
OS 0.09291828 2.15368378
OS 0.09291828 2.15275922
OS 0.09291828 2.15183466
OS 0.0947674 2.1324189
OS 0.09846564 2.11577682
OS 0.104013 2.10098386
OS 0.11048492 2.08896458
OS 0.11695684 2.07971898
OS 0.1225042 2.0723225
OS 0.12620244 2.06862426
OS 0.12805156 2.06677514
OS 0.13452348 2.06122778
OS 0.14284452 2.05660498
OS 0.16041116 2.0492085
OS 0.17982692 2.04366114
OS 0.19924268 2.0399629
OS 0.21680932 2.03811378
OS 0.2242058 2.03718922
OS 0.23067772 2.03718922
OS 0.23714964 2.03626466
OS 0.4091178 2.03626466
OS 0.4091178 2.26463098
OS 0.22605492 2.26463098
OE
SE
S P 0
OB 2.29342188 45.22313282 I
OS 2.30729028 45.22405738
OS 2.56986532 45.22405738
OS 2.56986532 44.58426186
OS 2.4848058 44.58426186
OS 2.4848058 44.84406322
OS 2.32115868 44.84406322
OS 2.29712012 44.84498778
OS 2.27400612 44.8468369
OS 2.2536658 44.84961058
OS 2.2351746 44.85330882
OS 2.21760796 44.85700706
OS 2.202815 44.86162986
OS 2.1889466 44.86717722
OS 2.17692732 44.87272458
OS 2.16675716 44.87734738
OS 2.15751156 44.88289474
OS 2.15011508 44.88751754
OS 2.14456772 44.89214034
OS 2.13994492 44.89491402
OS 2.13717124 44.8976877
OS 2.13532212 44.89953682
OS 2.13439756 44.90046138
OS 2.12515196 44.9115561
OS 2.11683092 44.92265082
OS 2.110359 44.93374554
OS 2.10388708 44.94576482
OS 2.09833972 44.9577841
OS 2.09464148 44.96887882
OS 2.08816956 44.9901437
OS 2.08632044 45.00031386
OS 2.08447132 45.00955946
OS 2.08354676 45.0178805
OS 2.0826222 45.02435242
OS 2.08169764 45.03082434
OS 2.08169764 45.03452258
OS 2.08169764 45.03729626
OS 2.08169764 45.03822082
OS 2.0826222 45.05578746
OS 2.08447132 45.07242954
OS 2.08816956 45.0872225
OS 2.09094324 45.10016634
OS 2.09464148 45.11126106
OS 2.09833972 45.1195821
OS 2.10018884 45.1242049
OS 2.1011134 45.12605402
OS 2.10850988 45.13992242
OS 2.11775548 45.1519417
OS 2.12607652 45.16303642
OS 2.13439756 45.17135746
OS 2.14179404 45.17782938
OS 2.1473414 45.18337674
OS 2.15103964 45.18615042
OS 2.15288876 45.18707498
OS 2.16490804 45.19447146
OS 2.17877644 45.20094338
OS 2.19172028 45.20649074
OS 2.20373956 45.21111354
OS 2.21483428 45.21388722
OS 2.22315532 45.21573634
OS 2.22962724 45.21758546
OS 2.23147636 45.21758546
OS 2.24534476 45.21943458
OS 2.26106228 45.2212837
OS 2.27770436 45.22220826
OS 2.29342188 45.22313282
OE
OB 1.76642268 45.2259065 I
OS 1.77197004 45.22683106
OS 1.77936652 45.22683106
OS 1.79785772 45.2259065
OS 1.81542436 45.22405738
OS 1.83206644 45.22035914
OS 1.84778396 45.21573634
OS 1.86165236 45.20926442
OS 1.87552076 45.20371706
OS 1.88754004 45.19632058
OS 1.89863476 45.18984866
OS 1.90788036 45.18337674
OS 1.91712596 45.17598026
OS 1.92452244 45.1704329
OS 1.9300698 45.16488554
OS 1.9346926 45.15933818
OS 1.93839084 45.15563994
OS 1.94023996 45.15379082
OS 1.94116452 45.15286626
OS 1.9531838 45.13622418
OS 1.96335396 45.11680842
OS 1.97259956 45.0964681
OS 1.9809206 45.07520322
OS 1.98739252 45.05301378
OS 1.99293988 45.03082434
OS 1.99756268 45.00771034
OS 2.00126092 44.98644546
OS 2.0040346 44.96518058
OS 2.00588372 44.94576482
OS 2.00773284 44.92819818
OS 2.0086574 44.91340522
OS 2.0086574 44.90046138
OS 2.00958196 44.89121578
OS 2.00958196 44.88751754
OS 2.00958196 44.88474386
OS 2.00958196 44.8838193
OS 2.00958196 44.88289474
OS 2.0086574 44.85330882
OS 2.00680828 44.82557202
OS 2.0040346 44.79968434
OS 1.9994118 44.77564578
OS 1.994789 44.7543809
OS 1.9901662 44.73496514
OS 1.98461884 44.7173985
OS 1.97814692 44.70168098
OS 1.97259956 44.68873714
OS 1.9670522 44.67671786
OS 1.9624294 44.66747226
OS 1.95688204 44.65915122
OS 1.9531838 44.6526793
OS 1.95041012 44.64898106
OS 1.948561 44.64620738
OS 1.94763644 44.64528282
OS 1.93561716 44.63233898
OS 1.92267332 44.62124426
OS 1.90972948 44.61199866
OS 1.89678564 44.60367762
OS 1.88291724 44.59628114
OS 1.8699734 44.59073378
OS 1.85702956 44.58611098
OS 1.84408572 44.58241274
OS 1.832991 44.57963906
OS 1.82189628 44.57686538
OS 1.81265068 44.57501626
OS 1.80432964 44.5740917
OS 1.79693316 44.5740917
OS 1.79231036 44.57316714
OS 1.78768756 44.57316714
OS 1.76642268 44.5740917
OS 1.74700692 44.57778994
OS 1.72944028 44.58148818
OS 1.71372276 44.58703554
OS 1.70170348 44.59165834
OS 1.69245788 44.59628114
OS 1.68875964 44.5972057
OS 1.68598596 44.59905482
OS 1.6850614 44.59997938
OS 1.68413684 44.59997938
OS 1.66841932 44.6110741
OS 1.65362636 44.62401794
OS 1.64160708 44.63696178
OS 1.63143692 44.64990562
OS 1.62311588 44.6619249
OS 1.61756852 44.6711705
OS 1.6157194 44.67486874
OS 1.61387028 44.67764242
OS 1.61294572 44.67856698
OS 1.61294572 44.67949154
OS 1.60370012 44.6989073
OS 1.5972282 44.71924762
OS 1.5926054 44.73773882
OS 1.58983172 44.75530546
OS 1.58705804 44.77009842
OS 1.58705804 44.77564578
OS 1.58613348 44.78119314
OS 1.58613348 44.78581594
OS 1.58613348 44.78858962
OS 1.58613348 44.79043874
OS 1.58613348 44.7913633
OS 1.58705804 44.80800538
OS 1.58890716 44.8237229
OS 1.59168084 44.83944042
OS 1.59445452 44.85330882
OS 1.59907732 44.86625266
OS 1.60370012 44.8791965
OS 1.60832292 44.89029122
OS 1.61387028 44.90046138
OS 1.61941764 44.90970698
OS 1.62404044 44.91802802
OS 1.62866324 44.92449994
OS 1.63328604 44.93097186
OS 1.63605972 44.93559466
OS 1.6388334 44.93836834
OS 1.64068252 44.94021746
OS 1.64160708 44.94114202
OS 1.65177724 44.95131218
OS 1.66287196 44.96055778
OS 1.67489124 44.96795426
OS 1.68598596 44.97442618
OS 1.69708068 44.9808981
OS 1.7081754 44.9855209
OS 1.72944028 44.99199282
OS 1.73868588 44.9947665
OS 1.74793148 44.99661562
OS 1.75532796 44.99754018
OS 1.76272444 44.99846474
OS 1.7682718 44.9993893
OS 1.77566828 44.9993893
OS 1.79231036 44.99846474
OS 1.80802788 44.99569106
OS 1.82282084 44.99291738
OS 1.83576468 44.98921914
OS 1.8468594 44.98459634
OS 1.85518044 44.98182266
OS 1.8607278 44.97904898
OS 1.86165236 44.97812442
OS 1.86257692 44.97812442
OS 1.87736988 44.96887882
OS 1.89031372 44.95870866
OS 1.902333 44.9485385
OS 1.9115786 44.93744378
OS 1.91989964 44.92819818
OS 1.92637156 44.9208017
OS 1.9300698 44.91525434
OS 1.93099436 44.91432978
OS 1.93099436 44.93097186
OS 1.9300698 44.94761394
OS 1.92914524 44.9624069
OS 1.92729612 44.97719986
OS 1.92637156 44.9901437
OS 1.92452244 45.00216298
OS 1.92267332 45.0132577
OS 1.91989964 45.02342786
OS 1.91805052 45.03267346
OS 1.9162014 45.04006994
OS 1.91435228 45.04654186
OS 1.91342772 45.05208922
OS 1.9115786 45.05578746
OS 1.91065404 45.05856114
OS 1.90972948 45.06041026
OS 1.90972948 45.06133482
OS 1.90048388 45.07982602
OS 1.89123828 45.0964681
OS 1.88106812 45.10941194
OS 1.87182252 45.12050666
OS 1.86350148 45.12975226
OS 1.85702956 45.13622418
OS 1.85240676 45.13992242
OS 1.85055764 45.14084698
OS 1.83946292 45.14824346
OS 1.8283682 45.15286626
OS 1.81727348 45.1565645
OS 1.80617876 45.15933818
OS 1.79785772 45.1611873
OS 1.79046124 45.16211186
OS 1.78398932 45.16211186
OS 1.76734724 45.16026274
OS 1.75162972 45.1565645
OS 1.73868588 45.15101714
OS 1.7266666 45.14546978
OS 1.717421 45.13899786
OS 1.71094908 45.1334505
OS 1.70725084 45.12975226
OS 1.70540172 45.12790314
OS 1.6989298 45.1195821
OS 1.69245788 45.10941194
OS 1.68691052 45.09831722
OS 1.68321228 45.0872225
OS 1.67951404 45.07705234
OS 1.67674036 45.0687313
OS 1.6758158 45.06318394
OS 1.67489124 45.06225938
OS 1.67489124 45.06133482
OS 1.59630364 45.06780674
OS 1.601851 45.09369442
OS 1.61017204 45.11680842
OS 1.61941764 45.13714874
OS 1.6295878 45.15379082
OS 1.63975796 45.16673466
OS 1.6434562 45.17228202
OS 1.648079 45.17690482
OS 1.65085268 45.1796785
OS 1.65362636 45.18245218
OS 1.65455092 45.18337674
OS 1.65547548 45.1843013
OS 1.66472108 45.19169778
OS 1.67489124 45.1981697
OS 1.69523156 45.20926442
OS 1.71557188 45.2166609
OS 1.73498764 45.2212837
OS 1.75255428 45.22498194
OS 1.75995076 45.2259065
OS 1.76642268 45.2259065
OE
OB 2.30174292 45.14824346 H
OS 2.28510084 45.1473189
OS 2.27123244 45.14639434
OS 2.26013772 45.14546978
OS 2.25274124 45.14362066
OS 2.24719388 45.1426961
OS 2.24349564 45.14177154
OS 2.24257108 45.14177154
OS 2.2305518 45.13714874
OS 2.22038164 45.13160138
OS 2.21113604 45.12605402
OS 2.202815 45.1195821
OS 2.19726764 45.11311018
OS 2.19264484 45.10848738
OS 2.18987116 45.10478914
OS 2.1889466 45.10386458
OS 2.18247468 45.09276986
OS 2.17692732 45.08167514
OS 2.17322908 45.06965586
OS 2.17137996 45.0594857
OS 2.16953084 45.0502401
OS 2.16860628 45.04191906
OS 2.16860628 45.03729626
OS 2.16860628 45.0363717
OS 2.16860628 45.03544714
OS 2.1704554 45.01603138
OS 2.17415364 44.9993893
OS 2.179701 44.98459634
OS 2.18617292 44.97257706
OS 2.19264484 44.96333146
OS 2.1981922 44.95593498
OS 2.20189044 44.95223674
OS 2.20373956 44.95038762
OS 2.21021148 44.94484026
OS 2.21853252 44.94021746
OS 2.23609916 44.93282098
OS 2.25551492 44.92727362
OS 2.27493068 44.92357538
OS 2.29249732 44.92172626
OS 2.2998938 44.9208017
OS 2.30636572 44.9208017
OS 2.31283764 44.91987714
OS 2.4848058 44.91987714
OS 2.4848058 45.14824346
OS 2.30174292 45.14824346
OE
OB 1.7913858 44.9300473 H
OS 1.77197004 44.92819818
OS 1.7544034 44.92357538
OS 1.73961044 44.91802802
OS 1.7266666 44.91063154
OS 1.71649644 44.90323506
OS 1.70909996 44.8976877
OS 1.70447716 44.8930649
OS 1.70262804 44.89121578
OS 1.69060876 44.87549826
OS 1.68136316 44.85885618
OS 1.67489124 44.84128954
OS 1.671193 44.82464746
OS 1.66841932 44.8098545
OS 1.66749476 44.80338258
OS 1.66749476 44.79783522
OS 1.6665702 44.79321242
OS 1.6665702 44.78951418
OS 1.6665702 44.78766506
OS 1.6665702 44.7867405
OS 1.66841932 44.76177738
OS 1.67211756 44.7405125
OS 1.67766492 44.7220213
OS 1.68413684 44.70630378
OS 1.69153332 44.6942845
OS 1.69708068 44.6850389
OS 1.70077892 44.67949154
OS 1.70262804 44.67856698
OS 1.70262804 44.67764242
OS 1.70909996 44.67024594
OS 1.71649644 44.66469858
OS 1.7312894 44.65452842
OS 1.74608236 44.6480565
OS 1.7590262 44.64250914
OS 1.77104548 44.63973546
OS 1.78029108 44.6388109
OS 1.78398932 44.63788634
OS 1.78861212 44.63788634
OS 1.80155596 44.6388109
OS 1.81357524 44.64066002
OS 1.82466996 44.64435826
OS 1.83391556 44.6480565
OS 1.8422366 44.65083018
OS 1.84870852 44.65452842
OS 1.85240676 44.65637754
OS 1.85425588 44.6573021
OS 1.8653506 44.66562314
OS 1.8745962 44.67394418
OS 1.88291724 44.68411434
OS 1.88938916 44.69243538
OS 1.89493652 44.70075642
OS 1.89863476 44.70722834
OS 1.90140844 44.71185114
OS 1.902333 44.71370026
OS 1.90788036 44.72756866
OS 1.9115786 44.74143706
OS 1.91527684 44.7543809
OS 1.91712596 44.76640018
OS 1.91805052 44.77657034
OS 1.91897508 44.78489138
OS 1.91897508 44.78951418
OS 1.91897508 44.7913633
OS 1.91712596 44.81355274
OS 1.91342772 44.8329685
OS 1.9069558 44.85053514
OS 1.90048388 44.86440354
OS 1.89401196 44.87642282
OS 1.88754004 44.88474386
OS 1.8838418 44.88936666
OS 1.88199268 44.89121578
OS 1.86719972 44.90415962
OS 1.85240676 44.91340522
OS 1.83668924 44.9208017
OS 1.82282084 44.9254245
OS 1.809877 44.92819818
OS 1.8006314 44.92912274
OS 1.79693316 44.9300473
OS 1.7913858 44.9300473
OE
SE
S P 0
OB 4.37809386 34.61266636 I
OS 4.37809386 35.04905868
OS 4.46315338 35.04905868
OS 4.46315338 34.60804356
OS 4.46315338 34.5886278
OS 4.4650025 34.57198572
OS 4.46592706 34.55811732
OS 4.46777618 34.5470226
OS 4.4696253 34.53870156
OS 4.47054986 34.53222964
OS 4.47239898 34.5285314
OS 4.47239898 34.52760684
OS 4.47609722 34.51836124
OS 4.48072002 34.51096476
OS 4.48626738 34.50449284
OS 4.49089018 34.49802092
OS 4.49643754 34.49432268
OS 4.50013578 34.49062444
OS 4.50290946 34.48877532
OS 4.50383402 34.48785076
OS 4.51307962 34.48322796
OS 4.52232522 34.47952972
OS 4.53157082 34.4776806
OS 4.53989186 34.47583148
OS 4.5482129 34.47490692
OS 4.55376026 34.47398236
OS 4.55930762 34.47398236
OS 4.57410058 34.47490692
OS 4.58796898 34.47860516
OS 4.5990637 34.4823034
OS 4.60923386 34.48785076
OS 4.61663034 34.49247356
OS 4.6221777 34.49709636
OS 4.62587594 34.49987004
OS 4.6268005 34.5007946
OS 4.6314233 34.50634196
OS 4.63512154 34.51281388
OS 4.6406689 34.52760684
OS 4.64621626 34.54424892
OS 4.64898994 34.560891
OS 4.65176362 34.57660852
OS 4.65176362 34.58308044
OS 4.65268818 34.5886278
OS 4.65361274 34.59417516
OS 4.65361274 34.5978734
OS 4.65361274 34.59972252
OS 4.65361274 34.60064708
OS 4.73035122 34.58955236
OS 4.73035122 34.57198572
OS 4.72942666 34.5562682
OS 4.72665298 34.54055068
OS 4.72480386 34.52668228
OS 4.72110562 34.51373844
OS 4.71740738 34.50264372
OS 4.71370914 34.491549
OS 4.7100109 34.4823034
OS 4.7053881 34.47398236
OS 4.70168986 34.46658588
OS 4.69799162 34.46011396
OS 4.69429338 34.45549116
OS 4.6915197 34.45179292
OS 4.68967058 34.44809468
OS 4.68874602 34.44717012
OS 4.68782146 34.44624556
OS 4.67857586 34.43792452
OS 4.66933026 34.43052804
OS 4.6591601 34.42405612
OS 4.64806538 34.41850876
OS 4.6268005 34.41018772
OS 4.60646018 34.40464036
OS 4.58704442 34.40094212
OS 4.57964794 34.40001756
OS 4.57225146 34.399093
OS 4.5667041 34.39816844
OS 4.55838306 34.39816844
OS 4.53804274 34.399093
OS 4.51955154 34.40186668
OS 4.50290946 34.40556492
OS 4.4881165 34.41018772
OS 4.47609722 34.41388596
OS 4.46777618 34.4175842
OS 4.46222882 34.42035788
OS 4.4603797 34.42128244
OS 4.44558674 34.43052804
OS 4.4326429 34.44162276
OS 4.42247274 34.45271748
OS 4.41322714 34.46288764
OS 4.40675522 34.4730578
OS 4.40213242 34.48045428
OS 4.39935874 34.48600164
OS 4.39843418 34.4869262
OS 4.39843418 34.48785076
OS 4.39196226 34.50634196
OS 4.3864149 34.52575772
OS 4.38271666 34.5470226
OS 4.38086754 34.56736292
OS 4.37901842 34.58492956
OS 4.37901842 34.59232604
OS 4.37809386 34.59972252
OS 4.37809386 34.60526988
OS 4.37809386 34.60896812
OS 4.37809386 34.6117418
OS 4.37809386 34.61266636
OE
OB 4.03230842 35.0509078 I
OS 4.03785578 35.05183236
OS 4.04525226 35.05183236
OS 4.06374346 35.0509078
OS 4.0813101 35.04905868
OS 4.09795218 35.04536044
OS 4.1136697 35.04073764
OS 4.1275381 35.03426572
OS 4.1414065 35.02871836
OS 4.15342578 35.02132188
OS 4.1645205 35.01484996
OS 4.1737661 35.00837804
OS 4.1830117 35.00098156
OS 4.19040818 34.9954342
OS 4.19595554 34.98988684
OS 4.20057834 34.98433948
OS 4.20427658 34.98064124
OS 4.2061257 34.97879212
OS 4.20705026 34.97786756
OS 4.21906954 34.96122548
OS 4.2292397 34.94180972
OS 4.2384853 34.9214694
OS 4.24680634 34.90020452
OS 4.25327826 34.87801508
OS 4.25882562 34.85582564
OS 4.26344842 34.83271164
OS 4.26714666 34.81144676
OS 4.26992034 34.79018188
OS 4.27176946 34.77076612
OS 4.27361858 34.75319948
OS 4.27454314 34.73840652
OS 4.27454314 34.72546268
OS 4.2754677 34.71621708
OS 4.2754677 34.71251884
OS 4.2754677 34.70974516
OS 4.2754677 34.7088206
OS 4.2754677 34.70789604
OS 4.27454314 34.67831012
OS 4.27269402 34.65057332
OS 4.26992034 34.62468564
OS 4.26529754 34.60064708
OS 4.26067474 34.5793822
OS 4.25605194 34.55996644
OS 4.25050458 34.5423998
OS 4.24403266 34.52668228
OS 4.2384853 34.51373844
OS 4.23293794 34.50171916
OS 4.22831514 34.49247356
OS 4.22276778 34.48415252
OS 4.21906954 34.4776806
OS 4.21629586 34.47398236
OS 4.21444674 34.47120868
OS 4.21352218 34.47028412
OS 4.2015029 34.45734028
OS 4.18855906 34.44624556
OS 4.17561522 34.43699996
OS 4.16267138 34.42867892
OS 4.14880298 34.42128244
OS 4.13585914 34.41573508
OS 4.1229153 34.41111228
OS 4.10997146 34.40741404
OS 4.09887674 34.40464036
OS 4.08778202 34.40186668
OS 4.07853642 34.40001756
OS 4.07021538 34.399093
OS 4.0628189 34.399093
OS 4.0581961 34.39816844
OS 4.0535733 34.39816844
OS 4.03230842 34.399093
OS 4.01289266 34.40279124
OS 3.99532602 34.40648948
OS 3.9796085 34.41203684
OS 3.96758922 34.41665964
OS 3.95834362 34.42128244
OS 3.95464538 34.422207
OS 3.9518717 34.42405612
OS 3.95094714 34.42498068
OS 3.95002258 34.42498068
OS 3.93430506 34.4360754
OS 3.9195121 34.44901924
OS 3.90749282 34.46196308
OS 3.89732266 34.47490692
OS 3.88900162 34.4869262
OS 3.88345426 34.4961718
OS 3.88160514 34.49987004
OS 3.87975602 34.50264372
OS 3.87883146 34.50356828
OS 3.87883146 34.50449284
OS 3.86958586 34.5239086
OS 3.86311394 34.54424892
OS 3.85849114 34.56274012
OS 3.85571746 34.58030676
OS 3.85294378 34.59509972
OS 3.85294378 34.60064708
OS 3.85201922 34.60619444
OS 3.85201922 34.61081724
OS 3.85201922 34.61359092
OS 3.85201922 34.61544004
OS 3.85201922 34.6163646
OS 3.85294378 34.63300668
OS 3.8547929 34.6487242
OS 3.85756658 34.66444172
OS 3.86034026 34.67831012
OS 3.86496306 34.69125396
OS 3.86958586 34.7041978
OS 3.87420866 34.71529252
OS 3.87975602 34.72546268
OS 3.88530338 34.73470828
OS 3.88992618 34.74302932
OS 3.89454898 34.74950124
OS 3.89917178 34.75597316
OS 3.90194546 34.76059596
OS 3.90471914 34.76336964
OS 3.90656826 34.76521876
OS 3.90749282 34.76614332
OS 3.91766298 34.77631348
OS 3.9287577 34.78555908
OS 3.94077698 34.79295556
OS 3.9518717 34.79942748
OS 3.96296642 34.8058994
OS 3.97406114 34.8105222
OS 3.99532602 34.81699412
OS 4.00457162 34.8197678
OS 4.01381722 34.82161692
OS 4.0212137 34.82254148
OS 4.02861018 34.82346604
OS 4.03415754 34.8243906
OS 4.04155402 34.8243906
OS 4.0581961 34.82346604
OS 4.07391362 34.82069236
OS 4.08870658 34.81791868
OS 4.10165042 34.81422044
OS 4.11274514 34.80959764
OS 4.12106618 34.80682396
OS 4.12661354 34.80405028
OS 4.1275381 34.80312572
OS 4.12846266 34.80312572
OS 4.14325562 34.79388012
OS 4.15619946 34.78370996
OS 4.16821874 34.7735398
OS 4.17746434 34.76244508
OS 4.18578538 34.75319948
OS 4.1922573 34.745803
OS 4.19595554 34.74025564
OS 4.1968801 34.73933108
OS 4.1968801 34.75597316
OS 4.19595554 34.77261524
OS 4.19503098 34.7874082
OS 4.19318186 34.80220116
OS 4.1922573 34.815145
OS 4.19040818 34.82716428
OS 4.18855906 34.838259
OS 4.18578538 34.84842916
OS 4.18393626 34.85767476
OS 4.18208714 34.86507124
OS 4.18023802 34.87154316
OS 4.17931346 34.87709052
OS 4.17746434 34.88078876
OS 4.17653978 34.88356244
OS 4.17561522 34.88541156
OS 4.17561522 34.88633612
OS 4.16636962 34.90482732
OS 4.15712402 34.9214694
OS 4.14695386 34.93441324
OS 4.13770826 34.94550796
OS 4.12938722 34.95475356
OS 4.1229153 34.96122548
OS 4.1182925 34.96492372
OS 4.11644338 34.96584828
OS 4.10534866 34.97324476
OS 4.09425394 34.97786756
OS 4.08315922 34.9815658
OS 4.0720645 34.98433948
OS 4.06374346 34.9861886
OS 4.05634698 34.98711316
OS 4.04987506 34.98711316
OS 4.03323298 34.98526404
OS 4.01751546 34.9815658
OS 4.00457162 34.97601844
OS 3.99255234 34.97047108
OS 3.98330674 34.96399916
OS 3.97683482 34.9584518
OS 3.97313658 34.95475356
OS 3.97128746 34.95290444
OS 3.96481554 34.9445834
OS 3.95834362 34.93441324
OS 3.95279626 34.92331852
OS 3.94909802 34.9122238
OS 3.94539978 34.90205364
OS 3.9426261 34.8937326
OS 3.94170154 34.88818524
OS 3.94077698 34.88726068
OS 3.94077698 34.88633612
OS 3.86218938 34.89280804
OS 3.86773674 34.91869572
OS 3.87605778 34.94180972
OS 3.88530338 34.96215004
OS 3.89547354 34.97879212
OS 3.9056437 34.99173596
OS 3.90934194 34.99728332
OS 3.91396474 35.00190612
OS 3.91673842 35.0046798
OS 3.9195121 35.00745348
OS 3.92043666 35.00837804
OS 3.92136122 35.0093026
OS 3.93060682 35.01669908
OS 3.94077698 35.023171
OS 3.9611173 35.03426572
OS 3.98145762 35.0416622
OS 4.00087338 35.046285
OS 4.01844002 35.04998324
OS 4.0258365 35.0509078
OS 4.03230842 35.0509078
OE
OB 4.05727154 34.7550486 H
OS 4.03785578 34.75319948
OS 4.02028914 34.74857668
OS 4.00549618 34.74302932
OS 3.99255234 34.73563284
OS 3.98238218 34.72823636
OS 3.9749857 34.722689
OS 3.9703629 34.7180662
OS 3.96851378 34.71621708
OS 3.9564945 34.70049956
OS 3.9472489 34.68385748
OS 3.94077698 34.66629084
OS 3.93707874 34.64964876
OS 3.93430506 34.6348558
OS 3.9333805 34.62838388
OS 3.9333805 34.62283652
OS 3.93245594 34.61821372
OS 3.93245594 34.61451548
OS 3.93245594 34.61266636
OS 3.93245594 34.6117418
OS 3.93430506 34.58677868
OS 3.9380033 34.5655138
OS 3.94355066 34.5470226
OS 3.95002258 34.53130508
OS 3.95741906 34.5192858
OS 3.96296642 34.5100402
OS 3.96666466 34.50449284
OS 3.96851378 34.50356828
OS 3.96851378 34.50264372
OS 3.9749857 34.49524724
OS 3.98238218 34.48969988
OS 3.99717514 34.47952972
OS 4.0119681 34.4730578
OS 4.02491194 34.46751044
OS 4.03693122 34.46473676
OS 4.04617682 34.4638122
OS 4.04987506 34.46288764
OS 4.05449786 34.46288764
OS 4.0674417 34.4638122
OS 4.07946098 34.46566132
OS 4.0905557 34.46935956
OS 4.0998013 34.4730578
OS 4.10812234 34.47583148
OS 4.11459426 34.47952972
OS 4.1182925 34.48137884
OS 4.12014162 34.4823034
OS 4.13123634 34.49062444
OS 4.14048194 34.49894548
OS 4.14880298 34.50911564
OS 4.1552749 34.51743668
OS 4.16082226 34.52575772
OS 4.1645205 34.53222964
OS 4.16729418 34.53685244
OS 4.16821874 34.53870156
OS 4.1737661 34.55256996
OS 4.17746434 34.56643836
OS 4.18116258 34.5793822
OS 4.1830117 34.59140148
OS 4.18393626 34.60157164
OS 4.18486082 34.60989268
OS 4.18486082 34.61451548
OS 4.18486082 34.6163646
OS 4.1830117 34.63855404
OS 4.17931346 34.6579698
OS 4.17284154 34.67553644
OS 4.16636962 34.68940484
OS 4.1598977 34.70142412
OS 4.15342578 34.70974516
OS 4.14972754 34.71436796
OS 4.14787842 34.71621708
OS 4.13308546 34.72916092
OS 4.1182925 34.73840652
OS 4.10257498 34.745803
OS 4.08870658 34.7504258
OS 4.07576274 34.75319948
OS 4.06651714 34.75412404
OS 4.0628189 34.7550486
OS 4.05727154 34.7550486
OE
SE
S P 0
OB 5.34142188 45.2189723 I
OS 5.35529028 45.21989686
OS 5.61786532 45.21989686
OS 5.61786532 44.58010134
OS 5.5328058 44.58010134
OS 5.5328058 44.8399027
OS 5.36915868 44.8399027
OS 5.34512012 44.84082726
OS 5.32200612 44.84267638
OS 5.3016658 44.84545006
OS 5.2831746 44.8491483
OS 5.26560796 44.85284654
OS 5.250815 44.85746934
OS 5.2369466 44.8630167
OS 5.22492732 44.86856406
OS 5.21475716 44.87318686
OS 5.20551156 44.87873422
OS 5.19811508 44.88335702
OS 5.19256772 44.88797982
OS 5.18794492 44.8907535
OS 5.18517124 44.89352718
OS 5.18332212 44.8953763
OS 5.18239756 44.89630086
OS 5.17315196 44.90739558
OS 5.16483092 44.9184903
OS 5.158359 44.92958502
OS 5.15188708 44.9416043
OS 5.14633972 44.95362358
OS 5.14264148 44.9647183
OS 5.13616956 44.98598318
OS 5.13432044 44.99615334
OS 5.13247132 45.00539894
OS 5.13154676 45.01371998
OS 5.1306222 45.0201919
OS 5.12969764 45.02666382
OS 5.12969764 45.03036206
OS 5.12969764 45.03313574
OS 5.12969764 45.0340603
OS 5.1306222 45.05162694
OS 5.13247132 45.06826902
OS 5.13616956 45.08306198
OS 5.13894324 45.09600582
OS 5.14264148 45.10710054
OS 5.14633972 45.11542158
OS 5.14818884 45.12004438
OS 5.1491134 45.1218935
OS 5.15650988 45.1357619
OS 5.16575548 45.14778118
OS 5.17407652 45.1588759
OS 5.18239756 45.16719694
OS 5.18979404 45.17366886
OS 5.1953414 45.17921622
OS 5.19903964 45.1819899
OS 5.20088876 45.18291446
OS 5.21290804 45.19031094
OS 5.22677644 45.19678286
OS 5.23972028 45.20233022
OS 5.25173956 45.20695302
OS 5.26283428 45.2097267
OS 5.27115532 45.21157582
OS 5.27762724 45.21342494
OS 5.27947636 45.21342494
OS 5.29334476 45.21527406
OS 5.30906228 45.21712318
OS 5.32570436 45.21804774
OS 5.34142188 45.2189723
OE
OB 4.63413348 45.1496303 I
OS 4.63413348 45.21157582
OS 5.04833636 45.21157582
OS 5.04833636 45.1357619
OS 4.73491052 45.1357619
OS 4.75709996 45.10894966
OS 4.77836484 45.0802883
OS 4.79685604 45.0525515
OS 4.81442268 45.02573926
OS 4.82181916 45.01371998
OS 4.82829108 45.00262526
OS 4.834763 44.9924551
OS 4.8393858 44.98413406
OS 4.84308404 44.97673758
OS 4.84585772 44.97211478
OS 4.84770684 44.96841654
OS 4.8486314 44.96749198
OS 4.8671226 44.93050958
OS 4.88376468 44.89352718
OS 4.89763308 44.8583939
OS 4.90318044 44.84267638
OS 4.9087278 44.82695886
OS 4.91427516 44.81309046
OS 4.9179734 44.80014662
OS 4.92167164 44.7890519
OS 4.92444532 44.7798063
OS 4.927219 44.77148526
OS 4.92906812 44.7659379
OS 4.92999268 44.76223966
OS 4.92999268 44.7613151
OS 4.93923828 44.72340814
OS 4.94293652 44.70491694
OS 4.9457102 44.68827486
OS 4.94848388 44.67255734
OS 4.95125756 44.65683982
OS 4.95310668 44.64389598
OS 4.9549558 44.63095214
OS 4.95588036 44.61985742
OS 4.95680492 44.60968726
OS 4.95772948 44.60044166
OS 4.95772948 44.59304518
OS 4.95865404 44.58749782
OS 4.95865404 44.58379958
OS 4.95865404 44.5810259
OS 4.95865404 44.58010134
OS 4.87821732 44.58010134
OS 4.87544364 44.61523462
OS 4.87082084 44.64759422
OS 4.86619804 44.67718014
OS 4.86342436 44.69104854
OS 4.86065068 44.70399238
OS 4.85880156 44.7150871
OS 4.85602788 44.72525726
OS 4.85417876 44.73450286
OS 4.85232964 44.74189934
OS 4.85048052 44.7474467
OS 4.84955596 44.7520695
OS 4.8486314 44.75484318
OS 4.8486314 44.75576774
OS 4.834763 44.7982975
OS 4.81997004 44.83805358
OS 4.81257356 44.85746934
OS 4.80517708 44.87596054
OS 4.79685604 44.89260262
OS 4.78945956 44.9092447
OS 4.78298764 44.92403766
OS 4.77651572 44.9369815
OS 4.77096836 44.94807622
OS 4.76634556 44.95824638
OS 4.76172276 44.96656742
OS 4.75894908 44.97211478
OS 4.75709996 44.97581302
OS 4.7561754 44.97673758
OS 4.74508068 44.99615334
OS 4.73398596 45.0155691
OS 4.72289124 45.03313574
OS 4.71179652 45.04977782
OS 4.70162636 45.06457078
OS 4.6914562 45.07936374
OS 4.68128604 45.09230758
OS 4.672965 45.1034023
OS 4.66464396 45.11449702
OS 4.65724748 45.12374262
OS 4.649851 45.1311391
OS 4.64430364 45.13761102
OS 4.6406054 45.14315838
OS 4.63690716 45.14685662
OS 4.63505804 45.14870574
OS 4.63413348 45.1496303
OE
OB 5.34974292 45.14408294 H
OS 5.33310084 45.14315838
OS 5.31923244 45.14223382
OS 5.30813772 45.14130926
OS 5.30074124 45.13946014
OS 5.29519388 45.13853558
OS 5.29149564 45.13761102
OS 5.29057108 45.13761102
OS 5.2785518 45.13298822
OS 5.26838164 45.12744086
OS 5.25913604 45.1218935
OS 5.250815 45.11542158
OS 5.24526764 45.10894966
OS 5.24064484 45.10432686
OS 5.23787116 45.10062862
OS 5.2369466 45.09970406
OS 5.23047468 45.08860934
OS 5.22492732 45.07751462
OS 5.22122908 45.06549534
OS 5.21937996 45.05532518
OS 5.21753084 45.04607958
OS 5.21660628 45.03775854
OS 5.21660628 45.03313574
OS 5.21660628 45.03221118
OS 5.21660628 45.03128662
OS 5.2184554 45.01187086
OS 5.22215364 44.99522878
OS 5.227701 44.98043582
OS 5.23417292 44.96841654
OS 5.24064484 44.95917094
OS 5.2461922 44.95177446
OS 5.24989044 44.94807622
OS 5.25173956 44.9462271
OS 5.25821148 44.94067974
OS 5.26653252 44.93605694
OS 5.28409916 44.92866046
OS 5.30351492 44.9231131
OS 5.32293068 44.91941486
OS 5.34049732 44.91756574
OS 5.3478938 44.91664118
OS 5.35436572 44.91664118
OS 5.36083764 44.91571662
OS 5.5328058 44.91571662
OS 5.5328058 45.14408294
OS 5.34974292 45.14408294
OE
SE
S P 0
OB 7.8804516 41.60661986 I
OS 7.88599896 41.60754442
OS 7.89432 41.60754442
OS 7.90911296 41.60661986
OS 7.92390592 41.6056953
OS 7.9497936 41.60014794
OS 7.96181288 41.5964497
OS 7.9729076 41.59275146
OS 7.98307776 41.58812866
OS 7.99232336 41.58350586
OS 7.99971984 41.57888306
OS 8.00711632 41.57426026
OS 8.01358824 41.57056202
OS 8.01821104 41.56686378
OS 8.02190928 41.5640901
OS 8.02468296 41.56131642
OS 8.02653208 41.56039186
OS 8.02745664 41.5594673
OS 8.03577768 41.5502217
OS 8.04409872 41.5409761
OS 8.05057064 41.53080594
OS 8.056118 41.52063578
OS 8.0653636 41.50122002
OS 8.07091096 41.48272882
OS 8.0746092 41.4670113
OS 8.07553376 41.45961482
OS 8.07645832 41.45406746
OS 8.07738288 41.4485201
OS 8.07738288 41.44482186
OS 8.07738288 41.44297274
OS 8.07738288 41.44204818
OS 8.07645832 41.4254061
OS 8.07368464 41.40968858
OS 8.0699864 41.39582018
OS 8.0653636 41.3838009
OS 8.06166536 41.3745553
OS 8.05796712 41.36715882
OS 8.05519344 41.36346058
OS 8.05426888 41.36161146
OS 8.04409872 41.35051674
OS 8.033004 41.34034658
OS 8.02098472 41.33110098
OS 8.00896544 41.3237045
OS 7.99787072 41.31815714
OS 7.98954968 41.3144589
OS 7.98585144 41.31260978
OS 7.98307776 41.31168522
OS 7.9821532 41.31076066
OS 7.98122864 41.31076066
OS 8.00249352 41.30428874
OS 8.02006016 41.2959677
OS 8.03577768 41.28579754
OS 8.04872152 41.27655194
OS 8.05889168 41.26730634
OS 8.06628816 41.25990986
OS 8.0699864 41.25528706
OS 8.07183552 41.2543625
OS 8.07183552 41.25343794
OS 8.08200568 41.23679586
OS 8.09032672 41.21922922
OS 8.09587408 41.20258714
OS 8.09957232 41.18594506
OS 8.10142144 41.1711521
OS 8.102346 41.16468018
OS 8.102346 41.15913282
OS 8.10327056 41.15543458
OS 8.10327056 41.15173634
OS 8.10327056 41.14988722
OS 8.10327056 41.14896266
OS 8.102346 41.1341697
OS 8.10049688 41.11937674
OS 8.0977232 41.10550834
OS 8.09402496 41.09163994
OS 8.08477936 41.06852594
OS 8.08015656 41.05743122
OS 8.0746092 41.04818562
OS 8.06906184 41.03894002
OS 8.06443904 41.03154354
OS 8.05889168 41.02507162
OS 8.05519344 41.01952426
OS 8.0514952 41.01490146
OS 8.04872152 41.01212778
OS 8.0468724 41.01027866
OS 8.04594784 41.0093541
OS 8.03485312 40.99918394
OS 8.02283384 40.9908629
OS 8.00989 40.98346642
OS 7.99694616 40.9769945
OS 7.98492688 40.9723717
OS 7.97198304 40.9677489
OS 7.94701992 40.96127698
OS 7.9359252 40.9585033
OS 7.92575504 40.95665418
OS 7.91650944 40.95572962
OS 7.9081884 40.95480506
OS 7.90171648 40.9538805
OS 7.89247088 40.9538805
OS 7.87490424 40.95480506
OS 7.85918672 40.95665418
OS 7.8434692 40.95942786
OS 7.82867624 40.96220154
OS 7.8157324 40.96682434
OS 7.80278856 40.97144714
OS 7.79076928 40.97606994
OS 7.78059912 40.9816173
OS 7.77135352 40.98716466
OS 7.76303248 40.99178746
OS 7.75656056 40.99641026
OS 7.75008864 41.00103306
OS 7.74546584 41.00380674
OS 7.74269216 41.00658042
OS 7.74084304 41.00842954
OS 7.73991848 41.0093541
OS 7.72974832 41.02044882
OS 7.72050272 41.03154354
OS 7.71310624 41.04263826
OS 7.70663432 41.05465754
OS 7.7001624 41.06575226
OS 7.6955396 41.07777154
OS 7.68906768 41.09903642
OS 7.686294 41.10920658
OS 7.68444488 41.11845218
OS 7.68352032 41.12677322
OS 7.68259576 41.13324514
OS 7.6816712 41.1387925
OS 7.6816712 41.1434153
OS 7.6816712 41.14618898
OS 7.6816712 41.14711354
OS 7.68259576 41.16837842
OS 7.686294 41.18779418
OS 7.69184136 41.20536082
OS 7.69738872 41.22015378
OS 7.70293608 41.23217306
OS 7.70848344 41.24141866
OS 7.71218168 41.24696602
OS 7.71310624 41.24789058
OS 7.71310624 41.24881514
OS 7.72605008 41.2636081
OS 7.73991848 41.27655194
OS 7.75471144 41.2867221
OS 7.76857984 41.2959677
OS 7.78152368 41.30243962
OS 7.7926184 41.30706242
OS 7.79631664 41.30891154
OS 7.79909032 41.3098361
OS 7.80093944 41.31076066
OS 7.801864 41.31076066
OS 7.78522192 41.31815714
OS 7.77135352 41.32647818
OS 7.75933424 41.33479922
OS 7.74916408 41.34312026
OS 7.7417676 41.35051674
OS 7.73622024 41.3560641
OS 7.732522 41.35976234
OS 7.73159744 41.36161146
OS 7.7232764 41.3745553
OS 7.71772904 41.38749914
OS 7.71310624 41.40044298
OS 7.71033256 41.41338682
OS 7.70848344 41.42355698
OS 7.70755888 41.43187802
OS 7.70755888 41.43742538
OS 7.70755888 41.43834994
OS 7.70755888 41.4392745
OS 7.70848344 41.45221834
OS 7.709408 41.46423762
OS 7.71587992 41.48735162
OS 7.72420096 41.50769194
OS 7.73344656 41.52525858
OS 7.74269216 41.53912698
OS 7.74731496 41.54467434
OS 7.7510132 41.5502217
OS 7.75471144 41.55391994
OS 7.75748512 41.55669362
OS 7.75840968 41.55761818
OS 7.75933424 41.55854274
OS 7.7695044 41.56686378
OS 7.77967456 41.57518482
OS 7.79076928 41.58165674
OS 7.801864 41.5872041
OS 7.82405344 41.59552514
OS 7.84624288 41.6010725
OS 7.85548848 41.60384618
OS 7.86473408 41.60477074
OS 7.87305512 41.6056953
OS 7.8804516 41.60661986
OE
OB 8.38988416 41.60384618 I
OS 8.40375256 41.60477074
OS 8.6663276 41.60477074
OS 8.6663276 40.96497522
OS 8.58126808 40.96497522
OS 8.58126808 41.22477658
OS 8.41762096 41.22477658
OS 8.3935824 41.22570114
OS 8.3704684 41.22755026
OS 8.35012808 41.23032394
OS 8.33163688 41.23402218
OS 8.31407024 41.23772042
OS 8.29927728 41.24234322
OS 8.28540888 41.24789058
OS 8.2733896 41.25343794
OS 8.26321944 41.25806074
OS 8.25397384 41.2636081
OS 8.24657736 41.2682309
OS 8.24103 41.2728537
OS 8.2364072 41.27562738
OS 8.23363352 41.27840106
OS 8.2317844 41.28025018
OS 8.23085984 41.28117474
OS 8.22161424 41.29226946
OS 8.2132932 41.30336418
OS 8.20682128 41.3144589
OS 8.20034936 41.32647818
OS 8.194802 41.33849746
OS 8.19110376 41.34959218
OS 8.18463184 41.37085706
OS 8.18278272 41.38102722
OS 8.1809336 41.39027282
OS 8.18000904 41.39859386
OS 8.17908448 41.40506578
OS 8.17815992 41.4115377
OS 8.17815992 41.41523594
OS 8.17815992 41.41800962
OS 8.17815992 41.41893418
OS 8.17908448 41.43650082
OS 8.1809336 41.4531429
OS 8.18463184 41.46793586
OS 8.18740552 41.4808797
OS 8.19110376 41.49197442
OS 8.194802 41.50029546
OS 8.19665112 41.50491826
OS 8.19757568 41.50676738
OS 8.20497216 41.52063578
OS 8.21421776 41.53265506
OS 8.2225388 41.54374978
OS 8.23085984 41.55207082
OS 8.23825632 41.55854274
OS 8.24380368 41.5640901
OS 8.24750192 41.56686378
OS 8.24935104 41.56778834
OS 8.26137032 41.57518482
OS 8.27523872 41.58165674
OS 8.28818256 41.5872041
OS 8.30020184 41.5918269
OS 8.31129656 41.59460058
OS 8.3196176 41.5964497
OS 8.32608952 41.59829882
OS 8.32793864 41.59829882
OS 8.34180704 41.60014794
OS 8.35752456 41.60199706
OS 8.37416664 41.60292162
OS 8.38988416 41.60384618
OE
OB 7.89247088 41.54282522 H
OS 7.87675336 41.54190066
OS 7.8619604 41.53820242
OS 7.84994112 41.53357962
OS 7.8388464 41.52803226
OS 7.83052536 41.5224849
OS 7.82405344 41.5178621
OS 7.81943064 41.51416386
OS 7.81850608 41.5132393
OS 7.80833592 41.50122002
OS 7.80093944 41.48920074
OS 7.79539208 41.47718146
OS 7.79169384 41.46608674
OS 7.78984472 41.45591658
OS 7.7879956 41.44759554
OS 7.7879956 41.44204818
OS 7.7879956 41.44112362
OS 7.7879956 41.44019906
OS 7.78892016 41.4254061
OS 7.7926184 41.4115377
OS 7.7972412 41.39951842
OS 7.80278856 41.38934826
OS 7.80833592 41.38102722
OS 7.81295872 41.37547986
OS 7.81665696 41.37085706
OS 7.81758152 41.3699325
OS 7.82867624 41.3606869
OS 7.84162008 41.35329042
OS 7.85363936 41.34866762
OS 7.86565864 41.34496938
OS 7.87675336 41.34312026
OS 7.8850744 41.3421957
OS 7.89062176 41.34127114
OS 7.89247088 41.34127114
OS 7.90911296 41.3421957
OS 7.92390592 41.34589394
OS 7.93684976 41.35051674
OS 7.94794448 41.3560641
OS 7.95626552 41.3606869
OS 7.96273744 41.3653097
OS 7.96736024 41.36900794
OS 7.9682848 41.3699325
OS 7.9775304 41.38102722
OS 7.98492688 41.39397106
OS 7.98954968 41.40599034
OS 7.99324792 41.41800962
OS 7.99509704 41.42817978
OS 7.9960216 41.43650082
OS 7.99694616 41.44204818
OS 7.99694616 41.44297274
OS 7.99694616 41.4438973
OS 7.9960216 41.45869026
OS 7.99232336 41.4716341
OS 7.98770056 41.48365338
OS 7.9821532 41.49382354
OS 7.9775304 41.50214458
OS 7.9729076 41.5086165
OS 7.96920936 41.51231474
OS 7.9682848 41.5132393
OS 7.95626552 41.52340946
OS 7.94424624 41.53080594
OS 7.9313024 41.53542874
OS 7.91928312 41.53912698
OS 7.9081884 41.5409761
OS 7.89986736 41.54282522
OS 7.89247088 41.54282522
OE
OB 8.3982052 41.52895682 H
OS 8.38156312 41.52803226
OS 8.36769472 41.5271077
OS 8.3566 41.52618314
OS 8.34920352 41.52433402
OS 8.34365616 41.52340946
OS 8.33995792 41.5224849
OS 8.33903336 41.5224849
OS 8.32701408 41.5178621
OS 8.31684392 41.51231474
OS 8.30759832 41.50676738
OS 8.29927728 41.50029546
OS 8.29372992 41.49382354
OS 8.28910712 41.48920074
OS 8.28633344 41.4855025
OS 8.28540888 41.48457794
OS 8.27893696 41.47348322
OS 8.2733896 41.4623885
OS 8.26969136 41.45036922
OS 8.26784224 41.44019906
OS 8.26599312 41.43095346
OS 8.26506856 41.42263242
OS 8.26506856 41.41800962
OS 8.26506856 41.41708506
OS 8.26506856 41.4161605
OS 8.26691768 41.39674474
OS 8.27061592 41.38010266
OS 8.27616328 41.3653097
OS 8.2826352 41.35329042
OS 8.28910712 41.34404482
OS 8.29465448 41.33664834
OS 8.29835272 41.3329501
OS 8.30020184 41.33110098
OS 8.30667376 41.32555362
OS 8.3149948 41.32093082
OS 8.33256144 41.31353434
OS 8.3519772 41.30798698
OS 8.37139296 41.30428874
OS 8.3889596 41.30243962
OS 8.39635608 41.30151506
OS 8.402828 41.30151506
OS 8.40929992 41.3005905
OS 8.58126808 41.3005905
OS 8.58126808 41.52895682
OS 8.3982052 41.52895682
OE
OB 7.89524456 41.2774765 H
OS 7.87490424 41.27562738
OS 7.85641304 41.27192914
OS 7.83977096 41.26545722
OS 7.82590256 41.2589853
OS 7.81480784 41.25158882
OS 7.8064868 41.2451169
OS 7.801864 41.24141866
OS 7.80001488 41.23956954
OS 7.78707104 41.22477658
OS 7.77782544 41.20905906
OS 7.77135352 41.19334154
OS 7.76673072 41.17947314
OS 7.76395704 41.16560474
OS 7.76303248 41.15543458
OS 7.76210792 41.15173634
OS 7.76210792 41.14896266
OS 7.76210792 41.14711354
OS 7.76210792 41.14618898
OS 7.76395704 41.12677322
OS 7.76765528 41.10828202
OS 7.7741272 41.0925645
OS 7.78059912 41.07962066
OS 7.78707104 41.0694505
OS 7.79354296 41.06112946
OS 7.7972412 41.05650666
OS 7.79909032 41.05465754
OS 7.81388328 41.04263826
OS 7.82867624 41.03339266
OS 7.84439376 41.0278453
OS 7.85918672 41.0232225
OS 7.87213056 41.02044882
OS 7.88322528 41.01952426
OS 7.88692352 41.0185997
OS 7.89247088 41.0185997
OS 7.90541472 41.01952426
OS 7.91835856 41.02137338
OS 7.93037784 41.02414706
OS 7.940548 41.02692074
OS 7.94886904 41.02969442
OS 7.95534096 41.0324681
OS 7.9590392 41.03431722
OS 7.96088832 41.03524178
OS 7.97198304 41.04263826
OS 7.98122864 41.05003474
OS 7.98954968 41.05835578
OS 7.9960216 41.06667682
OS 8.00156896 41.07314874
OS 8.0052672 41.0786961
OS 8.00711632 41.0833189
OS 8.00804088 41.08424346
OS 8.01266368 41.09626274
OS 8.01636192 41.10735746
OS 8.0191356 41.11845218
OS 8.02098472 41.12862234
OS 8.02190928 41.13694338
OS 8.02283384 41.1434153
OS 8.02283384 41.14711354
OS 8.02283384 41.14896266
OS 8.02098472 41.16837842
OS 8.01728648 41.18594506
OS 8.01173912 41.20166258
OS 8.00434264 41.21553098
OS 7.99787072 41.22570114
OS 7.99232336 41.23402218
OS 7.98862512 41.23864498
OS 7.986776 41.2404941
OS 7.9729076 41.25251338
OS 7.95719008 41.26175898
OS 7.94239712 41.2682309
OS 7.92760416 41.2728537
OS 7.91466032 41.27562738
OS 7.90449016 41.27655194
OS 7.90079192 41.2774765
OS 7.89524456 41.2774765
OE
SE
S P 0
OB 8.5619082 1.93766694 I
OS 8.5619082 2.37405926
OS 8.64696772 2.37405926
OS 8.64696772 1.93304414
OS 8.64696772 1.91362838
OS 8.64881684 1.8969863
OS 8.6497414 1.8831179
OS 8.65159052 1.87202318
OS 8.65343964 1.86370214
OS 8.6543642 1.85723022
OS 8.65621332 1.85353198
OS 8.65621332 1.85260742
OS 8.65991156 1.84336182
OS 8.66453436 1.83596534
OS 8.67008172 1.82949342
OS 8.67470452 1.8230215
OS 8.68025188 1.81932326
OS 8.68395012 1.81562502
OS 8.6867238 1.8137759
OS 8.68764836 1.81285134
OS 8.69689396 1.80822854
OS 8.70613956 1.8045303
OS 8.71538516 1.80268118
OS 8.7237062 1.80083206
OS 8.73202724 1.7999075
OS 8.7375746 1.79898294
OS 8.74312196 1.79898294
OS 8.75791492 1.7999075
OS 8.77178332 1.80360574
OS 8.78287804 1.80730398
OS 8.7930482 1.81285134
OS 8.80044468 1.81747414
OS 8.80599204 1.82209694
OS 8.80969028 1.82487062
OS 8.81061484 1.82579518
OS 8.81523764 1.83134254
OS 8.81893588 1.83781446
OS 8.82448324 1.85260742
OS 8.8300306 1.8692495
OS 8.83280428 1.88589158
OS 8.83557796 1.9016091
OS 8.83557796 1.90808102
OS 8.83650252 1.91362838
OS 8.83742708 1.91917574
OS 8.83742708 1.92287398
OS 8.83742708 1.9247231
OS 8.83742708 1.92564766
OS 8.91416556 1.91455294
OS 8.91416556 1.8969863
OS 8.913241 1.88126878
OS 8.91046732 1.86555126
OS 8.9086182 1.85168286
OS 8.90491996 1.83873902
OS 8.90122172 1.8276443
OS 8.89752348 1.81654958
OS 8.89382524 1.80730398
OS 8.88920244 1.79898294
OS 8.8855042 1.79158646
OS 8.88180596 1.78511454
OS 8.87810772 1.78049174
OS 8.87533404 1.7767935
OS 8.87348492 1.77309526
OS 8.87256036 1.7721707
OS 8.8716358 1.77124614
OS 8.8623902 1.7629251
OS 8.8531446 1.75552862
OS 8.84297444 1.7490567
OS 8.83187972 1.74350934
OS 8.81061484 1.7351883
OS 8.79027452 1.72964094
OS 8.77085876 1.7259427
OS 8.76346228 1.72501814
OS 8.7560658 1.72409358
OS 8.75051844 1.72316902
OS 8.7421974 1.72316902
OS 8.72185708 1.72409358
OS 8.70336588 1.72686726
OS 8.6867238 1.7305655
OS 8.67193084 1.7351883
OS 8.65991156 1.73888654
OS 8.65159052 1.74258478
OS 8.64604316 1.74535846
OS 8.64419404 1.74628302
OS 8.62940108 1.75552862
OS 8.61645724 1.76662334
OS 8.60628708 1.77771806
OS 8.59704148 1.78788822
OS 8.59056956 1.79805838
OS 8.58594676 1.80545486
OS 8.58317308 1.81100222
OS 8.58224852 1.81192678
OS 8.58224852 1.81285134
OS 8.5757766 1.83134254
OS 8.57022924 1.8507583
OS 8.566531 1.87202318
OS 8.56468188 1.8923635
OS 8.56283276 1.90993014
OS 8.56283276 1.91732662
OS 8.5619082 1.9247231
OS 8.5619082 1.93027046
OS 8.5619082 1.9339687
OS 8.5619082 1.93674238
OS 8.5619082 1.93766694
OE
OB 8.23553852 2.37590838 I
OS 8.24570868 2.37683294
OS 8.26882268 2.37683294
OS 8.28176652 2.37498382
OS 8.30672964 2.37036102
OS 8.32799452 2.36296454
OS 8.34648572 2.35556806
OS 8.35480676 2.35094526
OS 8.36127868 2.34724702
OS 8.3677506 2.34354878
OS 8.3723734 2.33985054
OS 8.37607164 2.33707686
OS 8.37884532 2.33522774
OS 8.38069444 2.33430318
OS 8.381619 2.33337862
OS 8.39918564 2.31581198
OS 8.41305404 2.29639622
OS 8.42414876 2.2760559
OS 8.43339436 2.25571558
OS 8.43894172 2.23814894
OS 8.4417154 2.23075246
OS 8.44356452 2.22428054
OS 8.44448908 2.21873318
OS 8.44541364 2.21503494
OS 8.4463382 2.21226126
OS 8.4463382 2.2113367
OS 8.3677506 2.1974683
OS 8.36405236 2.21780862
OS 8.358505 2.23537526
OS 8.35203308 2.25016822
OS 8.34556116 2.2621875
OS 8.33908924 2.2714331
OS 8.33354188 2.27790502
OS 8.32984364 2.28252782
OS 8.32891908 2.28345238
OS 8.3168998 2.29269798
OS 8.30395596 2.30009446
OS 8.29193668 2.30471726
OS 8.2799174 2.3084155
OS 8.26882268 2.31026462
OS 8.26050164 2.31211374
OS 8.25310516 2.31211374
OS 8.23646308 2.31118918
OS 8.22167012 2.30749094
OS 8.20872628 2.30286814
OS 8.19763156 2.29824534
OS 8.18931052 2.29269798
OS 8.1828386 2.28807518
OS 8.1782158 2.28437694
OS 8.17729124 2.28345238
OS 8.16712108 2.27235766
OS 8.1597246 2.26033838
OS 8.1551018 2.2483191
OS 8.15140356 2.23722438
OS 8.14955444 2.22705422
OS 8.14770532 2.21965774
OS 8.14770532 2.21411038
OS 8.14770532 2.21318582
OS 8.14770532 2.21226126
OS 8.14770532 2.2020911
OS 8.14955444 2.1928455
OS 8.15417724 2.17712798
OS 8.16064916 2.16325958
OS 8.16804564 2.1512403
OS 8.17544212 2.14291926
OS 8.18191404 2.13644734
OS 8.18653684 2.1327491
OS 8.1874614 2.13182454
OS 8.18838596 2.13182454
OS 8.20410348 2.1235035
OS 8.21889644 2.11703158
OS 8.23461396 2.11240878
OS 8.24848236 2.1096351
OS 8.26050164 2.10778598
OS 8.2706718 2.10593686
OS 8.28269108 2.10593686
OS 8.28638932 2.10686142
OS 8.29101212 2.10686142
OS 8.30025772 2.03751942
OS 8.28823844 2.0402931
OS 8.27714372 2.04214222
OS 8.26789812 2.04399134
OS 8.25957708 2.0449159
OS 8.25310516 2.04584046
OS 8.24478412 2.04584046
OS 8.22536836 2.04399134
OS 8.20780172 2.0402931
OS 8.1920842 2.03474574
OS 8.17914036 2.02827382
OS 8.1689702 2.0218019
OS 8.16157372 2.01625454
OS 8.15695092 2.0125563
OS 8.1551018 2.01070718
OS 8.14308252 1.99683878
OS 8.13383692 1.98204582
OS 8.127365 1.96725286
OS 8.12366676 1.9524599
OS 8.12089308 1.94044062
OS 8.11996852 1.93027046
OS 8.11904396 1.92657222
OS 8.11904396 1.92379854
OS 8.11904396 1.92194942
OS 8.11904396 1.92102486
OS 8.12089308 1.90068454
OS 8.12551588 1.88219334
OS 8.13106324 1.86647582
OS 8.13845972 1.85260742
OS 8.1458562 1.8415127
OS 8.15140356 1.83319166
OS 8.15602636 1.8276443
OS 8.15787548 1.82579518
OS 8.17266844 1.81285134
OS 8.18838596 1.80360574
OS 8.20410348 1.79713382
OS 8.21889644 1.79251102
OS 8.23184028 1.78973734
OS 8.24201044 1.78881278
OS 8.24570868 1.78788822
OS 8.25125604 1.78788822
OS 8.26789812 1.78881278
OS 8.28361564 1.79251102
OS 8.29748404 1.79713382
OS 8.30857876 1.80268118
OS 8.31782436 1.80730398
OS 8.32522084 1.81192678
OS 8.32891908 1.81562502
OS 8.3307682 1.81654958
OS 8.34186292 1.82949342
OS 8.35110852 1.84428638
OS 8.35942956 1.8600039
OS 8.36590148 1.87664598
OS 8.37052428 1.89051438
OS 8.3723734 1.8969863
OS 8.37329796 1.90253366
OS 8.37422252 1.90715646
OS 8.37514708 1.9108547
OS 8.37607164 1.91270382
OS 8.37607164 1.91362838
OS 8.45465924 1.90345822
OS 8.45281012 1.88866526
OS 8.45003644 1.87479686
OS 8.4417154 1.84890918
OS 8.43154524 1.82671974
OS 8.42599788 1.81747414
OS 8.42045052 1.80822854
OS 8.41490316 1.7999075
OS 8.4093558 1.79343558
OS 8.404733 1.78696366
OS 8.4001102 1.78234086
OS 8.39733652 1.77864262
OS 8.39456284 1.77586894
OS 8.39271372 1.77401982
OS 8.39178916 1.77309526
OS 8.38069444 1.76477422
OS 8.36959972 1.75645318
OS 8.358505 1.74998126
OS 8.34648572 1.7444339
OS 8.32337172 1.7351883
OS 8.30118228 1.72964094
OS 8.29101212 1.72779182
OS 8.28176652 1.7259427
OS 8.27344548 1.72501814
OS 8.266049 1.72409358
OS 8.26050164 1.72316902
OS 8.2521806 1.72316902
OS 8.23461396 1.72409358
OS 8.21889644 1.7259427
OS 8.20317892 1.72871638
OS 8.18838596 1.73241462
OS 8.17451756 1.73703742
OS 8.16249828 1.74166022
OS 8.150479 1.74720758
OS 8.14030884 1.75275494
OS 8.13013868 1.75737774
OS 8.12181764 1.7629251
OS 8.11442116 1.7675479
OS 8.1088738 1.7721707
OS 8.104251 1.77586894
OS 8.10055276 1.77864262
OS 8.09870364 1.78049174
OS 8.09777908 1.7814163
OS 8.08668436 1.79251102
OS 8.07743876 1.8045303
OS 8.06911772 1.81654958
OS 8.06172124 1.82856886
OS 8.05617388 1.83966358
OS 8.05062652 1.85168286
OS 8.04323004 1.8738723
OS 8.04138092 1.88404246
OS 8.0395318 1.89328806
OS 8.03768268 1.9016091
OS 8.03675812 1.90900558
OS 8.03583356 1.91455294
OS 8.03583356 1.91917574
OS 8.03583356 1.92194942
OS 8.03583356 1.92287398
OS 8.03675812 1.94506342
OS 8.04045636 1.96540374
OS 8.04600372 1.98297038
OS 8.05155108 1.99776334
OS 8.05709844 2.00978262
OS 8.0626458 2.01902822
OS 8.06634404 2.02457558
OS 8.0672686 2.0264247
OS 8.08021244 2.0402931
OS 8.09408084 2.05231238
OS 8.1088738 2.06155798
OS 8.12366676 2.06895446
OS 8.1366106 2.07450182
OS 8.14678076 2.07820006
OS 8.150479 2.07912462
OS 8.15325268 2.08004918
OS 8.1551018 2.08097374
OS 8.15602636 2.08097374
OS 8.14030884 2.08929478
OS 8.127365 2.09761582
OS 8.11627028 2.10686142
OS 8.10702468 2.11518246
OS 8.0996282 2.12257894
OS 8.09408084 2.12905086
OS 8.09130716 2.1327491
OS 8.0903826 2.13459822
OS 8.08298612 2.14754206
OS 8.07743876 2.1604859
OS 8.07281596 2.17342974
OS 8.07004228 2.18544902
OS 8.06819316 2.19561918
OS 8.0672686 2.20301566
OS 8.0672686 2.20856302
OS 8.0672686 2.21041214
OS 8.06819316 2.22612966
OS 8.07096684 2.24184718
OS 8.07466508 2.25571558
OS 8.07928788 2.26773486
OS 8.08391068 2.27790502
OS 8.08760892 2.28622606
OS 8.0903826 2.29084886
OS 8.09130716 2.29269798
OS 8.10055276 2.30656638
OS 8.11164748 2.31858566
OS 8.1227422 2.32875582
OS 8.13383692 2.33800142
OS 8.14308252 2.34447334
OS 8.15140356 2.3500207
OS 8.15695092 2.35279438
OS 8.15787548 2.35371894
OS 8.15880004 2.35371894
OS 8.17544212 2.36111542
OS 8.1920842 2.36666278
OS 8.20872628 2.37128558
OS 8.22351924 2.37405926
OS 8.23553852 2.37590838
OE
SE
S P 0
OB 11.43788416 41.63813364 I
OS 11.45175256 41.6390582
OS 11.7143276 41.6390582
OS 11.7143276 40.99926268
OS 11.62926808 40.99926268
OS 11.62926808 41.25906404
OS 11.46562096 41.25906404
OS 11.4415824 41.2599886
OS 11.4184684 41.26183772
OS 11.39812808 41.2646114
OS 11.37963688 41.26830964
OS 11.36207024 41.27200788
OS 11.34727728 41.27663068
OS 11.33340888 41.28217804
OS 11.3213896 41.2877254
OS 11.31121944 41.2923482
OS 11.30197384 41.29789556
OS 11.29457736 41.30251836
OS 11.28903 41.30714116
OS 11.2844072 41.30991484
OS 11.28163352 41.31268852
OS 11.2797844 41.31453764
OS 11.27885984 41.3154622
OS 11.26961424 41.32655692
OS 11.2612932 41.33765164
OS 11.25482128 41.34874636
OS 11.24834936 41.36076564
OS 11.242802 41.37278492
OS 11.23910376 41.38387964
OS 11.23263184 41.40514452
OS 11.23078272 41.41531468
OS 11.2289336 41.42456028
OS 11.22800904 41.43288132
OS 11.22708448 41.43935324
OS 11.22615992 41.44582516
OS 11.22615992 41.4495234
OS 11.22615992 41.45229708
OS 11.22615992 41.45322164
OS 11.22708448 41.47078828
OS 11.2289336 41.48743036
OS 11.23263184 41.50222332
OS 11.23540552 41.51516716
OS 11.23910376 41.52626188
OS 11.242802 41.53458292
OS 11.24465112 41.53920572
OS 11.24557568 41.54105484
OS 11.25297216 41.55492324
OS 11.26221776 41.56694252
OS 11.2705388 41.57803724
OS 11.27885984 41.58635828
OS 11.28625632 41.5928302
OS 11.29180368 41.59837756
OS 11.29550192 41.60115124
OS 11.29735104 41.6020758
OS 11.30937032 41.60947228
OS 11.32323872 41.6159442
OS 11.33618256 41.62149156
OS 11.34820184 41.62611436
OS 11.35929656 41.62888804
OS 11.3676176 41.63073716
OS 11.37408952 41.63258628
OS 11.37593864 41.63258628
OS 11.38980704 41.6344354
OS 11.40552456 41.63628452
OS 11.42216664 41.63720908
OS 11.43788416 41.63813364
OE
OB 10.93862176 41.64090732 I
OS 10.94324456 41.64183188
OS 10.94971648 41.64183188
OS 10.965434 41.64090732
OS 10.98022696 41.6390582
OS 10.99501992 41.63628452
OS 11.00796376 41.63258628
OS 11.03292688 41.62241612
OS 11.0440216 41.61779332
OS 11.0532672 41.61224596
OS 11.0625128 41.60577404
OS 11.06990928 41.60115124
OS 11.07730576 41.59560388
OS 11.08285312 41.59098108
OS 11.08747592 41.58728284
OS 11.0902496 41.58450916
OS 11.09209872 41.58266004
OS 11.09302328 41.58173548
OS 11.10319344 41.57064076
OS 11.11151448 41.55769692
OS 11.11983552 41.54567764
OS 11.12630744 41.5327338
OS 11.1318548 41.5188654
OS 11.1364776 41.50592156
OS 11.14294952 41.481883
OS 11.1457232 41.46986372
OS 11.14757232 41.45969356
OS 11.14849688 41.4495234
OS 11.14942144 41.44120236
OS 11.150346 41.43473044
OS 11.150346 41.43010764
OS 11.150346 41.4264094
OS 11.150346 41.42548484
OS 11.14942144 41.4079182
OS 11.14757232 41.39220068
OS 11.1457232 41.37648316
OS 11.14202496 41.3616902
OS 11.13740216 41.34874636
OS 11.13277936 41.33580252
OS 11.12815656 41.3247078
OS 11.1226092 41.31453764
OS 11.1179864 41.30529204
OS 11.1133636 41.296971
OS 11.1087408 41.29049908
OS 11.104118 41.28402716
OS 11.10041976 41.27940436
OS 11.09857064 41.27663068
OS 11.09672152 41.27478156
OS 11.09579696 41.273857
OS 11.0856268 41.26368684
OS 11.07453208 41.2553658
OS 11.06343736 41.24704476
OS 11.05141808 41.24057284
OS 11.04032336 41.23502548
OS 11.02922864 41.23040268
OS 11.00796376 41.22393076
OS 10.99871816 41.22115708
OS 10.98947256 41.21930796
OS 10.98207608 41.2183834
OS 10.9746796 41.21745884
OS 10.96913224 41.21653428
OS 10.96173576 41.21653428
OS 10.94416912 41.21745884
OS 10.92752704 41.22023252
OS 10.91273408 41.22393076
OS 10.89886568 41.22855356
OS 10.88869552 41.2322518
OS 10.88037448 41.23595004
OS 10.87482712 41.23872372
OS 10.872978 41.23964828
OS 10.85818504 41.24889388
OS 10.8452412 41.25906404
OS 10.83414648 41.2692342
OS 10.82490088 41.2784798
OS 10.81842896 41.2877254
OS 10.8128816 41.29419732
OS 10.80918336 41.29882012
OS 10.8082588 41.30066924
OS 10.8082588 41.29327276
OS 10.8082588 41.28864996
OS 10.8082588 41.28587628
OS 10.8082588 41.28495172
OS 10.80918336 41.26646052
OS 10.81010792 41.24889388
OS 10.81195704 41.23317636
OS 10.81380616 41.2183834
OS 10.81657984 41.20636412
OS 10.81842896 41.19711852
OS 10.81935352 41.19342028
OS 10.81935352 41.1906466
OS 10.82027808 41.18972204
OS 10.82027808 41.18879748
OS 10.82490088 41.1721554
OS 10.82952368 41.15736244
OS 10.83414648 41.1444186
OS 10.83876928 41.13332388
OS 10.84246752 41.12500284
OS 10.84616576 41.11853092
OS 10.84801488 41.11390812
OS 10.84893944 41.11298356
OS 10.85633592 41.1028134
OS 10.8637324 41.09449236
OS 10.87112888 41.08709588
OS 10.87852536 41.08062396
OS 10.88407272 41.0750766
OS 10.88962008 41.07137836
OS 10.89331832 41.06952924
OS 10.89424288 41.06860468
OS 10.90441304 41.06305732
OS 10.91550776 41.05935908
OS 10.92567792 41.0565854
OS 10.93584808 41.05473628
OS 10.94416912 41.05381172
OS 10.95064104 41.05288716
OS 10.95711296 41.05288716
OS 10.97190592 41.05381172
OS 10.98577432 41.0565854
OS 10.9977936 41.06028364
OS 11.00796376 41.06490644
OS 11.01536024 41.06860468
OS 11.02183216 41.07230292
OS 11.0255304 41.0750766
OS 11.02645496 41.07600116
OS 11.03570056 41.08617132
OS 11.04309704 41.0981906
OS 11.04956896 41.11113444
OS 11.05419176 41.12407828
OS 11.05789 41.135173
OS 11.06066368 41.14534316
OS 11.06158824 41.1490414
OS 11.06158824 41.15089052
OS 11.0625128 41.15273964
OS 11.0625128 41.1536642
OS 11.13832672 41.14719228
OS 11.13277936 41.12038004
OS 11.12538288 41.09726604
OS 11.11613728 41.07692572
OS 11.10689168 41.06028364
OS 11.09764608 41.0473398
OS 11.09302328 41.04179244
OS 11.08932504 41.03716964
OS 11.08655136 41.03439596
OS 11.08377768 41.03162228
OS 11.08285312 41.03069772
OS 11.08192856 41.02977316
OS 11.07268296 41.02237668
OS 11.0625128 41.01590476
OS 11.04217248 41.0057346
OS 11.02183216 40.99833812
OS 11.0024164 40.99371532
OS 10.98484976 40.99001708
OS 10.97745328 40.98909252
OS 10.97098136 40.98909252
OS 10.96635856 40.98816796
OS 10.95896208 40.98816796
OS 10.9330744 40.99001708
OS 10.9099604 40.99371532
OS 10.88869552 41.00018724
OS 10.87112888 41.00758372
OS 10.8637324 41.0103574
OS 10.85633592 41.01405564
OS 10.85078856 41.01775388
OS 10.8452412 41.02052756
OS 10.84154296 41.02237668
OS 10.83876928 41.0242258
OS 10.83692016 41.02607492
OS 10.8359956 41.02607492
OS 10.8175044 41.04179244
OS 10.80086232 41.05935908
OS 10.78791848 41.07785028
OS 10.77682376 41.09541692
OS 10.76757816 41.11113444
OS 10.76387992 41.11853092
OS 10.76110624 41.12407828
OS 10.75925712 41.12962564
OS 10.757408 41.13332388
OS 10.75648344 41.135173
OS 10.75648344 41.13609756
OS 10.75186064 41.14996596
OS 10.74723784 41.16568348
OS 10.74076592 41.19711852
OS 10.73614312 41.23040268
OS 10.73336944 41.26183772
OS 10.73152032 41.27570612
OS 10.73059576 41.28957452
OS 10.73059576 41.3015938
OS 10.7296712 41.31176396
OS 10.7296712 41.320085
OS 10.7296712 41.32655692
OS 10.7296712 41.33117972
OS 10.7296712 41.33210428
OS 10.7296712 41.35336916
OS 10.73059576 41.37370948
OS 10.73244488 41.39220068
OS 10.734294 41.40976732
OS 10.73614312 41.42548484
OS 10.73799224 41.4402778
OS 10.74076592 41.4541462
OS 10.7435396 41.46616548
OS 10.74631328 41.47633564
OS 10.7481624 41.48558124
OS 10.75093608 41.49390228
OS 10.7527852 41.5003742
OS 10.75463432 41.504997
OS 10.75648344 41.50869524
OS 10.757408 41.51054436
OS 10.757408 41.51146892
OS 10.76850272 41.53365836
OS 10.780522 41.55307412
OS 10.7943904 41.5697162
OS 10.80640968 41.5835846
OS 10.81842896 41.59375476
OS 10.82767456 41.60115124
OS 10.8313728 41.60392492
OS 10.83414648 41.60577404
OS 10.83507104 41.60762316
OS 10.8359956 41.60762316
OS 10.85541136 41.61871788
OS 10.87482712 41.62703892
OS 10.89424288 41.63351084
OS 10.91180952 41.63720908
OS 10.92752704 41.63998276
OS 10.93399896 41.64090732
OS 10.93862176 41.64090732
OE
OB 10.93030072 41.57711268 H
OS 10.92105512 41.57526356
OS 10.90441304 41.57064076
OS 10.88962008 41.56416884
OS 10.87667624 41.55769692
OS 10.86650608 41.55030044
OS 10.8591096 41.54382852
OS 10.8544868 41.53920572
OS 10.85263768 41.53828116
OS 10.85263768 41.5373566
OS 10.8406184 41.52163908
OS 10.8313728 41.50407244
OS 10.82490088 41.48558124
OS 10.82120264 41.4680146
OS 10.81842896 41.45322164
OS 10.8175044 41.44674972
OS 10.8175044 41.4402778
OS 10.81657984 41.435655
OS 10.81657984 41.43195676
OS 10.81657984 41.43010764
OS 10.81657984 41.42918308
OS 10.81842896 41.40514452
OS 10.8221272 41.38387964
OS 10.82767456 41.366313
OS 10.83414648 41.35152004
OS 10.84154296 41.33950076
OS 10.84709032 41.33117972
OS 10.85078856 41.32563236
OS 10.85263768 41.32378324
OS 10.86650608 41.3108394
OS 10.88129904 41.3015938
OS 10.896092 41.29512188
OS 10.91088496 41.29049908
OS 10.92290424 41.2877254
OS 10.9330744 41.28680084
OS 10.93677264 41.28587628
OS 10.94232 41.28587628
OS 10.96173576 41.2877254
OS 10.9793024 41.29142364
OS 10.99501992 41.29789556
OS 11.00888832 41.30529204
OS 11.01905848 41.31176396
OS 11.02737952 41.31823588
OS 11.03200232 41.32193412
OS 11.03385144 41.32378324
OS 11.04587072 41.3385762
OS 11.05511632 41.35521828
OS 11.06066368 41.37186036
OS 11.06528648 41.38757788
OS 11.06806016 41.40144628
OS 11.06898472 41.40699364
OS 11.06898472 41.412541
OS 11.06990928 41.4171638
OS 11.06990928 41.41993748
OS 11.06990928 41.4217866
OS 11.06990928 41.42271116
OS 11.06806016 41.44674972
OS 11.06436192 41.46893916
OS 11.05789 41.48835492
OS 11.05049352 41.50407244
OS 11.0440216 41.51701628
OS 11.03754968 41.52626188
OS 11.03570056 41.52903556
OS 11.03385144 41.53180924
OS 11.03200232 41.5327338
OS 11.03200232 41.53365836
OS 11.02460584 41.54105484
OS 11.01720936 41.54845132
OS 11.00149184 41.55862148
OS 10.98577432 41.56694252
OS 10.97098136 41.57156532
OS 10.95896208 41.57526356
OS 10.94879192 41.57618812
OS 10.94509368 41.57711268
OS 10.93030072 41.57711268
OE
OB 11.4462052 41.56324428 H
OS 11.42956312 41.56231972
OS 11.41569472 41.56139516
OS 11.4046 41.5604706
OS 11.39720352 41.55862148
OS 11.39165616 41.55769692
OS 11.38795792 41.55677236
OS 11.38703336 41.55677236
OS 11.37501408 41.55214956
OS 11.36484392 41.5466022
OS 11.35559832 41.54105484
OS 11.34727728 41.53458292
OS 11.34172992 41.528111
OS 11.33710712 41.5234882
OS 11.33433344 41.51978996
OS 11.33340888 41.5188654
OS 11.32693696 41.50777068
OS 11.3213896 41.49667596
OS 11.31769136 41.48465668
OS 11.31584224 41.47448652
OS 11.31399312 41.46524092
OS 11.31306856 41.45691988
OS 11.31306856 41.45229708
OS 11.31306856 41.45137252
OS 11.31306856 41.45044796
OS 11.31491768 41.4310322
OS 11.31861592 41.41439012
OS 11.32416328 41.39959716
OS 11.3306352 41.38757788
OS 11.33710712 41.37833228
OS 11.34265448 41.3709358
OS 11.34635272 41.36723756
OS 11.34820184 41.36538844
OS 11.35467376 41.35984108
OS 11.3629948 41.35521828
OS 11.38056144 41.3478218
OS 11.3999772 41.34227444
OS 11.41939296 41.3385762
OS 11.4369596 41.33672708
OS 11.44435608 41.33580252
OS 11.450828 41.33580252
OS 11.45729992 41.33487796
OS 11.62926808 41.33487796
OS 11.62926808 41.56324428
OS 11.4462052 41.56324428
OE
SE
S P 0
OB 12.27348828 19.4825874 I
OS 12.28088476 19.48351196
OS 12.57766852 19.48351196
OS 12.57766852 18.84371644
OS 12.492609 18.84371644
OS 12.492609 19.12755636
OS 12.38351092 19.12755636
OS 12.37334076 19.1266318
OS 12.36594428 19.1266318
OS 12.35947236 19.12570724
OS 12.35484956 19.12478268
OS 12.35115132 19.12478268
OS 12.3493022 19.12385812
OS 12.34837764 19.12385812
OS 12.33358468 19.11923532
OS 12.32711276 19.11646164
OS 12.3215654 19.11368796
OS 12.31601804 19.11091428
OS 12.3123198 19.10906516
OS 12.31047068 19.1081406
OS 12.30954612 19.10721604
OS 12.30214964 19.10166868
OS 12.29475316 19.09519676
OS 12.28088476 19.08132836
OS 12.27441284 19.07485644
OS 12.26979004 19.06930908
OS 12.26701636 19.06561084
OS 12.2660918 19.06468628
OS 12.2568462 19.05174244
OS 12.24667604 19.03787404
OS 12.23650588 19.02308108
OS 12.22633572 19.00921268
OS 12.21801468 18.99626884
OS 12.21154276 18.98609868
OS 12.20876908 18.98240044
OS 12.20691996 18.97962676
OS 12.20507084 18.97777764
OS 12.20507084 18.97685308
OS 12.12093588 18.84371644
OS 12.01553604 18.84371644
OS 12.12555868 19.01753372
OS 12.13850252 19.03602492
OS 12.1505218 19.052667
OS 12.16254108 19.0665354
OS 12.17271124 19.07947924
OS 12.18195684 19.08872484
OS 12.18935332 19.09612132
OS 12.19397612 19.10074412
OS 12.19582524 19.10259324
OS 12.20322172 19.1081406
OS 12.21154276 19.11461252
OS 12.22818484 19.12478268
OS 12.23558132 19.12848092
OS 12.24112868 19.13217916
OS 12.24482692 19.13402828
OS 12.24667604 19.13495284
OS 12.23003396 19.13772652
OS 12.21431644 19.1405002
OS 12.20044804 19.145123
OS 12.18657964 19.14882124
OS 12.17456036 19.15344404
OS 12.16346564 19.1589914
OS 12.15329548 19.1636142
OS 12.14404988 19.168237
OS 12.1366534 19.17378436
OS 12.12925692 19.17840716
OS 12.12370956 19.1821054
OS 12.11908676 19.18580364
OS 12.11538852 19.18857732
OS 12.11261484 19.191351
OS 12.11169028 19.19227556
OS 12.11076572 19.19320012
OS 12.10336924 19.20244572
OS 12.09597276 19.21169132
OS 12.08487804 19.23110708
OS 12.07748156 19.25052284
OS 12.0719342 19.26901404
OS 12.06823596 19.28473156
OS 12.0673114 19.29120348
OS 12.0673114 19.2976754
OS 12.06638684 19.3022982
OS 12.06638684 19.30599644
OS 12.06638684 19.30784556
OS 12.06638684 19.30877012
OS 12.0673114 19.32818588
OS 12.07008508 19.34575252
OS 12.07470788 19.3623946
OS 12.07933068 19.376263
OS 12.08487804 19.38828228
OS 12.08857628 19.39752788
OS 12.09227452 19.40307524
OS 12.09319908 19.4039998
OS 12.09319908 19.40492436
OS 12.1042938 19.41971732
OS 12.11538852 19.43266116
OS 12.1274078 19.44375588
OS 12.13850252 19.45207692
OS 12.14867268 19.45854884
OS 12.15699372 19.46224708
OS 12.16254108 19.46502076
OS 12.16346564 19.46594532
OS 12.1643902 19.46594532
OS 12.17271124 19.468719
OS 12.1828814 19.47149268
OS 12.20322172 19.47611548
OS 12.22541116 19.47888916
OS 12.24575148 19.48166284
OS 12.26516724 19.4825874
OS 12.27348828 19.4825874
OE
OB 11.73816804 19.48536108 I
OS 11.74463996 19.48628564
OS 11.75388556 19.48628564
OS 11.77052764 19.48536108
OS 11.78624516 19.48443652
OS 11.80103812 19.48166284
OS 11.81490652 19.47888916
OS 11.82785036 19.47519092
OS 11.83986964 19.47149268
OS 11.85096436 19.46686988
OS 11.86113452 19.46224708
OS 11.87038012 19.45762428
OS 11.8777766 19.45300148
OS 11.88424852 19.44930324
OS 11.88979588 19.445605
OS 11.89441868 19.44283132
OS 11.89719236 19.44005764
OS 11.89904148 19.43913308
OS 11.89996604 19.43820852
OS 11.90921164 19.42896292
OS 11.91753268 19.41879276
OS 11.92585372 19.40769804
OS 11.93232564 19.39660332
OS 11.94342036 19.37441388
OS 11.95081684 19.35222444
OS 11.95359052 19.34205428
OS 11.9563642 19.33188412
OS 11.95821332 19.32356308
OS 11.96006244 19.3161666
OS 11.960987 19.30969468
OS 11.960987 19.30507188
OS 11.96191156 19.3022982
OS 11.96191156 19.30137364
OS 11.88147484 19.2930526
OS 11.87962572 19.31431748
OS 11.87592748 19.33280868
OS 11.87038012 19.34945076
OS 11.8639082 19.3623946
OS 11.85836084 19.37348932
OS 11.85281348 19.3808858
OS 11.84911524 19.3855086
OS 11.84726612 19.38735772
OS 11.83339772 19.39845244
OS 11.81860476 19.40677348
OS 11.80288724 19.4132454
OS 11.78901884 19.41694364
OS 11.776075 19.41971732
OS 11.76498028 19.42064188
OS 11.76128204 19.42156644
OS 11.75573468 19.42156644
OS 11.73631892 19.42064188
OS 11.71875228 19.41694364
OS 11.70395932 19.41139628
OS 11.69101548 19.40584892
OS 11.68084532 19.399377
OS 11.6743734 19.3947542
OS 11.6697506 19.39105596
OS 11.66790148 19.38920684
OS 11.65680676 19.376263
OS 11.64848572 19.36331916
OS 11.6420138 19.35037532
OS 11.63831556 19.33743148
OS 11.63554188 19.32726132
OS 11.63461732 19.31801572
OS 11.63369276 19.31246836
OS 11.63369276 19.3115438
OS 11.63369276 19.31061924
OS 11.63554188 19.29397716
OS 11.63924012 19.27641052
OS 11.64571204 19.260693
OS 11.65218396 19.24590004
OS 11.65958044 19.23388076
OS 11.66605236 19.2237106
OS 11.66790148 19.22001236
OS 11.6697506 19.21723868
OS 11.67159972 19.21631412
OS 11.67159972 19.21538956
OS 11.6789962 19.2052194
OS 11.6882418 19.19504924
OS 11.69841196 19.18395452
OS 11.70950668 19.1728598
OS 11.73262068 19.15067036
OS 11.75573468 19.12848092
OS 11.76775396 19.11831076
OS 11.77792412 19.10906516
OS 11.78809428 19.10074412
OS 11.79641532 19.09334764
OS 11.80288724 19.08780028
OS 11.8084346 19.08317748
OS 11.81213284 19.0804038
OS 11.8130574 19.07947924
OS 11.8361714 19.06006348
OS 11.85743628 19.04157228
OS 11.87500292 19.0249302
OS 11.88887132 19.0110618
OS 11.9008906 18.99904252
OS 11.90921164 18.99072148
OS 11.91383444 18.98517412
OS 11.91568356 18.98424956
OS 11.91568356 18.983325
OS 11.9286274 18.96760748
OS 11.93879756 18.95281452
OS 11.94804316 18.93802156
OS 11.95543964 18.92507772
OS 11.960987 18.913983
OS 11.96468524 18.90566196
OS 11.96653436 18.9001146
OS 11.96745892 18.89919004
OS 11.96745892 18.89826548
OS 11.97115716 18.88809532
OS 11.97300628 18.87884972
OS 11.9748554 18.86960412
OS 11.97577996 18.86128308
OS 11.97670452 18.8538866
OS 11.97670452 18.84833924
OS 11.97670452 18.844641
OS 11.97670452 18.84371644
OS 11.55233148 18.84371644
OS 11.55233148 18.91953036
OS 11.86760644 18.91953036
OS 11.85651172 18.93524788
OS 11.85096436 18.9417198
OS 11.84634156 18.94819172
OS 11.84171876 18.95373908
OS 11.83802052 18.95743732
OS 11.83524684 18.960211
OS 11.83432228 18.96113556
OS 11.82969948 18.96575836
OS 11.82415212 18.97038116
OS 11.81120828 18.98240044
OS 11.79641532 18.99626884
OS 11.7806978 19.01013724
OS 11.76590484 19.02215652
OS 11.75943292 19.02770388
OS 11.75388556 19.03325124
OS 11.74926276 19.03694948
OS 11.74556452 19.03972316
OS 11.7437154 19.04157228
OS 11.74279084 19.04249684
OS 11.72799788 19.05544068
OS 11.71320492 19.06745996
OS 11.70026108 19.07947924
OS 11.6882418 19.0896494
OS 11.67714708 19.09981956
OS 11.66790148 19.10906516
OS 11.65865588 19.1173862
OS 11.6512594 19.12478268
OS 11.64386292 19.13217916
OS 11.63831556 19.13772652
OS 11.63369276 19.14234932
OS 11.62906996 19.14697212
OS 11.62444716 19.15251948
OS 11.62259804 19.1543686
OS 11.6096542 19.17008612
OS 11.59855948 19.18395452
OS 11.58931388 19.19782292
OS 11.5819174 19.20891764
OS 11.57637004 19.2190878
OS 11.5726718 19.22648428
OS 11.57082268 19.23110708
OS 11.56989812 19.2329562
OS 11.56435076 19.2468246
OS 11.56065252 19.260693
OS 11.55695428 19.27363684
OS 11.55510516 19.28473156
OS 11.5541806 19.29490172
OS 11.55325604 19.3022982
OS 11.55325604 19.306921
OS 11.55325604 19.30877012
OS 11.5541806 19.32263852
OS 11.55602972 19.33558236
OS 11.55787884 19.3485262
OS 11.56157708 19.35962092
OS 11.57082268 19.38181036
OS 11.58006828 19.399377
OS 11.58561564 19.40769804
OS 11.59023844 19.41416996
OS 11.59486124 19.42064188
OS 11.59948404 19.42526468
OS 11.60318228 19.42896292
OS 11.6050314 19.43266116
OS 11.60688052 19.43358572
OS 11.60780508 19.43451028
OS 11.61797524 19.44375588
OS 11.62906996 19.45207692
OS 11.64108924 19.45854884
OS 11.65310852 19.4640962
OS 11.67714708 19.4733418
OS 11.70118564 19.47981372
OS 11.7113558 19.48166284
OS 11.72152596 19.48351196
OS 11.73077156 19.48443652
OS 11.73816804 19.48536108
OE
OB 12.29105492 19.41232084 H
OS 12.2660918 19.41139628
OS 12.24482692 19.40769804
OS 12.22633572 19.40307524
OS 12.21246732 19.39752788
OS 12.20044804 19.39198052
OS 12.19305156 19.38735772
OS 12.18842876 19.38365948
OS 12.18657964 19.38273492
OS 12.17548492 19.37071564
OS 12.16716388 19.35869636
OS 12.16161652 19.34575252
OS 12.15699372 19.3346578
OS 12.1551446 19.32356308
OS 12.15422004 19.31524204
OS 12.15329548 19.30969468
OS 12.15329548 19.30877012
OS 12.15329548 19.30784556
OS 12.15422004 19.29675084
OS 12.15606916 19.28565612
OS 12.15884284 19.27641052
OS 12.16161652 19.26808948
OS 12.16531476 19.260693
OS 12.16808844 19.25514564
OS 12.16993756 19.2514474
OS 12.17086212 19.25052284
OS 12.17733404 19.24127724
OS 12.18565508 19.2329562
OS 12.19397612 19.22648428
OS 12.20229716 19.22093692
OS 12.20969364 19.21723868
OS 12.215241 19.214465
OS 12.21893924 19.21261588
OS 12.22078836 19.21169132
OS 12.2337322 19.20799308
OS 12.24852516 19.2052194
OS 12.26331812 19.20337028
OS 12.27811108 19.20244572
OS 12.29105492 19.20152116
OS 12.30214964 19.2005966
OS 12.492609 19.2005966
OS 12.492609 19.41232084
OS 12.29105492 19.41232084
OE
SE
S P 0
OB 12.2753374 18.33005478 I
OS 12.28273388 18.33097934
OS 12.57951764 18.33097934
OS 12.57951764 17.69118382
OS 12.49445812 17.69118382
OS 12.49445812 17.97502374
OS 12.38536004 17.97502374
OS 12.37518988 17.97409918
OS 12.3677934 17.97409918
OS 12.36132148 17.97317462
OS 12.35669868 17.97225006
OS 12.35300044 17.97225006
OS 12.35115132 17.9713255
OS 12.35022676 17.9713255
OS 12.3354338 17.9667027
OS 12.32896188 17.96392902
OS 12.32341452 17.96115534
OS 12.31786716 17.95838166
OS 12.31416892 17.95653254
OS 12.3123198 17.95560798
OS 12.31139524 17.95468342
OS 12.30399876 17.94913606
OS 12.29660228 17.94266414
OS 12.28273388 17.92879574
OS 12.27626196 17.92232382
OS 12.27163916 17.91677646
OS 12.26886548 17.91307822
OS 12.26794092 17.91215366
OS 12.25869532 17.89920982
OS 12.24852516 17.88534142
OS 12.238355 17.87054846
OS 12.22818484 17.85668006
OS 12.2198638 17.84373622
OS 12.21339188 17.83356606
OS 12.2106182 17.82986782
OS 12.20876908 17.82709414
OS 12.20691996 17.82524502
OS 12.20691996 17.82432046
OS 12.122785 17.69118382
OS 12.01738516 17.69118382
OS 12.1274078 17.8650011
OS 12.14035164 17.8834923
OS 12.15237092 17.90013438
OS 12.1643902 17.91400278
OS 12.17456036 17.92694662
OS 12.18380596 17.93619222
OS 12.19120244 17.9435887
OS 12.19582524 17.9482115
OS 12.19767436 17.95006062
OS 12.20507084 17.95560798
OS 12.21339188 17.9620799
OS 12.23003396 17.97225006
OS 12.23743044 17.9759483
OS 12.2429778 17.97964654
OS 12.24667604 17.98149566
OS 12.24852516 17.98242022
OS 12.23188308 17.9851939
OS 12.21616556 17.98796758
OS 12.20229716 17.99259038
OS 12.18842876 17.99628862
OS 12.17640948 18.00091142
OS 12.16531476 18.00645878
OS 12.1551446 18.01108158
OS 12.145899 18.01570438
OS 12.13850252 18.02125174
OS 12.13110604 18.02587454
OS 12.12555868 18.02957278
OS 12.12093588 18.03327102
OS 12.11723764 18.0360447
OS 12.11446396 18.03881838
OS 12.1135394 18.03974294
OS 12.11261484 18.0406675
OS 12.10521836 18.0499131
OS 12.09782188 18.0591587
OS 12.08672716 18.07857446
OS 12.07933068 18.09799022
OS 12.07378332 18.11648142
OS 12.07008508 18.13219894
OS 12.06916052 18.13867086
OS 12.06916052 18.14514278
OS 12.06823596 18.14976558
OS 12.06823596 18.15346382
OS 12.06823596 18.15531294
OS 12.06823596 18.1562375
OS 12.06916052 18.17565326
OS 12.0719342 18.1932199
OS 12.076557 18.20986198
OS 12.0811798 18.22373038
OS 12.08672716 18.23574966
OS 12.0904254 18.24499526
OS 12.09412364 18.25054262
OS 12.0950482 18.25146718
OS 12.0950482 18.25239174
OS 12.10614292 18.2671847
OS 12.11723764 18.28012854
OS 12.12925692 18.29122326
OS 12.14035164 18.2995443
OS 12.1505218 18.30601622
OS 12.15884284 18.30971446
OS 12.1643902 18.31248814
OS 12.16531476 18.3134127
OS 12.16623932 18.3134127
OS 12.17456036 18.31618638
OS 12.18473052 18.31896006
OS 12.20507084 18.32358286
OS 12.22726028 18.32635654
OS 12.2476006 18.32913022
OS 12.26701636 18.33005478
OS 12.2753374 18.33005478
OE
OB 11.637391 17.91677646 I
OS 11.637391 18.33097934
OS 11.70118564 18.33097934
OS 11.99427116 17.91677646
OS 11.99427116 17.84466078
OS 11.7159786 17.84466078
OS 11.7159786 17.69118382
OS 11.637391 17.69118382
OS 11.637391 17.84466078
OS 11.55048236 17.84466078
OS 11.55048236 17.91677646
OS 11.637391 17.91677646
OE
OB 11.7159786 18.20339006 H
OS 11.7159786 17.91677646
OS 11.91753268 17.91677646
OS 11.7159786 18.20339006
OE
OB 12.29290404 18.25978822 H
OS 12.26794092 18.25886366
OS 12.24667604 18.25516542
OS 12.22818484 18.25054262
OS 12.21431644 18.24499526
OS 12.20229716 18.2394479
OS 12.19490068 18.2348251
OS 12.19027788 18.23112686
OS 12.18842876 18.2302023
OS 12.17733404 18.21818302
OS 12.169013 18.20616374
OS 12.16346564 18.1932199
OS 12.15884284 18.18212518
OS 12.15699372 18.17103046
OS 12.15606916 18.16270942
OS 12.1551446 18.15716206
OS 12.1551446 18.1562375
OS 12.1551446 18.15531294
OS 12.15606916 18.14421822
OS 12.15791828 18.1331235
OS 12.16069196 18.1238779
OS 12.16346564 18.11555686
OS 12.16716388 18.10816038
OS 12.16993756 18.10261302
OS 12.17178668 18.09891478
OS 12.17271124 18.09799022
OS 12.17918316 18.08874462
OS 12.1875042 18.08042358
OS 12.19582524 18.07395166
OS 12.20414628 18.0684043
OS 12.21154276 18.06470606
OS 12.21709012 18.06193238
OS 12.22078836 18.06008326
OS 12.22263748 18.0591587
OS 12.23558132 18.05546046
OS 12.25037428 18.05268678
OS 12.26516724 18.05083766
OS 12.2799602 18.0499131
OS 12.29290404 18.04898854
OS 12.30399876 18.04806398
OS 12.49445812 18.04806398
OS 12.49445812 18.25978822
OS 12.29290404 18.25978822
OE
SE
S P 0
OB 14.33057332 12.72006854 I
OS 14.33704524 12.7209931
OS 14.34629084 12.7209931
OS 14.37680132 12.71914398
OS 14.40638724 12.71452118
OS 14.43227492 12.70897382
OS 14.4442942 12.70527558
OS 14.45538892 12.70157734
OS 14.46555908 12.6978791
OS 14.47480468 12.69418086
OS 14.48220116 12.69140718
OS 14.48959764 12.6886335
OS 14.49422044 12.68585982
OS 14.49791868 12.6840107
OS 14.50069236 12.68308614
OS 14.50161692 12.68216158
OS 14.52658004 12.66644406
OS 14.54784492 12.64795286
OS 14.56633612 12.62946166
OS 14.58205364 12.61097046
OS 14.59407292 12.59432838
OS 14.59869572 12.5869319
OS 14.60239396 12.58045998
OS 14.6060922 12.57583718
OS 14.60794132 12.57213894
OS 14.60886588 12.56936526
OS 14.60979044 12.5684407
OS 14.62273428 12.53977934
OS 14.63197988 12.51019342
OS 14.6384518 12.4806075
OS 14.6430746 12.45379526
OS 14.64492372 12.44177598
OS 14.64584828 12.4297567
OS 14.64677284 12.4205111
OS 14.64677284 12.4112655
OS 14.6476974 12.40479358
OS 14.6476974 12.39924622
OS 14.6476974 12.39554798
OS 14.6476974 12.39462342
OS 14.64584828 12.36133926
OS 14.64215004 12.32897966
OS 14.63752724 12.3003183
OS 14.633829 12.2864499
OS 14.63105532 12.27443062
OS 14.62828164 12.2633359
OS 14.6245834 12.25316574
OS 14.62180972 12.24392014
OS 14.6199606 12.23652366
OS 14.61718692 12.2309763
OS 14.61626236 12.2263535
OS 14.61441324 12.22357982
OS 14.61441324 12.22265526
OS 14.60054484 12.19491846
OS 14.58482732 12.16995534
OS 14.56818524 12.14869046
OS 14.5598642 12.14036942
OS 14.55246772 12.13204838
OS 14.54507124 12.1246519
OS 14.53767476 12.11817998
OS 14.53120284 12.11263262
OS 14.52565548 12.10893438
OS 14.52195724 12.10523614
OS 14.518259 12.10246246
OS 14.51640988 12.1015379
OS 14.51548532 12.10061334
OS 14.50254148 12.09321686
OS 14.48959764 12.08674494
OS 14.46186084 12.07657478
OS 14.43412404 12.0691783
OS 14.4073118 12.0645555
OS 14.39436796 12.06270638
OS 14.38327324 12.06085726
OS 14.37310308 12.0599327
OS 14.36478204 12.0599327
OS 14.35738556 12.05900814
OS 14.3472154 12.05900814
OS 14.3287242 12.0599327
OS 14.31115756 12.06178182
OS 14.29451548 12.06363094
OS 14.27879796 12.06732918
OS 14.264005 12.07195198
OS 14.2501366 12.07657478
OS 14.23719276 12.08119758
OS 14.22517348 12.08674494
OS 14.21500332 12.09136774
OS 14.20483316 12.09599054
OS 14.19743668 12.10061334
OS 14.1900402 12.10523614
OS 14.1854174 12.10893438
OS 14.1807946 12.1107835
OS 14.17894548 12.11263262
OS 14.17802092 12.11355718
OS 14.16507708 12.1246519
OS 14.15398236 12.13574662
OS 14.1438122 12.14869046
OS 14.13364204 12.1616343
OS 14.11699996 12.18752198
OS 14.10405612 12.21340966
OS 14.09850876 12.22542894
OS 14.09388596 12.23652366
OS 14.09018772 12.24669382
OS 14.08741404 12.25501486
OS 14.08464036 12.26241134
OS 14.08279124 12.2679587
OS 14.08186668 12.27165694
OS 14.08186668 12.2725815
OS 14.1669262 12.29384638
OS 14.17062444 12.27905342
OS 14.17524724 12.26518502
OS 14.17987004 12.25224118
OS 14.18449284 12.2402219
OS 14.1900402 12.22912718
OS 14.19558756 12.21988158
OS 14.20205948 12.21063598
OS 14.20760684 12.20231494
OS 14.21222964 12.19491846
OS 14.217777 12.1893711
OS 14.2223998 12.18382374
OS 14.22609804 12.17920094
OS 14.22979628 12.17642726
OS 14.23256996 12.17365358
OS 14.23349452 12.17272902
OS 14.23441908 12.17180446
OS 14.24366468 12.16440798
OS 14.25383484 12.15886062
OS 14.27417516 12.14869046
OS 14.29359092 12.14129398
OS 14.31300668 12.13667118
OS 14.32964876 12.13297294
OS 14.33612068 12.13204838
OS 14.3425926 12.13204838
OS 14.34813996 12.13112382
OS 14.35461188 12.13112382
OS 14.37587676 12.13204838
OS 14.39621708 12.13574662
OS 14.41470828 12.14036942
OS 14.43135036 12.14591678
OS 14.4442942 12.15146414
OS 14.44984156 12.15423782
OS 14.45446436 12.15608694
OS 14.4581626 12.15793606
OS 14.46093628 12.15978518
OS 14.4627854 12.16070974
OS 14.46370996 12.16070974
OS 14.4812766 12.17365358
OS 14.49606956 12.18752198
OS 14.5090134 12.2032395
OS 14.51918356 12.21803246
OS 14.5275046 12.2309763
OS 14.53305196 12.24207102
OS 14.53490108 12.24669382
OS 14.5367502 12.2494675
OS 14.53767476 12.25131662
OS 14.53767476 12.25224118
OS 14.54507124 12.27627974
OS 14.5506186 12.3003183
OS 14.5552414 12.32435686
OS 14.55801508 12.3465463
OS 14.55893964 12.35671646
OS 14.5598642 12.36596206
OS 14.5598642 12.3742831
OS 14.56078876 12.38075502
OS 14.56078876 12.38630238
OS 14.56078876 12.39092518
OS 14.56078876 12.39369886
OS 14.56078876 12.39462342
OS 14.5598642 12.41866198
OS 14.55801508 12.44085142
OS 14.55431684 12.46119174
OS 14.5506186 12.47968294
OS 14.54784492 12.49540046
OS 14.5459958 12.50187238
OS 14.54414668 12.50741974
OS 14.54322212 12.51204254
OS 14.54229756 12.51481622
OS 14.541373 12.51666534
OS 14.541373 12.5175899
OS 14.5321274 12.53885478
OS 14.52195724 12.55827054
OS 14.51086252 12.57398806
OS 14.49884324 12.58785646
OS 14.48867308 12.59895118
OS 14.48035204 12.60634766
OS 14.47388012 12.61097046
OS 14.47295556 12.61281958
OS 14.472031 12.61281958
OS 14.45261524 12.62483886
OS 14.43135036 12.63408446
OS 14.41101004 12.64055638
OS 14.39159428 12.64425462
OS 14.37402764 12.6470283
OS 14.36663116 12.64795286
OS 14.36015924 12.64795286
OS 14.35553644 12.64887742
OS 14.34813996 12.64887742
OS 14.32502596 12.64795286
OS 14.30376108 12.64425462
OS 14.28619444 12.63870726
OS 14.27047692 12.6331599
OS 14.25845764 12.62668798
OS 14.24921204 12.62206518
OS 14.24366468 12.61836694
OS 14.24181556 12.61651782
OS 14.2270226 12.60264942
OS 14.2131542 12.5869319
OS 14.20205948 12.57028982
OS 14.19281388 12.55364774
OS 14.1854174 12.53885478
OS 14.18264372 12.5314583
OS 14.1807946 12.52591094
OS 14.17894548 12.52128814
OS 14.17709636 12.5175899
OS 14.1761718 12.51574078
OS 14.1761718 12.51481622
OS 14.0929614 12.53423198
OS 14.09850876 12.55087406
OS 14.10405612 12.56566702
OS 14.1114526 12.57953542
OS 14.11792452 12.59340382
OS 14.125321 12.6054231
OS 14.13364204 12.61651782
OS 14.14103852 12.62761254
OS 14.148435 12.63685814
OS 14.15583148 12.64425462
OS 14.1623034 12.6516511
OS 14.16877532 12.65812302
OS 14.17339812 12.66274582
OS 14.17802092 12.66736862
OS 14.18171916 12.6701423
OS 14.18356828 12.67106686
OS 14.18449284 12.67199142
OS 14.19743668 12.68031246
OS 14.21038052 12.6886335
OS 14.22332436 12.69510542
OS 14.23719276 12.70065278
OS 14.26492956 12.70897382
OS 14.28989268 12.71452118
OS 14.30191196 12.71729486
OS 14.31208212 12.71821942
OS 14.32225228 12.71914398
OS 14.33057332 12.72006854
OE
OB 13.59000076 12.63963182 I
OS 13.59000076 12.70157734
OS 14.00420364 12.70157734
OS 14.00420364 12.62576342
OS 13.6907778 12.62576342
OS 13.71296724 12.59895118
OS 13.73423212 12.57028982
OS 13.75272332 12.54255302
OS 13.77028996 12.51574078
OS 13.77768644 12.5037215
OS 13.78415836 12.49262678
OS 13.79063028 12.48245662
OS 13.79525308 12.47413558
OS 13.79895132 12.4667391
OS 13.801725 12.4621163
OS 13.80357412 12.45841806
OS 13.80449868 12.4574935
OS 13.82298988 12.4205111
OS 13.83963196 12.3835287
OS 13.85350036 12.34839542
OS 13.85904772 12.3326779
OS 13.86459508 12.31696038
OS 13.87014244 12.30309198
OS 13.87384068 12.29014814
OS 13.87753892 12.27905342
OS 13.8803126 12.26980782
OS 13.88308628 12.26148678
OS 13.8849354 12.25593942
OS 13.88585996 12.25224118
OS 13.88585996 12.25131662
OS 13.89510556 12.21340966
OS 13.8988038 12.19491846
OS 13.90157748 12.17827638
OS 13.90435116 12.16255886
OS 13.90712484 12.14684134
OS 13.90897396 12.1338975
OS 13.91082308 12.12095366
OS 13.91174764 12.10985894
OS 13.9126722 12.09968878
OS 13.91359676 12.09044318
OS 13.91359676 12.0830467
OS 13.91452132 12.07749934
OS 13.91452132 12.0738011
OS 13.91452132 12.07102742
OS 13.91452132 12.07010286
OS 13.8340846 12.07010286
OS 13.83131092 12.10523614
OS 13.82668812 12.13759574
OS 13.82206532 12.16718166
OS 13.81929164 12.18105006
OS 13.81651796 12.1939939
OS 13.81466884 12.20508862
OS 13.81189516 12.21525878
OS 13.81004604 12.22450438
OS 13.80819692 12.23190086
OS 13.8063478 12.23744822
OS 13.80542324 12.24207102
OS 13.80449868 12.2448447
OS 13.80449868 12.24576926
OS 13.79063028 12.28829902
OS 13.77583732 12.3280551
OS 13.76844084 12.34747086
OS 13.76104436 12.36596206
OS 13.75272332 12.38260414
OS 13.74532684 12.39924622
OS 13.73885492 12.41403918
OS 13.732383 12.42698302
OS 13.72683564 12.43807774
OS 13.72221284 12.4482479
OS 13.71759004 12.45656894
OS 13.71481636 12.4621163
OS 13.71296724 12.46581454
OS 13.71204268 12.4667391
OS 13.70094796 12.48615486
OS 13.68985324 12.50557062
OS 13.67875852 12.52313726
OS 13.6676638 12.53977934
OS 13.65749364 12.5545723
OS 13.64732348 12.56936526
OS 13.63715332 12.5823091
OS 13.62883228 12.59340382
OS 13.62051124 12.60449854
OS 13.61311476 12.61374414
OS 13.60571828 12.62114062
OS 13.60017092 12.62761254
OS 13.59647268 12.6331599
OS 13.59277444 12.63685814
OS 13.59092532 12.63870726
OS 13.59000076 12.63963182
OE
SE
S P 0
OB 13.78831888 7.7117448 I
OS 13.79386624 7.71266936
OS 13.80218728 7.71266936
OS 13.81698024 7.7117448
OS 13.8317732 7.71082024
OS 13.85766088 7.70527288
OS 13.86968016 7.70157464
OS 13.88077488 7.6978764
OS 13.89094504 7.6932536
OS 13.90019064 7.6886308
OS 13.90758712 7.684008
OS 13.9149836 7.6793852
OS 13.92145552 7.67568696
OS 13.92607832 7.67198872
OS 13.92977656 7.66921504
OS 13.93255024 7.66644136
OS 13.93439936 7.6655168
OS 13.93532392 7.66459224
OS 13.94364496 7.65534664
OS 13.951966 7.64610104
OS 13.95843792 7.63593088
OS 13.96398528 7.62576072
OS 13.97323088 7.60634496
OS 13.97877824 7.58785376
OS 13.98247648 7.57213624
OS 13.98340104 7.56473976
OS 13.9843256 7.5591924
OS 13.98525016 7.55364504
OS 13.98525016 7.5499468
OS 13.98525016 7.54809768
OS 13.98525016 7.54717312
OS 13.9843256 7.53053104
OS 13.98155192 7.51481352
OS 13.97785368 7.50094512
OS 13.97323088 7.48892584
OS 13.96953264 7.47968024
OS 13.9658344 7.47228376
OS 13.96306072 7.46858552
OS 13.96213616 7.4667364
OS 13.951966 7.45564168
OS 13.94087128 7.44547152
OS 13.928852 7.43622592
OS 13.91683272 7.42882944
OS 13.905738 7.42328208
OS 13.89741696 7.41958384
OS 13.89371872 7.41773472
OS 13.89094504 7.41681016
OS 13.89002048 7.4158856
OS 13.88909592 7.4158856
OS 13.9103608 7.40941368
OS 13.92792744 7.40109264
OS 13.94364496 7.39092248
OS 13.9565888 7.38167688
OS 13.96675896 7.37243128
OS 13.97415544 7.3650348
OS 13.97785368 7.360412
OS 13.9797028 7.35948744
OS 13.9797028 7.35856288
OS 13.98987296 7.3419208
OS 13.998194 7.32435416
OS 14.00374136 7.30771208
OS 14.0074396 7.29107
OS 14.00928872 7.27627704
OS 14.01021328 7.26980512
OS 14.01021328 7.26425776
OS 14.01113784 7.26055952
OS 14.01113784 7.25686128
OS 14.01113784 7.25501216
OS 14.01113784 7.2540876
OS 14.01021328 7.23929464
OS 14.00836416 7.22450168
OS 14.00559048 7.21063328
OS 14.00189224 7.19676488
OS 13.99264664 7.17365088
OS 13.98802384 7.16255616
OS 13.98247648 7.15331056
OS 13.97692912 7.14406496
OS 13.97230632 7.13666848
OS 13.96675896 7.13019656
OS 13.96306072 7.1246492
OS 13.95936248 7.1200264
OS 13.9565888 7.11725272
OS 13.95473968 7.1154036
OS 13.95381512 7.11447904
OS 13.9427204 7.10430888
OS 13.93070112 7.09598784
OS 13.91775728 7.08859136
OS 13.90481344 7.08211944
OS 13.89279416 7.07749664
OS 13.87985032 7.07287384
OS 13.8548872 7.06640192
OS 13.84379248 7.06362824
OS 13.83362232 7.06177912
OS 13.82437672 7.06085456
OS 13.81605568 7.05993
OS 13.80958376 7.05900544
OS 13.80033816 7.05900544
OS 13.78277152 7.05993
OS 13.767054 7.06177912
OS 13.75133648 7.0645528
OS 13.73654352 7.06732648
OS 13.72359968 7.07194928
OS 13.71065584 7.07657208
OS 13.69863656 7.08119488
OS 13.6884664 7.08674224
OS 13.6792208 7.0922896
OS 13.67089976 7.0969124
OS 13.66442784 7.1015352
OS 13.65795592 7.106158
OS 13.65333312 7.10893168
OS 13.65055944 7.11170536
OS 13.64871032 7.11355448
OS 13.64778576 7.11447904
OS 13.6376156 7.12557376
OS 13.62837 7.13666848
OS 13.62097352 7.1477632
OS 13.6145016 7.15978248
OS 13.60802968 7.1708772
OS 13.60340688 7.18289648
OS 13.59693496 7.20416136
OS 13.59416128 7.21433152
OS 13.59231216 7.22357712
OS 13.5913876 7.23189816
OS 13.59046304 7.23837008
OS 13.58953848 7.24391744
OS 13.58953848 7.24854024
OS 13.58953848 7.25131392
OS 13.58953848 7.25223848
OS 13.59046304 7.27350336
OS 13.59416128 7.29291912
OS 13.59970864 7.31048576
OS 13.605256 7.32527872
OS 13.61080336 7.337298
OS 13.61635072 7.3465436
OS 13.62004896 7.35209096
OS 13.62097352 7.35301552
OS 13.62097352 7.35394008
OS 13.63391736 7.36873304
OS 13.64778576 7.38167688
OS 13.66257872 7.39184704
OS 13.67644712 7.40109264
OS 13.68939096 7.40756456
OS 13.70048568 7.41218736
OS 13.70418392 7.41403648
OS 13.7069576 7.41496104
OS 13.70880672 7.4158856
OS 13.70973128 7.4158856
OS 13.6930892 7.42328208
OS 13.6792208 7.43160312
OS 13.66720152 7.43992416
OS 13.65703136 7.4482452
OS 13.64963488 7.45564168
OS 13.64408752 7.46118904
OS 13.64038928 7.46488728
OS 13.63946472 7.4667364
OS 13.63114368 7.47968024
OS 13.62559632 7.49262408
OS 13.62097352 7.50556792
OS 13.61819984 7.51851176
OS 13.61635072 7.52868192
OS 13.61542616 7.53700296
OS 13.61542616 7.54255032
OS 13.61542616 7.54347488
OS 13.61542616 7.54439944
OS 13.61635072 7.55734328
OS 13.61727528 7.56936256
OS 13.6237472 7.59247656
OS 13.63206824 7.61281688
OS 13.64131384 7.63038352
OS 13.65055944 7.64425192
OS 13.65518224 7.64979928
OS 13.65888048 7.65534664
OS 13.66257872 7.65904488
OS 13.6653524 7.66181856
OS 13.66627696 7.66274312
OS 13.66720152 7.66366768
OS 13.67737168 7.67198872
OS 13.68754184 7.68030976
OS 13.69863656 7.68678168
OS 13.70973128 7.69232904
OS 13.73192072 7.70065008
OS 13.75411016 7.70619744
OS 13.76335576 7.70897112
OS 13.77260136 7.70989568
OS 13.7809224 7.71082024
OS 13.78831888 7.7117448
OE
OB 14.3310356 7.72006584 I
OS 14.33750752 7.7209904
OS 14.34675312 7.7209904
OS 14.3772636 7.71914128
OS 14.40684952 7.71451848
OS 14.4327372 7.70897112
OS 14.44475648 7.70527288
OS 14.4558512 7.70157464
OS 14.46602136 7.6978764
OS 14.47526696 7.69417816
OS 14.48266344 7.69140448
OS 14.49005992 7.6886308
OS 14.49468272 7.68585712
OS 14.49838096 7.684008
OS 14.50115464 7.68308344
OS 14.5020792 7.68215888
OS 14.52704232 7.66644136
OS 14.5483072 7.64795016
OS 14.5667984 7.62945896
OS 14.58251592 7.61096776
OS 14.5945352 7.59432568
OS 14.599158 7.5869292
OS 14.60285624 7.58045728
OS 14.60655448 7.57583448
OS 14.6084036 7.57213624
OS 14.60932816 7.56936256
OS 14.61025272 7.568438
OS 14.62319656 7.53977664
OS 14.63244216 7.51019072
OS 14.63891408 7.4806048
OS 14.64353688 7.45379256
OS 14.645386 7.44177328
OS 14.64631056 7.429754
OS 14.64723512 7.4205084
OS 14.64723512 7.4112628
OS 14.64815968 7.40479088
OS 14.64815968 7.39924352
OS 14.64815968 7.39554528
OS 14.64815968 7.39462072
OS 14.64631056 7.36133656
OS 14.64261232 7.32897696
OS 14.63798952 7.3003156
OS 14.63429128 7.2864472
OS 14.6315176 7.27442792
OS 14.62874392 7.2633332
OS 14.62504568 7.25316304
OS 14.622272 7.24391744
OS 14.62042288 7.23652096
OS 14.6176492 7.2309736
OS 14.61672464 7.2263508
OS 14.61487552 7.22357712
OS 14.61487552 7.22265256
OS 14.60100712 7.19491576
OS 14.5852896 7.16995264
OS 14.56864752 7.14868776
OS 14.56032648 7.14036672
OS 14.55293 7.13204568
OS 14.54553352 7.1246492
OS 14.53813704 7.11817728
OS 14.53166512 7.11262992
OS 14.52611776 7.10893168
OS 14.52241952 7.10523344
OS 14.51872128 7.10245976
OS 14.51687216 7.1015352
OS 14.5159476 7.10061064
OS 14.50300376 7.09321416
OS 14.49005992 7.08674224
OS 14.46232312 7.07657208
OS 14.43458632 7.0691756
OS 14.40777408 7.0645528
OS 14.39483024 7.06270368
OS 14.38373552 7.06085456
OS 14.37356536 7.05993
OS 14.36524432 7.05993
OS 14.35784784 7.05900544
OS 14.34767768 7.05900544
OS 14.32918648 7.05993
OS 14.31161984 7.06177912
OS 14.29497776 7.06362824
OS 14.27926024 7.06732648
OS 14.26446728 7.07194928
OS 14.25059888 7.07657208
OS 14.23765504 7.08119488
OS 14.22563576 7.08674224
OS 14.2154656 7.09136504
OS 14.20529544 7.09598784
OS 14.19789896 7.10061064
OS 14.19050248 7.10523344
OS 14.18587968 7.10893168
OS 14.18125688 7.1107808
OS 14.17940776 7.11262992
OS 14.1784832 7.11355448
OS 14.16553936 7.1246492
OS 14.15444464 7.13574392
OS 14.14427448 7.14868776
OS 14.13410432 7.1616316
OS 14.11746224 7.18751928
OS 14.1045184 7.21340696
OS 14.09897104 7.22542624
OS 14.09434824 7.23652096
OS 14.09065 7.24669112
OS 14.08787632 7.25501216
OS 14.08510264 7.26240864
OS 14.08325352 7.267956
OS 14.08232896 7.27165424
OS 14.08232896 7.2725788
OS 14.16738848 7.29384368
OS 14.17108672 7.27905072
OS 14.17570952 7.26518232
OS 14.18033232 7.25223848
OS 14.18495512 7.2402192
OS 14.19050248 7.22912448
OS 14.19604984 7.21987888
OS 14.20252176 7.21063328
OS 14.20806912 7.20231224
OS 14.21269192 7.19491576
OS 14.21823928 7.1893684
OS 14.22286208 7.18382104
OS 14.22656032 7.17919824
OS 14.23025856 7.17642456
OS 14.23303224 7.17365088
OS 14.2339568 7.17272632
OS 14.23488136 7.17180176
OS 14.24412696 7.16440528
OS 14.25429712 7.15885792
OS 14.27463744 7.14868776
OS 14.2940532 7.14129128
OS 14.31346896 7.13666848
OS 14.33011104 7.13297024
OS 14.33658296 7.13204568
OS 14.34305488 7.13204568
OS 14.34860224 7.13112112
OS 14.35507416 7.13112112
OS 14.37633904 7.13204568
OS 14.39667936 7.13574392
OS 14.41517056 7.14036672
OS 14.43181264 7.14591408
OS 14.44475648 7.15146144
OS 14.45030384 7.15423512
OS 14.45492664 7.15608424
OS 14.45862488 7.15793336
OS 14.46139856 7.15978248
OS 14.46324768 7.16070704
OS 14.46417224 7.16070704
OS 14.48173888 7.17365088
OS 14.49653184 7.18751928
OS 14.50947568 7.2032368
OS 14.51964584 7.21802976
OS 14.52796688 7.2309736
OS 14.53351424 7.24206832
OS 14.53536336 7.24669112
OS 14.53721248 7.2494648
OS 14.53813704 7.25131392
OS 14.53813704 7.25223848
OS 14.54553352 7.27627704
OS 14.55108088 7.3003156
OS 14.55570368 7.32435416
OS 14.55847736 7.3465436
OS 14.55940192 7.35671376
OS 14.56032648 7.36595936
OS 14.56032648 7.3742804
OS 14.56125104 7.38075232
OS 14.56125104 7.38629968
OS 14.56125104 7.39092248
OS 14.56125104 7.39369616
OS 14.56125104 7.39462072
OS 14.56032648 7.41865928
OS 14.55847736 7.44084872
OS 14.55477912 7.46118904
OS 14.55108088 7.47968024
OS 14.5483072 7.49539776
OS 14.54645808 7.50186968
OS 14.54460896 7.50741704
OS 14.5436844 7.51203984
OS 14.54275984 7.51481352
OS 14.54183528 7.51666264
OS 14.54183528 7.5175872
OS 14.53258968 7.53885208
OS 14.52241952 7.55826784
OS 14.5113248 7.57398536
OS 14.49930552 7.58785376
OS 14.48913536 7.59894848
OS 14.48081432 7.60634496
OS 14.4743424 7.61096776
OS 14.47341784 7.61281688
OS 14.47249328 7.61281688
OS 14.45307752 7.62483616
OS 14.43181264 7.63408176
OS 14.41147232 7.64055368
OS 14.39205656 7.64425192
OS 14.37448992 7.6470256
OS 14.36709344 7.64795016
OS 14.36062152 7.64795016
OS 14.35599872 7.64887472
OS 14.34860224 7.64887472
OS 14.32548824 7.64795016
OS 14.30422336 7.64425192
OS 14.28665672 7.63870456
OS 14.2709392 7.6331572
OS 14.25891992 7.62668528
OS 14.24967432 7.62206248
OS 14.24412696 7.61836424
OS 14.24227784 7.61651512
OS 14.22748488 7.60264672
OS 14.21361648 7.5869292
OS 14.20252176 7.57028712
OS 14.19327616 7.55364504
OS 14.18587968 7.53885208
OS 14.183106 7.5314556
OS 14.18125688 7.52590824
OS 14.17940776 7.52128544
OS 14.17755864 7.5175872
OS 14.17663408 7.51573808
OS 14.17663408 7.51481352
OS 14.09342368 7.53422928
OS 14.09897104 7.55087136
OS 14.1045184 7.56566432
OS 14.11191488 7.57953272
OS 14.1183868 7.59340112
OS 14.12578328 7.6054204
OS 14.13410432 7.61651512
OS 14.1415008 7.62760984
OS 14.14889728 7.63685544
OS 14.15629376 7.64425192
OS 14.16276568 7.6516484
OS 14.1692376 7.65812032
OS 14.1738604 7.66274312
OS 14.1784832 7.66736592
OS 14.18218144 7.6701396
OS 14.18403056 7.67106416
OS 14.18495512 7.67198872
OS 14.19789896 7.68030976
OS 14.2108428 7.6886308
OS 14.22378664 7.69510272
OS 14.23765504 7.70065008
OS 14.26539184 7.70897112
OS 14.29035496 7.71451848
OS 14.30237424 7.71729216
OS 14.3125444 7.71821672
OS 14.32271456 7.71914128
OS 14.3310356 7.72006584
OE
OB 13.80033816 7.64795016 H
OS 13.78462064 7.6470256
OS 13.76982768 7.64332736
OS 13.7578084 7.63870456
OS 13.74671368 7.6331572
OS 13.73839264 7.62760984
OS 13.73192072 7.62298704
OS 13.72729792 7.6192888
OS 13.72637336 7.61836424
OS 13.7162032 7.60634496
OS 13.70880672 7.59432568
OS 13.70325936 7.5823064
OS 13.69956112 7.57121168
OS 13.697712 7.56104152
OS 13.69586288 7.55272048
OS 13.69586288 7.54717312
OS 13.69586288 7.54624856
OS 13.69586288 7.545324
OS 13.69678744 7.53053104
OS 13.70048568 7.51666264
OS 13.70510848 7.50464336
OS 13.71065584 7.4944732
OS 13.7162032 7.48615216
OS 13.720826 7.4806048
OS 13.72452424 7.475982
OS 13.7254488 7.47505744
OS 13.73654352 7.46581184
OS 13.74948736 7.45841536
OS 13.76150664 7.45379256
OS 13.77352592 7.45009432
OS 13.78462064 7.4482452
OS 13.79294168 7.44732064
OS 13.79848904 7.44639608
OS 13.80033816 7.44639608
OS 13.81698024 7.44732064
OS 13.8317732 7.45101888
OS 13.84471704 7.45564168
OS 13.85581176 7.46118904
OS 13.8641328 7.46581184
OS 13.87060472 7.47043464
OS 13.87522752 7.47413288
OS 13.87615208 7.47505744
OS 13.88539768 7.48615216
OS 13.89279416 7.499096
OS 13.89741696 7.51111528
OS 13.9011152 7.52313456
OS 13.90296432 7.53330472
OS 13.90388888 7.54162576
OS 13.90481344 7.54717312
OS 13.90481344 7.54809768
OS 13.90481344 7.54902224
OS 13.90388888 7.5638152
OS 13.90019064 7.57675904
OS 13.89556784 7.58877832
OS 13.89002048 7.59894848
OS 13.88539768 7.60726952
OS 13.88077488 7.61374144
OS 13.87707664 7.61743968
OS 13.87615208 7.61836424
OS 13.8641328 7.6285344
OS 13.85211352 7.63593088
OS 13.83916968 7.64055368
OS 13.8271504 7.64425192
OS 13.81605568 7.64610104
OS 13.80773464 7.64795016
OS 13.80033816 7.64795016
OE
OB 13.80311184 7.38260144 H
OS 13.78277152 7.38075232
OS 13.76428032 7.37705408
OS 13.74763824 7.37058216
OS 13.73376984 7.36411024
OS 13.72267512 7.35671376
OS 13.71435408 7.35024184
OS 13.70973128 7.3465436
OS 13.70788216 7.34469448
OS 13.69493832 7.32990152
OS 13.68569272 7.314184
OS 13.6792208 7.29846648
OS 13.674598 7.28459808
OS 13.67182432 7.27072968
OS 13.67089976 7.26055952
OS 13.6699752 7.25686128
OS 13.6699752 7.2540876
OS 13.6699752 7.25223848
OS 13.6699752 7.25131392
OS 13.67182432 7.23189816
OS 13.67552256 7.21340696
OS 13.68199448 7.19768944
OS 13.6884664 7.1847456
OS 13.69493832 7.17457544
OS 13.70141024 7.1662544
OS 13.70510848 7.1616316
OS 13.7069576 7.15978248
OS 13.72175056 7.1477632
OS 13.73654352 7.1385176
OS 13.75226104 7.13297024
OS 13.767054 7.12834744
OS 13.77999784 7.12557376
OS 13.79109256 7.1246492
OS 13.7947908 7.12372464
OS 13.80033816 7.12372464
OS 13.813282 7.1246492
OS 13.82622584 7.12649832
OS 13.83824512 7.129272
OS 13.84841528 7.13204568
OS 13.85673632 7.13481936
OS 13.86320824 7.13759304
OS 13.86690648 7.13944216
OS 13.8687556 7.14036672
OS 13.87985032 7.1477632
OS 13.88909592 7.15515968
OS 13.89741696 7.16348072
OS 13.90388888 7.17180176
OS 13.90943624 7.17827368
OS 13.91313448 7.18382104
OS 13.9149836 7.18844384
OS 13.91590816 7.1893684
OS 13.92053096 7.20138768
OS 13.9242292 7.2124824
OS 13.92700288 7.22357712
OS 13.928852 7.23374728
OS 13.92977656 7.24206832
OS 13.93070112 7.24854024
OS 13.93070112 7.25223848
OS 13.93070112 7.2540876
OS 13.928852 7.27350336
OS 13.92515376 7.29107
OS 13.9196064 7.30678752
OS 13.91220992 7.32065592
OS 13.905738 7.33082608
OS 13.90019064 7.33914712
OS 13.8964924 7.34376992
OS 13.89464328 7.34561904
OS 13.88077488 7.35763832
OS 13.86505736 7.36688392
OS 13.8502644 7.37335584
OS 13.83547144 7.37797864
OS 13.8225276 7.38075232
OS 13.81235744 7.38167688
OS 13.8086592 7.38260144
OS 13.80311184 7.38260144
OE
SE
S P 0
OB 14.33288472 10.12006612 I
OS 14.33935664 10.12099068
OS 14.34860224 10.12099068
OS 14.37911272 10.11914156
OS 14.40869864 10.11451876
OS 14.43458632 10.1089714
OS 14.4466056 10.10527316
OS 14.45770032 10.10157492
OS 14.46787048 10.09787668
OS 14.47711608 10.09417844
OS 14.48451256 10.09140476
OS 14.49190904 10.08863108
OS 14.49653184 10.0858574
OS 14.50023008 10.08400828
OS 14.50300376 10.08308372
OS 14.50392832 10.08215916
OS 14.52889144 10.06644164
OS 14.55015632 10.04795044
OS 14.56864752 10.02945924
OS 14.58436504 10.01096804
OS 14.59638432 9.99432596
OS 14.60100712 9.98692948
OS 14.60470536 9.98045756
OS 14.6084036 9.97583476
OS 14.61025272 9.97213652
OS 14.61117728 9.96936284
OS 14.61210184 9.96843828
OS 14.62504568 9.93977692
OS 14.63429128 9.910191
OS 14.6407632 9.88060508
OS 14.645386 9.85379284
OS 14.64723512 9.84177356
OS 14.64815968 9.82975428
OS 14.64908424 9.82050868
OS 14.64908424 9.81126308
OS 14.6500088 9.80479116
OS 14.6500088 9.7992438
OS 14.6500088 9.79554556
OS 14.6500088 9.794621
OS 14.64815968 9.76133684
OS 14.64446144 9.72897724
OS 14.63983864 9.70031588
OS 14.6361404 9.68644748
OS 14.63336672 9.6744282
OS 14.63059304 9.66333348
OS 14.6268948 9.65316332
OS 14.62412112 9.64391772
OS 14.622272 9.63652124
OS 14.61949832 9.63097388
OS 14.61857376 9.62635108
OS 14.61672464 9.6235774
OS 14.61672464 9.62265284
OS 14.60285624 9.59491604
OS 14.58713872 9.56995292
OS 14.57049664 9.54868804
OS 14.5621756 9.540367
OS 14.55477912 9.53204596
OS 14.54738264 9.52464948
OS 14.53998616 9.51817756
OS 14.53351424 9.5126302
OS 14.52796688 9.50893196
OS 14.52426864 9.50523372
OS 14.5205704 9.50246004
OS 14.51872128 9.50153548
OS 14.51779672 9.50061092
OS 14.50485288 9.49321444
OS 14.49190904 9.48674252
OS 14.46417224 9.47657236
OS 14.43643544 9.46917588
OS 14.4096232 9.46455308
OS 14.39667936 9.46270396
OS 14.38558464 9.46085484
OS 14.37541448 9.45993028
OS 14.36709344 9.45993028
OS 14.35969696 9.45900572
OS 14.3495268 9.45900572
OS 14.3310356 9.45993028
OS 14.31346896 9.4617794
OS 14.29682688 9.46362852
OS 14.28110936 9.46732676
OS 14.2663164 9.47194956
OS 14.252448 9.47657236
OS 14.23950416 9.48119516
OS 14.22748488 9.48674252
OS 14.21731472 9.49136532
OS 14.20714456 9.49598812
OS 14.19974808 9.50061092
OS 14.1923516 9.50523372
OS 14.1877288 9.50893196
OS 14.183106 9.51078108
OS 14.18125688 9.5126302
OS 14.18033232 9.51355476
OS 14.16738848 9.52464948
OS 14.15629376 9.5357442
OS 14.1461236 9.54868804
OS 14.13595344 9.56163188
OS 14.11931136 9.58751956
OS 14.10636752 9.61340724
OS 14.10082016 9.62542652
OS 14.09619736 9.63652124
OS 14.09249912 9.6466914
OS 14.08972544 9.65501244
OS 14.08695176 9.66240892
OS 14.08510264 9.66795628
OS 14.08417808 9.67165452
OS 14.08417808 9.67257908
OS 14.1692376 9.69384396
OS 14.17293584 9.679051
OS 14.17755864 9.6651826
OS 14.18218144 9.65223876
OS 14.18680424 9.64021948
OS 14.1923516 9.62912476
OS 14.19789896 9.61987916
OS 14.20437088 9.61063356
OS 14.20991824 9.60231252
OS 14.21454104 9.59491604
OS 14.2200884 9.58936868
OS 14.2247112 9.58382132
OS 14.22840944 9.57919852
OS 14.23210768 9.57642484
OS 14.23488136 9.57365116
OS 14.23580592 9.5727266
OS 14.23673048 9.57180204
OS 14.24597608 9.56440556
OS 14.25614624 9.5588582
OS 14.27648656 9.54868804
OS 14.29590232 9.54129156
OS 14.31531808 9.53666876
OS 14.33196016 9.53297052
OS 14.33843208 9.53204596
OS 14.344904 9.53204596
OS 14.35045136 9.5311214
OS 14.35692328 9.5311214
OS 14.37818816 9.53204596
OS 14.39852848 9.5357442
OS 14.41701968 9.540367
OS 14.43366176 9.54591436
OS 14.4466056 9.55146172
OS 14.45215296 9.5542354
OS 14.45677576 9.55608452
OS 14.460474 9.55793364
OS 14.46324768 9.55978276
OS 14.4650968 9.56070732
OS 14.46602136 9.56070732
OS 14.483588 9.57365116
OS 14.49838096 9.58751956
OS 14.5113248 9.60323708
OS 14.52149496 9.61803004
OS 14.529816 9.63097388
OS 14.53536336 9.6420686
OS 14.53721248 9.6466914
OS 14.5390616 9.64946508
OS 14.53998616 9.6513142
OS 14.53998616 9.65223876
OS 14.54738264 9.67627732
OS 14.55293 9.70031588
OS 14.5575528 9.72435444
OS 14.56032648 9.74654388
OS 14.56125104 9.75671404
OS 14.5621756 9.76595964
OS 14.5621756 9.77428068
OS 14.56310016 9.7807526
OS 14.56310016 9.78629996
OS 14.56310016 9.79092276
OS 14.56310016 9.79369644
OS 14.56310016 9.794621
OS 14.5621756 9.81865956
OS 14.56032648 9.840849
OS 14.55662824 9.86118932
OS 14.55293 9.87968052
OS 14.55015632 9.89539804
OS 14.5483072 9.90186996
OS 14.54645808 9.90741732
OS 14.54553352 9.91204012
OS 14.54460896 9.9148138
OS 14.5436844 9.91666292
OS 14.5436844 9.91758748
OS 14.5344388 9.93885236
OS 14.52426864 9.95826812
OS 14.51317392 9.97398564
OS 14.50115464 9.98785404
OS 14.49098448 9.99894876
OS 14.48266344 10.00634524
OS 14.47619152 10.01096804
OS 14.47526696 10.01281716
OS 14.4743424 10.01281716
OS 14.45492664 10.02483644
OS 14.43366176 10.03408204
OS 14.41332144 10.04055396
OS 14.39390568 10.0442522
OS 14.37633904 10.04702588
OS 14.36894256 10.04795044
OS 14.36247064 10.04795044
OS 14.35784784 10.048875
OS 14.35045136 10.048875
OS 14.32733736 10.04795044
OS 14.30607248 10.0442522
OS 14.28850584 10.03870484
OS 14.27278832 10.03315748
OS 14.26076904 10.02668556
OS 14.25152344 10.02206276
OS 14.24597608 10.01836452
OS 14.24412696 10.0165154
OS 14.229334 10.002647
OS 14.2154656 9.98692948
OS 14.20437088 9.9702874
OS 14.19512528 9.95364532
OS 14.1877288 9.93885236
OS 14.18495512 9.93145588
OS 14.183106 9.92590852
OS 14.18125688 9.92128572
OS 14.17940776 9.91758748
OS 14.1784832 9.91573836
OS 14.1784832 9.9148138
OS 14.0952728 9.93422956
OS 14.10082016 9.95087164
OS 14.10636752 9.9656646
OS 14.113764 9.979533
OS 14.12023592 9.9934014
OS 14.1276324 10.00542068
OS 14.13595344 10.0165154
OS 14.14334992 10.02761012
OS 14.1507464 10.03685572
OS 14.15814288 10.0442522
OS 14.1646148 10.05164868
OS 14.17108672 10.0581206
OS 14.17570952 10.0627434
OS 14.18033232 10.0673662
OS 14.18403056 10.07013988
OS 14.18587968 10.07106444
OS 14.18680424 10.071989
OS 14.19974808 10.08031004
OS 14.21269192 10.08863108
OS 14.22563576 10.095103
OS 14.23950416 10.10065036
OS 14.26724096 10.1089714
OS 14.29220408 10.11451876
OS 14.30422336 10.11729244
OS 14.31439352 10.118217
OS 14.32456368 10.11914156
OS 14.33288472 10.12006612
OE
OB 13.61819984 10.02668556 I
OS 13.61819984 10.10157492
OS 13.93624848 10.10157492
OS 13.998194 9.77243156
OS 13.9242292 9.7622614
OS 13.91775728 9.77243156
OS 13.90943624 9.7807526
OS 13.90203976 9.78907364
OS 13.89464328 9.79554556
OS 13.8872468 9.80016836
OS 13.88169944 9.80479116
OS 13.8780012 9.80664028
OS 13.87707664 9.80756484
OS 13.86505736 9.8131122
OS 13.85303808 9.817735
OS 13.84194336 9.82050868
OS 13.83084864 9.82328236
OS 13.82160304 9.82420692
OS 13.81420656 9.82513148
OS 13.79663992 9.82513148
OS 13.7855452 9.82328236
OS 13.76612944 9.81865956
OS 13.74948736 9.81218764
OS 13.7346944 9.80571572
OS 13.72359968 9.79831924
OS 13.71527864 9.79184732
OS 13.71065584 9.78722452
OS 13.70880672 9.78629996
OS 13.70880672 9.7853754
OS 13.69586288 9.76965788
OS 13.68661728 9.7530158
OS 13.68014536 9.73544916
OS 13.67552256 9.71788252
OS 13.67274888 9.70308956
OS 13.67182432 9.69661764
OS 13.67182432 9.69107028
OS 13.67089976 9.68644748
OS 13.67089976 9.68274924
OS 13.67089976 9.68090012
OS 13.67089976 9.67997556
OS 13.67089976 9.66703172
OS 13.67274888 9.65501244
OS 13.67737168 9.63189844
OS 13.6838436 9.61248268
OS 13.69031552 9.59676516
OS 13.697712 9.58382132
OS 13.70418392 9.57365116
OS 13.7069576 9.57087748
OS 13.70880672 9.5681038
OS 13.70973128 9.56717924
OS 13.71065584 9.56625468
OS 13.71805232 9.5588582
OS 13.7254488 9.55238628
OS 13.74209088 9.54129156
OS 13.7578084 9.53389508
OS 13.77352592 9.52927228
OS 13.78646976 9.52557404
OS 13.79756448 9.52464948
OS 13.80126272 9.52372492
OS 13.80681008 9.52372492
OS 13.82437672 9.52464948
OS 13.84009424 9.52834772
OS 13.85396264 9.53297052
OS 13.86505736 9.53851788
OS 13.87522752 9.54406524
OS 13.882624 9.54868804
OS 13.88632224 9.55238628
OS 13.88817136 9.55331084
OS 13.89926608 9.56625468
OS 13.90851168 9.58012308
OS 13.91590816 9.5958406
OS 13.92145552 9.609709
OS 13.92515376 9.6235774
OS 13.92792744 9.63374756
OS 13.928852 9.63837036
OS 13.92977656 9.64114404
OS 13.92977656 9.64299316
OS 13.92977656 9.64391772
OS 14.0120624 9.6374458
OS 14.01021328 9.62265284
OS 14.0074396 9.60878444
OS 13.99911856 9.58289676
OS 13.9889484 9.56070732
OS 13.98340104 9.55053716
OS 13.97785368 9.54221612
OS 13.97323088 9.53389508
OS 13.96768352 9.5264986
OS 13.96306072 9.52095124
OS 13.95843792 9.51632844
OS 13.95473968 9.5126302
OS 13.95289056 9.50893196
OS 13.95104144 9.5080074
OS 13.95011688 9.50708284
OS 13.93902216 9.4987618
OS 13.92792744 9.49136532
OS 13.91590816 9.4848934
OS 13.90388888 9.47934604
OS 13.88077488 9.471025
OS 13.85766088 9.46547764
OS 13.84749072 9.46270396
OS 13.83732056 9.4617794
OS 13.82899952 9.46085484
OS 13.82160304 9.45993028
OS 13.81513112 9.45900572
OS 13.80681008 9.45900572
OS 13.78739432 9.45993028
OS 13.76890312 9.46270396
OS 13.75133648 9.4664022
OS 13.73561896 9.471025
OS 13.720826 9.47749692
OS 13.7069576 9.48396884
OS 13.69401376 9.49044076
OS 13.68291904 9.49783724
OS 13.67274888 9.50523372
OS 13.66350328 9.51170564
OS 13.6561068 9.51910212
OS 13.64963488 9.52464948
OS 13.64501208 9.52927228
OS 13.64131384 9.53297052
OS 13.63946472 9.5357442
OS 13.63854016 9.53666876
OS 13.62929456 9.54868804
OS 13.62189808 9.56163188
OS 13.6145016 9.57365116
OS 13.60895424 9.586595
OS 13.59970864 9.61155812
OS 13.59416128 9.63559668
OS 13.59231216 9.64576684
OS 13.59046304 9.655937
OS 13.58953848 9.66425804
OS 13.58861392 9.67165452
OS 13.58768936 9.67812644
OS 13.58768936 9.68274924
OS 13.58768936 9.68552292
OS 13.58768936 9.68644748
OS 13.58861392 9.70308956
OS 13.59046304 9.71880708
OS 13.59323672 9.7345246
OS 13.59693496 9.748393
OS 13.60155776 9.76133684
OS 13.60618056 9.77428068
OS 13.61172792 9.7853754
OS 13.61635072 9.79554556
OS 13.62189808 9.80479116
OS 13.62744544 9.8131122
OS 13.63206824 9.81958412
OS 13.63669104 9.82605604
OS 13.64038928 9.83067884
OS 13.64316296 9.83345252
OS 13.64501208 9.83530164
OS 13.64593664 9.8362262
OS 13.65703136 9.84639636
OS 13.66812608 9.85564196
OS 13.68014536 9.86303844
OS 13.69216464 9.86951036
OS 13.70418392 9.87598228
OS 13.7162032 9.88060508
OS 13.73839264 9.887077
OS 13.7485628 9.88985068
OS 13.7578084 9.8916998
OS 13.76612944 9.89262436
OS 13.77352592 9.89354892
OS 13.77907328 9.89447348
OS 13.7994136 9.89447348
OS 13.81050832 9.89262436
OS 13.83269776 9.88800156
OS 13.85303808 9.88152964
OS 13.87152928 9.87413316
OS 13.88632224 9.86673668
OS 13.89279416 9.86303844
OS 13.89834152 9.86026476
OS 13.90296432 9.85749108
OS 13.905738 9.85564196
OS 13.90758712 9.8547174
OS 13.90851168 9.85379284
OS 13.87430296 10.02668556
OS 13.61819984 10.02668556
OE
SE
S P 0
OB 14.59533784 24.16461512 I
OS 14.60180976 24.16553968
OS 14.61105536 24.16553968
OS 14.64156584 24.16369056
OS 14.67115176 24.15906776
OS 14.69703944 24.1535204
OS 14.70905872 24.14982216
OS 14.72015344 24.14612392
OS 14.7303236 24.14242568
OS 14.7395692 24.13872744
OS 14.74696568 24.13595376
OS 14.75436216 24.13318008
OS 14.75898496 24.1304064
OS 14.7626832 24.12855728
OS 14.76545688 24.12763272
OS 14.76638144 24.12670816
OS 14.79134456 24.11099064
OS 14.81260944 24.09249944
OS 14.83110064 24.07400824
OS 14.84681816 24.05551704
OS 14.85883744 24.03887496
OS 14.86346024 24.03147848
OS 14.86715848 24.02500656
OS 14.87085672 24.02038376
OS 14.87270584 24.01668552
OS 14.8736304 24.01391184
OS 14.87455496 24.01298728
OS 14.8874988 23.98432592
OS 14.8967444 23.95474
OS 14.90321632 23.92515408
OS 14.90783912 23.89834184
OS 14.90968824 23.88632256
OS 14.9106128 23.87430328
OS 14.91153736 23.86505768
OS 14.91153736 23.85581208
OS 14.91246192 23.84934016
OS 14.91246192 23.8437928
OS 14.91246192 23.84009456
OS 14.91246192 23.83917
OS 14.9106128 23.80588584
OS 14.90691456 23.77352624
OS 14.90229176 23.74486488
OS 14.89859352 23.73099648
OS 14.89581984 23.7189772
OS 14.89304616 23.70788248
OS 14.88934792 23.69771232
OS 14.88657424 23.68846672
OS 14.88472512 23.68107024
OS 14.88195144 23.67552288
OS 14.88102688 23.67090008
OS 14.87917776 23.6681264
OS 14.87917776 23.66720184
OS 14.86530936 23.63946504
OS 14.84959184 23.61450192
OS 14.83294976 23.59323704
OS 14.82462872 23.584916
OS 14.81723224 23.57659496
OS 14.80983576 23.56919848
OS 14.80243928 23.56272656
OS 14.79596736 23.5571792
OS 14.79042 23.55348096
OS 14.78672176 23.54978272
OS 14.78302352 23.54700904
OS 14.7811744 23.54608448
OS 14.78024984 23.54515992
OS 14.767306 23.53776344
OS 14.75436216 23.53129152
OS 14.72662536 23.52112136
OS 14.69888856 23.51372488
OS 14.67207632 23.50910208
OS 14.65913248 23.50725296
OS 14.64803776 23.50540384
OS 14.6378676 23.50447928
OS 14.62954656 23.50447928
OS 14.62215008 23.50355472
OS 14.61197992 23.50355472
OS 14.59348872 23.50447928
OS 14.57592208 23.5063284
OS 14.55928 23.50817752
OS 14.54356248 23.51187576
OS 14.52876952 23.51649856
OS 14.51490112 23.52112136
OS 14.50195728 23.52574416
OS 14.489938 23.53129152
OS 14.47976784 23.53591432
OS 14.46959768 23.54053712
OS 14.4622012 23.54515992
OS 14.45480472 23.54978272
OS 14.45018192 23.55348096
OS 14.44555912 23.55533008
OS 14.44371 23.5571792
OS 14.44278544 23.55810376
OS 14.4298416 23.56919848
OS 14.41874688 23.5802932
OS 14.40857672 23.59323704
OS 14.39840656 23.60618088
OS 14.38176448 23.63206856
OS 14.36882064 23.65795624
OS 14.36327328 23.66997552
OS 14.35865048 23.68107024
OS 14.35495224 23.6912404
OS 14.35217856 23.69956144
OS 14.34940488 23.70695792
OS 14.34755576 23.71250528
OS 14.3466312 23.71620352
OS 14.3466312 23.71712808
OS 14.43169072 23.73839296
OS 14.43538896 23.7236
OS 14.44001176 23.7097316
OS 14.44463456 23.69678776
OS 14.44925736 23.68476848
OS 14.45480472 23.67367376
OS 14.46035208 23.66442816
OS 14.466824 23.65518256
OS 14.47237136 23.64686152
OS 14.47699416 23.63946504
OS 14.48254152 23.63391768
OS 14.48716432 23.62837032
OS 14.49086256 23.62374752
OS 14.4945608 23.62097384
OS 14.49733448 23.61820016
OS 14.49825904 23.6172756
OS 14.4991836 23.61635104
OS 14.5084292 23.60895456
OS 14.51859936 23.6034072
OS 14.53893968 23.59323704
OS 14.55835544 23.58584056
OS 14.5777712 23.58121776
OS 14.59441328 23.57751952
OS 14.6008852 23.57659496
OS 14.60735712 23.57659496
OS 14.61290448 23.5756704
OS 14.6193764 23.5756704
OS 14.64064128 23.57659496
OS 14.6609816 23.5802932
OS 14.6794728 23.584916
OS 14.69611488 23.59046336
OS 14.70905872 23.59601072
OS 14.71460608 23.5987844
OS 14.71922888 23.60063352
OS 14.72292712 23.60248264
OS 14.7257008 23.60433176
OS 14.72754992 23.60525632
OS 14.72847448 23.60525632
OS 14.74604112 23.61820016
OS 14.76083408 23.63206856
OS 14.77377792 23.64778608
OS 14.78394808 23.66257904
OS 14.79226912 23.67552288
OS 14.79781648 23.6866176
OS 14.7996656 23.6912404
OS 14.80151472 23.69401408
OS 14.80243928 23.6958632
OS 14.80243928 23.69678776
OS 14.80983576 23.72082632
OS 14.81538312 23.74486488
OS 14.82000592 23.76890344
OS 14.8227796 23.79109288
OS 14.82370416 23.80126304
OS 14.82462872 23.81050864
OS 14.82462872 23.81882968
OS 14.82555328 23.8253016
OS 14.82555328 23.83084896
OS 14.82555328 23.83547176
OS 14.82555328 23.83824544
OS 14.82555328 23.83917
OS 14.82462872 23.86320856
OS 14.8227796 23.885398
OS 14.81908136 23.90573832
OS 14.81538312 23.92422952
OS 14.81260944 23.93994704
OS 14.81076032 23.94641896
OS 14.8089112 23.95196632
OS 14.80798664 23.95658912
OS 14.80706208 23.9593628
OS 14.80613752 23.96121192
OS 14.80613752 23.96213648
OS 14.79689192 23.98340136
OS 14.78672176 24.00281712
OS 14.77562704 24.01853464
OS 14.76360776 24.03240304
OS 14.7534376 24.04349776
OS 14.74511656 24.05089424
OS 14.73864464 24.05551704
OS 14.73772008 24.05736616
OS 14.73679552 24.05736616
OS 14.71737976 24.06938544
OS 14.69611488 24.07863104
OS 14.67577456 24.08510296
OS 14.6563588 24.0888012
OS 14.63879216 24.09157488
OS 14.63139568 24.09249944
OS 14.62492376 24.09249944
OS 14.62030096 24.093424
OS 14.61290448 24.093424
OS 14.58979048 24.09249944
OS 14.5685256 24.0888012
OS 14.55095896 24.08325384
OS 14.53524144 24.07770648
OS 14.52322216 24.07123456
OS 14.51397656 24.06661176
OS 14.5084292 24.06291352
OS 14.50658008 24.0610644
OS 14.49178712 24.047196
OS 14.47791872 24.03147848
OS 14.466824 24.0148364
OS 14.4575784 23.99819432
OS 14.45018192 23.98340136
OS 14.44740824 23.97600488
OS 14.44555912 23.97045752
OS 14.44371 23.96583472
OS 14.44186088 23.96213648
OS 14.44093632 23.96028736
OS 14.44093632 23.9593628
OS 14.35772592 23.97877856
OS 14.36327328 23.99542064
OS 14.36882064 24.0102136
OS 14.37621712 24.024082
OS 14.38268904 24.0379504
OS 14.39008552 24.04996968
OS 14.39840656 24.0610644
OS 14.40580304 24.07215912
OS 14.41319952 24.08140472
OS 14.420596 24.0888012
OS 14.42706792 24.09619768
OS 14.43353984 24.1026696
OS 14.43816264 24.1072924
OS 14.44278544 24.1119152
OS 14.44648368 24.11468888
OS 14.4483328 24.11561344
OS 14.44925736 24.116538
OS 14.4622012 24.12485904
OS 14.47514504 24.13318008
OS 14.48808888 24.139652
OS 14.50195728 24.14519936
OS 14.52969408 24.1535204
OS 14.5546572 24.15906776
OS 14.56667648 24.16184144
OS 14.57684664 24.162766
OS 14.5870168 24.16369056
OS 14.59533784 24.16461512
OE
OB 13.9444476 23.74024208 I
OS 13.9444476 24.15444496
OS 14.00824224 24.15444496
OS 14.30132776 23.74024208
OS 14.30132776 23.6681264
OS 14.0230352 23.6681264
OS 14.0230352 23.51464944
OS 13.9444476 23.51464944
OS 13.9444476 23.6681264
OS 13.85753896 23.6681264
OS 13.85753896 23.74024208
OS 13.9444476 23.74024208
OE
OB 14.0230352 24.02685568 H
OS 14.0230352 23.74024208
OS 14.22458928 23.74024208
OS 14.0230352 24.02685568
OE
SE
S P 0
OB 14.1498066 40.99926268 I
OS 14.1498066 41.64183188
OS 14.2006574 41.64183188
OS 14.209903 41.62611436
OS 14.22007316 41.6113214
OS 14.23209244 41.59652844
OS 14.24318716 41.5835846
OS 14.25428188 41.57248988
OS 14.26260292 41.56324428
OS 14.26630116 41.5604706
OS 14.26907484 41.55769692
OS 14.2699994 41.55677236
OS 14.27092396 41.5558478
OS 14.29033972 41.54013028
OS 14.30975548 41.52533732
OS 14.32824668 41.51239348
OS 14.34673788 41.50222332
OS 14.3624554 41.49297772
OS 14.36892732 41.48927948
OS 14.37447468 41.4865058
OS 14.37909748 41.48373212
OS 14.38279572 41.48280756
OS 14.38464484 41.48095844
OS 14.3855694 41.48095844
OS 14.3855694 41.40514452
OS 14.371701 41.41069188
OS 14.3578326 41.4171638
OS 14.3439642 41.42363572
OS 14.33102036 41.43010764
OS 14.31992564 41.435655
OS 14.31068004 41.4402778
OS 14.30513268 41.44397604
OS 14.30420812 41.4449006
OS 14.30328356 41.4449006
OS 14.28664148 41.45507076
OS 14.27184852 41.46524092
OS 14.25890468 41.47448652
OS 14.24873452 41.48280756
OS 14.23948892 41.48927948
OS 14.23394156 41.49482684
OS 14.22931876 41.49852508
OS 14.2283942 41.49944964
OS 14.2283942 40.99926268
OS 14.1498066 40.99926268
OE
OB 14.73320396 41.63813364 I
OS 14.74707236 41.6390582
OS 15.0096474 41.6390582
OS 15.0096474 40.99926268
OS 14.92458788 40.99926268
OS 14.92458788 41.25906404
OS 14.76094076 41.25906404
OS 14.7369022 41.2599886
OS 14.7137882 41.26183772
OS 14.69344788 41.2646114
OS 14.67495668 41.26830964
OS 14.65739004 41.27200788
OS 14.64259708 41.27663068
OS 14.62872868 41.28217804
OS 14.6167094 41.2877254
OS 14.60653924 41.2923482
OS 14.59729364 41.29789556
OS 14.58989716 41.30251836
OS 14.5843498 41.30714116
OS 14.579727 41.30991484
OS 14.57695332 41.31268852
OS 14.5751042 41.31453764
OS 14.57417964 41.3154622
OS 14.56493404 41.32655692
OS 14.556613 41.33765164
OS 14.55014108 41.34874636
OS 14.54366916 41.36076564
OS 14.5381218 41.37278492
OS 14.53442356 41.38387964
OS 14.52795164 41.40514452
OS 14.52610252 41.41531468
OS 14.5242534 41.42456028
OS 14.52332884 41.43288132
OS 14.52240428 41.43935324
OS 14.52147972 41.44582516
OS 14.52147972 41.4495234
OS 14.52147972 41.45229708
OS 14.52147972 41.45322164
OS 14.52240428 41.47078828
OS 14.5242534 41.48743036
OS 14.52795164 41.50222332
OS 14.53072532 41.51516716
OS 14.53442356 41.52626188
OS 14.5381218 41.53458292
OS 14.53997092 41.53920572
OS 14.54089548 41.54105484
OS 14.54829196 41.55492324
OS 14.55753756 41.56694252
OS 14.5658586 41.57803724
OS 14.57417964 41.58635828
OS 14.58157612 41.5928302
OS 14.58712348 41.59837756
OS 14.59082172 41.60115124
OS 14.59267084 41.6020758
OS 14.60469012 41.60947228
OS 14.61855852 41.6159442
OS 14.63150236 41.62149156
OS 14.64352164 41.62611436
OS 14.65461636 41.62888804
OS 14.6629374 41.63073716
OS 14.66940932 41.63258628
OS 14.67125844 41.63258628
OS 14.68512684 41.6344354
OS 14.70084436 41.63628452
OS 14.71748644 41.63720908
OS 14.73320396 41.63813364
OE
OB 13.72081076 41.64090732 I
OS 13.73098092 41.64183188
OS 13.73930196 41.64183188
OS 13.76426508 41.63998276
OS 13.78737908 41.63628452
OS 13.80679484 41.6298126
OS 13.82343692 41.62334068
OS 13.83730532 41.6159442
OS 13.84285268 41.61317052
OS 13.84747548 41.60947228
OS 13.85117372 41.60762316
OS 13.8539474 41.60577404
OS 13.85487196 41.60392492
OS 13.85579652 41.60392492
OS 13.8724386 41.58913196
OS 13.886307 41.57156532
OS 13.89832628 41.55399868
OS 13.90757188 41.5373566
OS 13.91496836 41.52163908
OS 13.9186666 41.51516716
OS 13.92051572 41.50869524
OS 13.92236484 41.50407244
OS 13.92421396 41.5003742
OS 13.92513852 41.49852508
OS 13.92513852 41.49760052
OS 13.92883676 41.48373212
OS 13.932535 41.46986372
OS 13.93808236 41.43935324
OS 13.94270516 41.40884276
OS 13.94547884 41.3801814
OS 13.9464034 41.366313
OS 13.94732796 41.35429372
OS 13.94732796 41.343199
OS 13.94825252 41.33302884
OS 13.94825252 41.32563236
OS 13.94825252 41.31916044
OS 13.94825252 41.3154622
OS 13.94825252 41.31453764
OS 13.94732796 41.28217804
OS 13.94547884 41.25166756
OS 13.94270516 41.22393076
OS 13.93808236 41.19804308
OS 13.93345956 41.17400452
OS 13.9279122 41.15273964
OS 13.92236484 41.13332388
OS 13.91681748 41.1166818
OS 13.91127012 41.10188884
OS 13.9047982 41.088945
OS 13.9001754 41.07785028
OS 13.8955526 41.06952924
OS 13.8909298 41.06213276
OS 13.88815612 41.05750996
OS 13.886307 41.05473628
OS 13.88538244 41.05381172
OS 13.87521228 41.042717
OS 13.86411756 41.03254684
OS 13.85209828 41.02330124
OS 13.840079 41.01590476
OS 13.82805972 41.00943284
OS 13.81604044 41.00388548
OS 13.80402116 41.00018724
OS 13.79292644 40.996489
OS 13.78183172 40.99371532
OS 13.77166156 40.9918662
OS 13.76241596 40.99001708
OS 13.75501948 40.98909252
OS 13.74854756 40.98816796
OS 13.73930196 40.98816796
OS 13.71433884 40.99001708
OS 13.69122484 40.99371532
OS 13.67180908 41.00018724
OS 13.655167 41.00665916
OS 13.6412986 41.01313108
OS 13.6366758 41.01682932
OS 13.632053 41.019603
OS 13.62835476 41.02145212
OS 13.62558108 41.02330124
OS 13.62465652 41.02515036
OS 13.62373196 41.02515036
OS 13.60708988 41.04086788
OS 13.59322148 41.05750996
OS 13.5812022 41.07600116
OS 13.5719566 41.09264324
OS 13.56456012 41.10836076
OS 13.56086188 41.11483268
OS 13.55901276 41.1213046
OS 13.55716364 41.1259274
OS 13.55531452 41.12962564
OS 13.55438996 41.13147476
OS 13.55438996 41.13239932
OS 13.54976716 41.14626772
OS 13.54606892 41.16013612
OS 13.54052156 41.18972204
OS 13.53589876 41.22023252
OS 13.53312508 41.24981844
OS 13.53220052 41.26276228
OS 13.53127596 41.27478156
OS 13.53127596 41.28587628
OS 13.5303514 41.29604644
OS 13.5303514 41.30344292
OS 13.5303514 41.30991484
OS 13.5303514 41.31361308
OS 13.5303514 41.31453764
OS 13.5303514 41.33210428
OS 13.53127596 41.34874636
OS 13.53127596 41.36353932
OS 13.53220052 41.37833228
OS 13.53404964 41.39127612
OS 13.5349742 41.40421996
OS 13.53589876 41.41531468
OS 13.53774788 41.42548484
OS 13.53867244 41.43473044
OS 13.54052156 41.44305148
OS 13.54144612 41.4495234
OS 13.54237068 41.45507076
OS 13.54329524 41.45969356
OS 13.5442198 41.46246724
OS 13.54514436 41.46431636
OS 13.54514436 41.46524092
OS 13.55069172 41.48558124
OS 13.55716364 41.50407244
OS 13.56456012 41.51978996
OS 13.57010748 41.53365836
OS 13.5765794 41.54567764
OS 13.58027764 41.55399868
OS 13.58397588 41.55862148
OS 13.58490044 41.5604706
OS 13.5950706 41.574339
OS 13.60524076 41.58635828
OS 13.61633548 41.59652844
OS 13.62650564 41.60577404
OS 13.63575124 41.61224596
OS 13.64314772 41.61686876
OS 13.64777052 41.61964244
OS 13.64869508 41.620567
OS 13.64961964 41.620567
OS 13.6644126 41.62796348
OS 13.68013012 41.63258628
OS 13.69492308 41.63628452
OS 13.70879148 41.6390582
OS 13.72081076 41.64090732
OE
OB 13.74022652 41.57711268 H
OS 13.73005636 41.57618812
OS 13.7198862 41.57526356
OS 13.7106406 41.57248988
OS 13.70231956 41.56879164
OS 13.68660204 41.5604706
OS 13.67273364 41.551225
OS 13.66256348 41.54105484
OS 13.65424244 41.5327338
OS 13.65146876 41.52903556
OS 13.64961964 41.52626188
OS 13.64777052 41.52533732
OS 13.64777052 41.52441276
OS 13.6412986 41.51331804
OS 13.63575124 41.5003742
OS 13.63020388 41.48558124
OS 13.62650564 41.46986372
OS 13.6228074 41.45322164
OS 13.62003372 41.435655
OS 13.61541092 41.40052172
OS 13.6135618 41.38295508
OS 13.61263724 41.36723756
OS 13.61171268 41.3524446
OS 13.61171268 41.34042532
OS 13.61078812 41.3293306
OS 13.61078812 41.32100956
OS 13.61078812 41.31638676
OS 13.61078812 41.3154622
OS 13.61078812 41.31453764
OS 13.61078812 41.28587628
OS 13.61263724 41.2599886
OS 13.61448636 41.2368746
OS 13.61633548 41.21468516
OS 13.61910916 41.19619396
OS 13.6228074 41.17862732
OS 13.62650564 41.16383436
OS 13.62927932 41.14996596
OS 13.63297756 41.13887124
OS 13.6366758 41.12962564
OS 13.63944948 41.1213046
OS 13.64314772 41.11483268
OS 13.64499684 41.11020988
OS 13.64684596 41.1074362
OS 13.64869508 41.10558708
OS 13.64869508 41.10466252
OS 13.65609156 41.09541692
OS 13.66348804 41.08802044
OS 13.67088452 41.08062396
OS 13.678281 41.0750766
OS 13.69399852 41.065831
OS 13.70786692 41.05935908
OS 13.72081076 41.05566084
OS 13.73005636 41.05381172
OS 13.7337546 41.05288716
OS 13.73930196 41.05288716
OS 13.74947212 41.05381172
OS 13.75871772 41.05473628
OS 13.77628436 41.0612082
OS 13.79200188 41.06952924
OS 13.80587028 41.07877484
OS 13.81604044 41.08802044
OS 13.82436148 41.09634148
OS 13.82898428 41.1028134
OS 13.8308334 41.10373796
OS 13.8308334 41.10466252
OS 13.83730532 41.11575724
OS 13.84285268 41.12870108
OS 13.84840004 41.14349404
OS 13.85209828 41.15921156
OS 13.85579652 41.17585364
OS 13.8585702 41.19342028
OS 13.863193 41.22947812
OS 13.86504212 41.2461202
OS 13.86596668 41.26183772
OS 13.86689124 41.27663068
OS 13.86689124 41.28864996
OS 13.8678158 41.29974468
OS 13.8678158 41.30806572
OS 13.8678158 41.31268852
OS 13.8678158 41.31453764
OS 13.86689124 41.343199
OS 13.86596668 41.36908668
OS 13.86411756 41.39312524
OS 13.86134388 41.41531468
OS 13.8585702 41.43473044
OS 13.85487196 41.45229708
OS 13.85117372 41.4680146
OS 13.84747548 41.481883
OS 13.84377724 41.49390228
OS 13.84100356 41.50407244
OS 13.83730532 41.51239348
OS 13.83453164 41.51978996
OS 13.83175796 41.52441276
OS 13.82990884 41.528111
OS 13.82805972 41.52996012
OS 13.82805972 41.53088468
OS 13.8215878 41.53920572
OS 13.81511588 41.5466022
OS 13.8077194 41.55214956
OS 13.80032292 41.55769692
OS 13.78552996 41.56601796
OS 13.77166156 41.57156532
OS 13.75964228 41.574339
OS 13.74947212 41.57618812
OS 13.74577388 41.57711268
OS 13.74022652 41.57711268
OE
OB 14.741525 41.56324428 H
OS 14.72488292 41.56231972
OS 14.71101452 41.56139516
OS 14.6999198 41.5604706
OS 14.69252332 41.55862148
OS 14.68697596 41.55769692
OS 14.68327772 41.55677236
OS 14.68235316 41.55677236
OS 14.67033388 41.55214956
OS 14.66016372 41.5466022
OS 14.65091812 41.54105484
OS 14.64259708 41.53458292
OS 14.63704972 41.528111
OS 14.63242692 41.5234882
OS 14.62965324 41.51978996
OS 14.62872868 41.5188654
OS 14.62225676 41.50777068
OS 14.6167094 41.49667596
OS 14.61301116 41.48465668
OS 14.61116204 41.47448652
OS 14.60931292 41.46524092
OS 14.60838836 41.45691988
OS 14.60838836 41.45229708
OS 14.60838836 41.45137252
OS 14.60838836 41.45044796
OS 14.61023748 41.4310322
OS 14.61393572 41.41439012
OS 14.61948308 41.39959716
OS 14.625955 41.38757788
OS 14.63242692 41.37833228
OS 14.63797428 41.3709358
OS 14.64167252 41.36723756
OS 14.64352164 41.36538844
OS 14.64999356 41.35984108
OS 14.6583146 41.35521828
OS 14.67588124 41.3478218
OS 14.695297 41.34227444
OS 14.71471276 41.3385762
OS 14.7322794 41.33672708
OS 14.73967588 41.33580252
OS 14.7461478 41.33580252
OS 14.75261972 41.33487796
OS 14.92458788 41.33487796
OS 14.92458788 41.56324428
OS 14.741525 41.56324428
OE
SE
S P 0
OB 14.72794362 15.94423532 I
OS 14.72794362 16.31405932
OS 14.81300314 16.31405932
OS 14.81300314 15.94423532
OS 14.81300314 15.92297044
OS 14.81485226 15.90263012
OS 14.81670138 15.88506348
OS 14.81947506 15.8684214
OS 14.82224874 15.85362844
OS 14.82594698 15.83976004
OS 14.82872066 15.82774076
OS 14.8324189 15.8175706
OS 14.83611714 15.80924956
OS 14.83981538 15.80092852
OS 14.84351362 15.79538116
OS 14.8462873 15.7898338
OS 14.84906098 15.78613556
OS 14.8509101 15.78336188
OS 14.85183466 15.78243732
OS 14.85275922 15.78151276
OS 14.86108026 15.77411628
OS 14.87032586 15.76764436
OS 14.89066618 15.7574742
OS 14.91193106 15.75007772
OS 14.9341205 15.74545492
OS 14.95446082 15.74175668
OS 14.96278186 15.74083212
OS 14.9711029 15.74083212
OS 14.97665026 15.73990756
OS 14.98589586 15.73990756
OS 15.00531162 15.74083212
OS 15.02287826 15.7436058
OS 15.03952034 15.74637948
OS 15.05246418 15.75100228
OS 15.0635589 15.75470052
OS 15.07187994 15.7574742
OS 15.07650274 15.76024788
OS 15.07835186 15.76117244
OS 15.0912957 15.76949348
OS 15.10239042 15.77966364
OS 15.11163602 15.7898338
OS 15.11810794 15.7990794
OS 15.1236553 15.808325
OS 15.1282781 15.81479692
OS 15.13012722 15.81941972
OS 15.13105178 15.82126884
OS 15.13382546 15.82958988
OS 15.13567458 15.83791092
OS 15.13937282 15.85732668
OS 15.1421465 15.877667
OS 15.14399562 15.89800732
OS 15.14492018 15.91557396
OS 15.14492018 15.923895
OS 15.14584474 15.93036692
OS 15.14584474 15.93591428
OS 15.14584474 15.94053708
OS 15.14584474 15.94331076
OS 15.14584474 15.94423532
OS 15.14584474 16.31405932
OS 15.23090426 16.31405932
OS 15.23090426 15.94423532
OS 15.23090426 15.92574412
OS 15.2299797 15.90817748
OS 15.22905514 15.8915354
OS 15.22720602 15.87581788
OS 15.2253569 15.86194948
OS 15.22350778 15.84900564
OS 15.2207341 15.83698636
OS 15.21888498 15.82589164
OS 15.21703586 15.81572148
OS 15.21426218 15.80740044
OS 15.21241306 15.80000396
OS 15.21056394 15.7944566
OS 15.20871482 15.7898338
OS 15.20779026 15.78613556
OS 15.2068657 15.78428644
OS 15.2068657 15.78336188
OS 15.19669554 15.76302156
OS 15.1837517 15.74453036
OS 15.17080786 15.7297374
OS 15.15693946 15.71679356
OS 15.14492018 15.7066234
OS 15.13475002 15.69922692
OS 15.13105178 15.6973778
OS 15.1282781 15.69552868
OS 15.12642898 15.69367956
OS 15.12550442 15.69367956
OS 15.10239042 15.6835094
OS 15.07835186 15.67611292
OS 15.05338874 15.67056556
OS 15.03027474 15.66686732
OS 15.02010458 15.66594276
OS 15.00993442 15.6650182
OS 15.00068882 15.66409364
OS 14.99329234 15.66409364
OS 14.98682042 15.66316908
OS 14.97849938 15.66316908
OS 14.94521522 15.6650182
OS 14.93042226 15.66686732
OS 14.91655386 15.66871644
OS 14.90268546 15.67149012
OS 14.89066618 15.6742638
OS 14.87957146 15.67703748
OS 14.8694013 15.68073572
OS 14.8601557 15.68443396
OS 14.85275922 15.68720764
OS 14.84536274 15.68998132
OS 14.83981538 15.692755
OS 14.83519258 15.69552868
OS 14.8324189 15.69645324
OS 14.83056978 15.69830236
OS 14.82964522 15.69830236
OS 14.8093049 15.71217076
OS 14.79266282 15.72788828
OS 14.77971898 15.74268124
OS 14.76862426 15.7574742
OS 14.76030322 15.77041804
OS 14.75475586 15.7805882
OS 14.75290674 15.78428644
OS 14.75105762 15.78706012
OS 14.75013306 15.78890924
OS 14.75013306 15.7898338
OS 14.74643482 15.80092852
OS 14.74273658 15.8129478
OS 14.73718922 15.83791092
OS 14.73349098 15.8637986
OS 14.7307173 15.88876172
OS 14.72979274 15.89985644
OS 14.72886818 15.91095116
OS 14.72886818 15.92019676
OS 14.72794362 15.9285178
OS 14.72794362 15.93498972
OS 14.72794362 15.93961252
OS 14.72794362 15.94331076
OS 14.72794362 15.94423532
OE
OB 14.39880026 16.31590844 I
OS 14.40897042 16.316833
OS 14.43208442 16.316833
OS 14.44502826 16.31498388
OS 14.46999138 16.31036108
OS 14.49125626 16.3029646
OS 14.50974746 16.29556812
OS 14.5180685 16.29094532
OS 14.52454042 16.28724708
OS 14.53101234 16.28354884
OS 14.53563514 16.2798506
OS 14.53933338 16.27707692
OS 14.54210706 16.2752278
OS 14.54395618 16.27430324
OS 14.54488074 16.27337868
OS 14.56244738 16.25581204
OS 14.57631578 16.23639628
OS 14.5874105 16.21605596
OS 14.5966561 16.19571564
OS 14.60220346 16.178149
OS 14.60497714 16.17075252
OS 14.60682626 16.1642806
OS 14.60775082 16.15873324
OS 14.60867538 16.155035
OS 14.60959994 16.15226132
OS 14.60959994 16.15133676
OS 14.53101234 16.13746836
OS 14.5273141 16.15780868
OS 14.52176674 16.17537532
OS 14.51529482 16.19016828
OS 14.5088229 16.20218756
OS 14.50235098 16.21143316
OS 14.49680362 16.21790508
OS 14.49310538 16.22252788
OS 14.49218082 16.22345244
OS 14.48016154 16.23269804
OS 14.4672177 16.24009452
OS 14.45519842 16.24471732
OS 14.44317914 16.24841556
OS 14.43208442 16.25026468
OS 14.42376338 16.2521138
OS 14.4163669 16.2521138
OS 14.39972482 16.25118924
OS 14.38493186 16.247491
OS 14.37198802 16.2428682
OS 14.3608933 16.2382454
OS 14.35257226 16.23269804
OS 14.34610034 16.22807524
OS 14.34147754 16.224377
OS 14.34055298 16.22345244
OS 14.33038282 16.21235772
OS 14.32298634 16.20033844
OS 14.31836354 16.18831916
OS 14.3146653 16.17722444
OS 14.31281618 16.16705428
OS 14.31096706 16.1596578
OS 14.31096706 16.15411044
OS 14.31096706 16.15318588
OS 14.31096706 16.15226132
OS 14.31096706 16.14209116
OS 14.31281618 16.13284556
OS 14.31743898 16.11712804
OS 14.3239109 16.10325964
OS 14.33130738 16.09124036
OS 14.33870386 16.08291932
OS 14.34517578 16.0764474
OS 14.34979858 16.07274916
OS 14.35072314 16.0718246
OS 14.3516477 16.0718246
OS 14.36736522 16.06350356
OS 14.38215818 16.05703164
OS 14.3978757 16.05240884
OS 14.4117441 16.04963516
OS 14.42376338 16.04778604
OS 14.43393354 16.04593692
OS 14.44595282 16.04593692
OS 14.44965106 16.04686148
OS 14.45427386 16.04686148
OS 14.46351946 15.97751948
OS 14.45150018 15.98029316
OS 14.44040546 15.98214228
OS 14.43115986 15.9839914
OS 14.42283882 15.98491596
OS 14.4163669 15.98584052
OS 14.40804586 15.98584052
OS 14.3886301 15.9839914
OS 14.37106346 15.98029316
OS 14.35534594 15.9747458
OS 14.3424021 15.96827388
OS 14.33223194 15.96180196
OS 14.32483546 15.9562546
OS 14.32021266 15.95255636
OS 14.31836354 15.95070724
OS 14.30634426 15.93683884
OS 14.29709866 15.92204588
OS 14.29062674 15.90725292
OS 14.2869285 15.89245996
OS 14.28415482 15.88044068
OS 14.28323026 15.87027052
OS 14.2823057 15.86657228
OS 14.2823057 15.8637986
OS 14.2823057 15.86194948
OS 14.2823057 15.86102492
OS 14.28415482 15.8406846
OS 14.28877762 15.8221934
OS 14.29432498 15.80647588
OS 14.30172146 15.79260748
OS 14.30911794 15.78151276
OS 14.3146653 15.77319172
OS 14.3192881 15.76764436
OS 14.32113722 15.76579524
OS 14.33593018 15.7528514
OS 14.3516477 15.7436058
OS 14.36736522 15.73713388
OS 14.38215818 15.73251108
OS 14.39510202 15.7297374
OS 14.40527218 15.72881284
OS 14.40897042 15.72788828
OS 14.41451778 15.72788828
OS 14.43115986 15.72881284
OS 14.44687738 15.73251108
OS 14.46074578 15.73713388
OS 14.4718405 15.74268124
OS 14.4810861 15.74730404
OS 14.48848258 15.75192684
OS 14.49218082 15.75562508
OS 14.49402994 15.75654964
OS 14.50512466 15.76949348
OS 14.51437026 15.78428644
OS 14.5226913 15.80000396
OS 14.52916322 15.81664604
OS 14.53378602 15.83051444
OS 14.53563514 15.83698636
OS 14.5365597 15.84253372
OS 14.53748426 15.84715652
OS 14.53840882 15.85085476
OS 14.53933338 15.85270388
OS 14.53933338 15.85362844
OS 14.61792098 15.84345828
OS 14.61607186 15.82866532
OS 14.61329818 15.81479692
OS 14.60497714 15.78890924
OS 14.59480698 15.7667198
OS 14.58925962 15.7574742
OS 14.58371226 15.7482286
OS 14.5781649 15.73990756
OS 14.57261754 15.73343564
OS 14.56799474 15.72696372
OS 14.56337194 15.72234092
OS 14.56059826 15.71864268
OS 14.55782458 15.715869
OS 14.55597546 15.71401988
OS 14.5550509 15.71309532
OS 14.54395618 15.70477428
OS 14.53286146 15.69645324
OS 14.52176674 15.68998132
OS 14.50974746 15.68443396
OS 14.48663346 15.67518836
OS 14.46444402 15.669641
OS 14.45427386 15.66779188
OS 14.44502826 15.66594276
OS 14.43670722 15.6650182
OS 14.42931074 15.66409364
OS 14.42376338 15.66316908
OS 14.41544234 15.66316908
OS 14.3978757 15.66409364
OS 14.38215818 15.66594276
OS 14.36644066 15.66871644
OS 14.3516477 15.67241468
OS 14.3377793 15.67703748
OS 14.32576002 15.68166028
OS 14.31374074 15.68720764
OS 14.30357058 15.692755
OS 14.29340042 15.6973778
OS 14.28507938 15.70292516
OS 14.2776829 15.70754796
OS 14.27213554 15.71217076
OS 14.26751274 15.715869
OS 14.2638145 15.71864268
OS 14.26196538 15.7204918
OS 14.26104082 15.72141636
OS 14.2499461 15.73251108
OS 14.2407005 15.74453036
OS 14.23237946 15.75654964
OS 14.22498298 15.76856892
OS 14.21943562 15.77966364
OS 14.21388826 15.79168292
OS 14.20649178 15.81387236
OS 14.20464266 15.82404252
OS 14.20279354 15.83328812
OS 14.20094442 15.84160916
OS 14.20001986 15.84900564
OS 14.1990953 15.854553
OS 14.1990953 15.8591758
OS 14.1990953 15.86194948
OS 14.1990953 15.86287404
OS 14.20001986 15.88506348
OS 14.2037181 15.9054038
OS 14.20926546 15.92297044
OS 14.21481282 15.9377634
OS 14.22036018 15.94978268
OS 14.22590754 15.95902828
OS 14.22960578 15.96457564
OS 14.23053034 15.96642476
OS 14.24347418 15.98029316
OS 14.25734258 15.99231244
OS 14.27213554 16.00155804
OS 14.2869285 16.00895452
OS 14.29987234 16.01450188
OS 14.3100425 16.01820012
OS 14.31374074 16.01912468
OS 14.31651442 16.02004924
OS 14.31836354 16.0209738
OS 14.3192881 16.0209738
OS 14.30357058 16.02929484
OS 14.29062674 16.03761588
OS 14.27953202 16.04686148
OS 14.27028642 16.05518252
OS 14.26288994 16.062579
OS 14.25734258 16.06905092
OS 14.2545689 16.07274916
OS 14.25364434 16.07459828
OS 14.24624786 16.08754212
OS 14.2407005 16.10048596
OS 14.2360777 16.1134298
OS 14.23330402 16.12544908
OS 14.2314549 16.13561924
OS 14.23053034 16.14301572
OS 14.23053034 16.14856308
OS 14.23053034 16.1504122
OS 14.2314549 16.16612972
OS 14.23422858 16.18184724
OS 14.23792682 16.19571564
OS 14.24254962 16.20773492
OS 14.24717242 16.21790508
OS 14.25087066 16.22622612
OS 14.25364434 16.23084892
OS 14.2545689 16.23269804
OS 14.2638145 16.24656644
OS 14.27490922 16.25858572
OS 14.28600394 16.26875588
OS 14.29709866 16.27800148
OS 14.30634426 16.2844734
OS 14.3146653 16.29002076
OS 14.32021266 16.29279444
OS 14.32113722 16.293719
OS 14.32206178 16.293719
OS 14.33870386 16.30111548
OS 14.35534594 16.30666284
OS 14.37198802 16.31128564
OS 14.38678098 16.31405932
OS 14.39880026 16.31590844
OE
SE
S P 0
OB 15.22672596 15.12006882 I
OS 15.23319788 15.12099338
OS 15.24244348 15.12099338
OS 15.27295396 15.11914426
OS 15.30253988 15.11452146
OS 15.32842756 15.1089741
OS 15.34044684 15.10527586
OS 15.35154156 15.10157762
OS 15.36171172 15.09787938
OS 15.37095732 15.09418114
OS 15.3783538 15.09140746
OS 15.38575028 15.08863378
OS 15.39037308 15.0858601
OS 15.39407132 15.08401098
OS 15.396845 15.08308642
OS 15.39776956 15.08216186
OS 15.42273268 15.06644434
OS 15.44399756 15.04795314
OS 15.46248876 15.02946194
OS 15.47820628 15.01097074
OS 15.49022556 14.99432866
OS 15.49484836 14.98693218
OS 15.4985466 14.98046026
OS 15.50224484 14.97583746
OS 15.50409396 14.97213922
OS 15.50501852 14.96936554
OS 15.50594308 14.96844098
OS 15.51888692 14.93977962
OS 15.52813252 14.9101937
OS 15.53460444 14.88060778
OS 15.53922724 14.85379554
OS 15.54107636 14.84177626
OS 15.54200092 14.82975698
OS 15.54292548 14.82051138
OS 15.54292548 14.81126578
OS 15.54385004 14.80479386
OS 15.54385004 14.7992465
OS 15.54385004 14.79554826
OS 15.54385004 14.7946237
OS 15.54200092 14.76133954
OS 15.53830268 14.72897994
OS 15.53367988 14.70031858
OS 15.52998164 14.68645018
OS 15.52720796 14.6744309
OS 15.52443428 14.66333618
OS 15.52073604 14.65316602
OS 15.51796236 14.64392042
OS 15.51611324 14.63652394
OS 15.51333956 14.63097658
OS 15.512415 14.62635378
OS 15.51056588 14.6235801
OS 15.51056588 14.62265554
OS 15.49669748 14.59491874
OS 15.48097996 14.56995562
OS 15.46433788 14.54869074
OS 15.45601684 14.5403697
OS 15.44862036 14.53204866
OS 15.44122388 14.52465218
OS 15.4338274 14.51818026
OS 15.42735548 14.5126329
OS 15.42180812 14.50893466
OS 15.41810988 14.50523642
OS 15.41441164 14.50246274
OS 15.41256252 14.50153818
OS 15.41163796 14.50061362
OS 15.39869412 14.49321714
OS 15.38575028 14.48674522
OS 15.35801348 14.47657506
OS 15.33027668 14.46917858
OS 15.30346444 14.46455578
OS 15.2905206 14.46270666
OS 15.27942588 14.46085754
OS 15.26925572 14.45993298
OS 15.26093468 14.45993298
OS 15.2535382 14.45900842
OS 15.24336804 14.45900842
OS 15.22487684 14.45993298
OS 15.2073102 14.4617821
OS 15.19066812 14.46363122
OS 15.1749506 14.46732946
OS 15.16015764 14.47195226
OS 15.14628924 14.47657506
OS 15.1333454 14.48119786
OS 15.12132612 14.48674522
OS 15.11115596 14.49136802
OS 15.1009858 14.49599082
OS 15.09358932 14.50061362
OS 15.08619284 14.50523642
OS 15.08157004 14.50893466
OS 15.07694724 14.51078378
OS 15.07509812 14.5126329
OS 15.07417356 14.51355746
OS 15.06122972 14.52465218
OS 15.050135 14.5357469
OS 15.03996484 14.54869074
OS 15.02979468 14.56163458
OS 15.0131526 14.58752226
OS 15.00020876 14.61340994
OS 14.9946614 14.62542922
OS 14.9900386 14.63652394
OS 14.98634036 14.6466941
OS 14.98356668 14.65501514
OS 14.980793 14.66241162
OS 14.97894388 14.66795898
OS 14.97801932 14.67165722
OS 14.97801932 14.67258178
OS 15.06307884 14.69384666
OS 15.06677708 14.6790537
OS 15.07139988 14.6651853
OS 15.07602268 14.65224146
OS 15.08064548 14.64022218
OS 15.08619284 14.62912746
OS 15.0917402 14.61988186
OS 15.09821212 14.61063626
OS 15.10375948 14.60231522
OS 15.10838228 14.59491874
OS 15.11392964 14.58937138
OS 15.11855244 14.58382402
OS 15.12225068 14.57920122
OS 15.12594892 14.57642754
OS 15.1287226 14.57365386
OS 15.12964716 14.5727293
OS 15.13057172 14.57180474
OS 15.13981732 14.56440826
OS 15.14998748 14.5588609
OS 15.1703278 14.54869074
OS 15.18974356 14.54129426
OS 15.20915932 14.53667146
OS 15.2258014 14.53297322
OS 15.23227332 14.53204866
OS 15.23874524 14.53204866
OS 15.2442926 14.5311241
OS 15.25076452 14.5311241
OS 15.2720294 14.53204866
OS 15.29236972 14.5357469
OS 15.31086092 14.5403697
OS 15.327503 14.54591706
OS 15.34044684 14.55146442
OS 15.3459942 14.5542381
OS 15.350617 14.55608722
OS 15.35431524 14.55793634
OS 15.35708892 14.55978546
OS 15.35893804 14.56071002
OS 15.3598626 14.56071002
OS 15.37742924 14.57365386
OS 15.3922222 14.58752226
OS 15.40516604 14.60323978
OS 15.4153362 14.61803274
OS 15.42365724 14.63097658
OS 15.4292046 14.6420713
OS 15.43105372 14.6466941
OS 15.43290284 14.64946778
OS 15.4338274 14.6513169
OS 15.4338274 14.65224146
OS 15.44122388 14.67628002
OS 15.44677124 14.70031858
OS 15.45139404 14.72435714
OS 15.45416772 14.74654658
OS 15.45509228 14.75671674
OS 15.45601684 14.76596234
OS 15.45601684 14.77428338
OS 15.4569414 14.7807553
OS 15.4569414 14.78630266
OS 15.4569414 14.79092546
OS 15.4569414 14.79369914
OS 15.4569414 14.7946237
OS 15.45601684 14.81866226
OS 15.45416772 14.8408517
OS 15.45046948 14.86119202
OS 15.44677124 14.87968322
OS 15.44399756 14.89540074
OS 15.44214844 14.90187266
OS 15.44029932 14.90742002
OS 15.43937476 14.91204282
OS 15.4384502 14.9148165
OS 15.43752564 14.91666562
OS 15.43752564 14.91759018
OS 15.42828004 14.93885506
OS 15.41810988 14.95827082
OS 15.40701516 14.97398834
OS 15.39499588 14.98785674
OS 15.38482572 14.99895146
OS 15.37650468 15.00634794
OS 15.37003276 15.01097074
OS 15.3691082 15.01281986
OS 15.36818364 15.01281986
OS 15.34876788 15.02483914
OS 15.327503 15.03408474
OS 15.30716268 15.04055666
OS 15.28774692 15.0442549
OS 15.27018028 15.04702858
OS 15.2627838 15.04795314
OS 15.25631188 15.04795314
OS 15.25168908 15.0488777
OS 15.2442926 15.0488777
OS 15.2211786 15.04795314
OS 15.19991372 15.0442549
OS 15.18234708 15.03870754
OS 15.16662956 15.03316018
OS 15.15461028 15.02668826
OS 15.14536468 15.02206546
OS 15.13981732 15.01836722
OS 15.1379682 15.0165181
OS 15.12317524 15.0026497
OS 15.10930684 14.98693218
OS 15.09821212 14.9702901
OS 15.08896652 14.95364802
OS 15.08157004 14.93885506
OS 15.07879636 14.93145858
OS 15.07694724 14.92591122
OS 15.07509812 14.92128842
OS 15.073249 14.91759018
OS 15.07232444 14.91574106
OS 15.07232444 14.9148165
OS 14.98911404 14.93423226
OS 14.9946614 14.95087434
OS 15.00020876 14.9656673
OS 15.00760524 14.9795357
OS 15.01407716 14.9934041
OS 15.02147364 15.00542338
OS 15.02979468 15.0165181
OS 15.03719116 15.02761282
OS 15.04458764 15.03685842
OS 15.05198412 15.0442549
OS 15.05845604 15.05165138
OS 15.06492796 15.0581233
OS 15.06955076 15.0627461
OS 15.07417356 15.0673689
OS 15.0778718 15.07014258
OS 15.07972092 15.07106714
OS 15.08064548 15.0719917
OS 15.09358932 15.08031274
OS 15.10653316 15.08863378
OS 15.119477 15.0951057
OS 15.1333454 15.10065306
OS 15.1610822 15.1089741
OS 15.18604532 15.11452146
OS 15.1980646 15.11729514
OS 15.20823476 15.1182197
OS 15.21840492 15.11914426
OS 15.22672596 15.12006882
OE
OB 14.6664426 15.11174778 I
OS 14.67198996 15.11267234
OS 14.67938644 15.11267234
OS 14.69787764 15.11174778
OS 14.71544428 15.10989866
OS 14.73208636 15.10620042
OS 14.74780388 15.10157762
OS 14.76167228 15.0951057
OS 14.77554068 15.08955834
OS 14.78755996 15.08216186
OS 14.79865468 15.07568994
OS 14.80790028 15.06921802
OS 14.81714588 15.06182154
OS 14.82454236 15.05627418
OS 14.83008972 15.05072682
OS 14.83471252 15.04517946
OS 14.83841076 15.04148122
OS 14.84025988 15.0396321
OS 14.84118444 15.03870754
OS 14.85320372 15.02206546
OS 14.86337388 15.0026497
OS 14.87261948 14.98230938
OS 14.88094052 14.9610445
OS 14.88741244 14.93885506
OS 14.8929598 14.91666562
OS 14.8975826 14.89355162
OS 14.90128084 14.87228674
OS 14.90405452 14.85102186
OS 14.90590364 14.8316061
OS 14.90775276 14.81403946
OS 14.90867732 14.7992465
OS 14.90867732 14.78630266
OS 14.90960188 14.77705706
OS 14.90960188 14.77335882
OS 14.90960188 14.77058514
OS 14.90960188 14.76966058
OS 14.90960188 14.76873602
OS 14.90867732 14.7391501
OS 14.9068282 14.7114133
OS 14.90405452 14.68552562
OS 14.89943172 14.66148706
OS 14.89480892 14.64022218
OS 14.89018612 14.62080642
OS 14.88463876 14.60323978
OS 14.87816684 14.58752226
OS 14.87261948 14.57457842
OS 14.86707212 14.56255914
OS 14.86244932 14.55331354
OS 14.85690196 14.5449925
OS 14.85320372 14.53852058
OS 14.85043004 14.53482234
OS 14.84858092 14.53204866
OS 14.84765636 14.5311241
OS 14.83563708 14.51818026
OS 14.82269324 14.50708554
OS 14.8097494 14.49783994
OS 14.79680556 14.4895189
OS 14.78293716 14.48212242
OS 14.76999332 14.47657506
OS 14.75704948 14.47195226
OS 14.74410564 14.46825402
OS 14.73301092 14.46548034
OS 14.7219162 14.46270666
OS 14.7126706 14.46085754
OS 14.70434956 14.45993298
OS 14.69695308 14.45993298
OS 14.69233028 14.45900842
OS 14.68770748 14.45900842
OS 14.6664426 14.45993298
OS 14.64702684 14.46363122
OS 14.6294602 14.46732946
OS 14.61374268 14.47287682
OS 14.6017234 14.47749962
OS 14.5924778 14.48212242
OS 14.58877956 14.48304698
OS 14.58600588 14.4848961
OS 14.58508132 14.48582066
OS 14.58415676 14.48582066
OS 14.56843924 14.49691538
OS 14.55364628 14.50985922
OS 14.541627 14.52280306
OS 14.53145684 14.5357469
OS 14.5231358 14.54776618
OS 14.51758844 14.55701178
OS 14.51573932 14.56071002
OS 14.5138902 14.5634837
OS 14.51296564 14.56440826
OS 14.51296564 14.56533282
OS 14.50372004 14.58474858
OS 14.49724812 14.6050889
OS 14.49262532 14.6235801
OS 14.48985164 14.64114674
OS 14.48707796 14.6559397
OS 14.48707796 14.66148706
OS 14.4861534 14.66703442
OS 14.4861534 14.67165722
OS 14.4861534 14.6744309
OS 14.4861534 14.67628002
OS 14.4861534 14.67720458
OS 14.48707796 14.69384666
OS 14.48892708 14.70956418
OS 14.49170076 14.7252817
OS 14.49447444 14.7391501
OS 14.49909724 14.75209394
OS 14.50372004 14.76503778
OS 14.50834284 14.7761325
OS 14.5138902 14.78630266
OS 14.51943756 14.79554826
OS 14.52406036 14.8038693
OS 14.52868316 14.81034122
OS 14.53330596 14.81681314
OS 14.53607964 14.82143594
OS 14.53885332 14.82420962
OS 14.54070244 14.82605874
OS 14.541627 14.8269833
OS 14.55179716 14.83715346
OS 14.56289188 14.84639906
OS 14.57491116 14.85379554
OS 14.58600588 14.86026746
OS 14.5971006 14.86673938
OS 14.60819532 14.87136218
OS 14.6294602 14.8778341
OS 14.6387058 14.88060778
OS 14.6479514 14.8824569
OS 14.65534788 14.88338146
OS 14.66274436 14.88430602
OS 14.66829172 14.88523058
OS 14.6756882 14.88523058
OS 14.69233028 14.88430602
OS 14.7080478 14.88153234
OS 14.72284076 14.87875866
OS 14.7357846 14.87506042
OS 14.74687932 14.87043762
OS 14.75520036 14.86766394
OS 14.76074772 14.86489026
OS 14.76167228 14.8639657
OS 14.76259684 14.8639657
OS 14.7773898 14.8547201
OS 14.79033364 14.84454994
OS 14.80235292 14.83437978
OS 14.81159852 14.82328506
OS 14.81991956 14.81403946
OS 14.82639148 14.80664298
OS 14.83008972 14.80109562
OS 14.83101428 14.80017106
OS 14.83101428 14.81681314
OS 14.83008972 14.83345522
OS 14.82916516 14.84824818
OS 14.82731604 14.86304114
OS 14.82639148 14.87598498
OS 14.82454236 14.88800426
OS 14.82269324 14.89909898
OS 14.81991956 14.90926914
OS 14.81807044 14.91851474
OS 14.81622132 14.92591122
OS 14.8143722 14.93238314
OS 14.81344764 14.9379305
OS 14.81159852 14.94162874
OS 14.81067396 14.94440242
OS 14.8097494 14.94625154
OS 14.8097494 14.9471761
OS 14.8005038 14.9656673
OS 14.7912582 14.98230938
OS 14.78108804 14.99525322
OS 14.77184244 15.00634794
OS 14.7635214 15.01559354
OS 14.75704948 15.02206546
OS 14.75242668 15.0257637
OS 14.75057756 15.02668826
OS 14.73948284 15.03408474
OS 14.72838812 15.03870754
OS 14.7172934 15.04240578
OS 14.70619868 15.04517946
OS 14.69787764 15.04702858
OS 14.69048116 15.04795314
OS 14.68400924 15.04795314
OS 14.66736716 15.04610402
OS 14.65164964 15.04240578
OS 14.6387058 15.03685842
OS 14.62668652 15.03131106
OS 14.61744092 15.02483914
OS 14.610969 15.01929178
OS 14.60727076 15.01559354
OS 14.60542164 15.01374442
OS 14.59894972 15.00542338
OS 14.5924778 14.99525322
OS 14.58693044 14.9841585
OS 14.5832322 14.97306378
OS 14.57953396 14.96289362
OS 14.57676028 14.95457258
OS 14.57583572 14.94902522
OS 14.57491116 14.94810066
OS 14.57491116 14.9471761
OS 14.49632356 14.95364802
OS 14.50187092 14.9795357
OS 14.51019196 15.0026497
OS 14.51943756 15.02299002
OS 14.52960772 15.0396321
OS 14.53977788 15.05257594
OS 14.54347612 15.0581233
OS 14.54809892 15.0627461
OS 14.5508726 15.06551978
OS 14.55364628 15.06829346
OS 14.55457084 15.06921802
OS 14.5554954 15.07014258
OS 14.564741 15.07753906
OS 14.57491116 15.08401098
OS 14.59525148 15.0951057
OS 14.6155918 15.10250218
OS 14.63500756 15.10712498
OS 14.6525742 15.11082322
OS 14.65997068 15.11174778
OS 14.6664426 15.11174778
OE
OB 14.69140572 14.81588858 H
OS 14.67198996 14.81403946
OS 14.65442332 14.80941666
OS 14.63963036 14.8038693
OS 14.62668652 14.79647282
OS 14.61651636 14.78907634
OS 14.60911988 14.78352898
OS 14.60449708 14.77890618
OS 14.60264796 14.77705706
OS 14.59062868 14.76133954
OS 14.58138308 14.74469746
OS 14.57491116 14.72713082
OS 14.57121292 14.71048874
OS 14.56843924 14.69569578
OS 14.56751468 14.68922386
OS 14.56751468 14.6836765
OS 14.56659012 14.6790537
OS 14.56659012 14.67535546
OS 14.56659012 14.67350634
OS 14.56659012 14.67258178
OS 14.56843924 14.64761866
OS 14.57213748 14.62635378
OS 14.57768484 14.60786258
OS 14.58415676 14.59214506
OS 14.59155324 14.58012578
OS 14.5971006 14.57088018
OS 14.60079884 14.56533282
OS 14.60264796 14.56440826
OS 14.60264796 14.5634837
OS 14.60911988 14.55608722
OS 14.61651636 14.55053986
OS 14.63130932 14.5403697
OS 14.64610228 14.53389778
OS 14.65904612 14.52835042
OS 14.6710654 14.52557674
OS 14.680311 14.52465218
OS 14.68400924 14.52372762
OS 14.68863204 14.52372762
OS 14.70157588 14.52465218
OS 14.71359516 14.5265013
OS 14.72468988 14.53019954
OS 14.73393548 14.53389778
OS 14.74225652 14.53667146
OS 14.74872844 14.5403697
OS 14.75242668 14.54221882
OS 14.7542758 14.54314338
OS 14.76537052 14.55146442
OS 14.77461612 14.55978546
OS 14.78293716 14.56995562
OS 14.78940908 14.57827666
OS 14.79495644 14.5865977
OS 14.79865468 14.59306962
OS 14.80142836 14.59769242
OS 14.80235292 14.59954154
OS 14.80790028 14.61340994
OS 14.81159852 14.62727834
OS 14.81529676 14.64022218
OS 14.81714588 14.65224146
OS 14.81807044 14.66241162
OS 14.818995 14.67073266
OS 14.818995 14.67535546
OS 14.818995 14.67720458
OS 14.81714588 14.69939402
OS 14.81344764 14.71880978
OS 14.80697572 14.73637642
OS 14.8005038 14.75024482
OS 14.79403188 14.7622641
OS 14.78755996 14.77058514
OS 14.78386172 14.77520794
OS 14.7820126 14.77705706
OS 14.76721964 14.7900009
OS 14.75242668 14.7992465
OS 14.73670916 14.80664298
OS 14.72284076 14.81126578
OS 14.70989692 14.81403946
OS 14.70065132 14.81496402
OS 14.69695308 14.81588858
OS 14.69140572 14.81588858
OE
SE
S P 0
OB 15.86672468 24.15768092 I
OS 15.87412116 24.15860548
OS 16.17090492 24.15860548
OS 16.17090492 23.51880996
OS 16.0858454 23.51880996
OS 16.0858454 23.80264988
OS 15.97674732 23.80264988
OS 15.96657716 23.80172532
OS 15.95918068 23.80172532
OS 15.95270876 23.80080076
OS 15.94808596 23.7998762
OS 15.94438772 23.7998762
OS 15.9425386 23.79895164
OS 15.94161404 23.79895164
OS 15.92682108 23.79432884
OS 15.92034916 23.79155516
OS 15.9148018 23.78878148
OS 15.90925444 23.7860078
OS 15.9055562 23.78415868
OS 15.90370708 23.78323412
OS 15.90278252 23.78230956
OS 15.89538604 23.7767622
OS 15.88798956 23.77029028
OS 15.87412116 23.75642188
OS 15.86764924 23.74994996
OS 15.86302644 23.7444026
OS 15.86025276 23.74070436
OS 15.8593282 23.7397798
OS 15.8500826 23.72683596
OS 15.83991244 23.71296756
OS 15.82974228 23.6981746
OS 15.81957212 23.6843062
OS 15.81125108 23.67136236
OS 15.80477916 23.6611922
OS 15.80200548 23.65749396
OS 15.80015636 23.65472028
OS 15.79830724 23.65287116
OS 15.79830724 23.6519466
OS 15.71417228 23.51880996
OS 15.60877244 23.51880996
OS 15.71879508 23.69262724
OS 15.73173892 23.71111844
OS 15.7437582 23.72776052
OS 15.75577748 23.74162892
OS 15.76594764 23.75457276
OS 15.77519324 23.76381836
OS 15.78258972 23.77121484
OS 15.78721252 23.77583764
OS 15.78906164 23.77768676
OS 15.79645812 23.78323412
OS 15.80477916 23.78970604
OS 15.82142124 23.7998762
OS 15.82881772 23.80357444
OS 15.83436508 23.80727268
OS 15.83806332 23.8091218
OS 15.83991244 23.81004636
OS 15.82327036 23.81282004
OS 15.80755284 23.81559372
OS 15.79368444 23.82021652
OS 15.77981604 23.82391476
OS 15.76779676 23.82853756
OS 15.75670204 23.83408492
OS 15.74653188 23.83870772
OS 15.73728628 23.84333052
OS 15.7298898 23.84887788
OS 15.72249332 23.85350068
OS 15.71694596 23.85719892
OS 15.71232316 23.86089716
OS 15.70862492 23.86367084
OS 15.70585124 23.86644452
OS 15.70492668 23.86736908
OS 15.70400212 23.86829364
OS 15.69660564 23.87753924
OS 15.68920916 23.88678484
OS 15.67811444 23.9062006
OS 15.67071796 23.92561636
OS 15.6651706 23.94410756
OS 15.66147236 23.95982508
OS 15.6605478 23.966297
OS 15.6605478 23.97276892
OS 15.65962324 23.97739172
OS 15.65962324 23.98108996
OS 15.65962324 23.98293908
OS 15.65962324 23.98386364
OS 15.6605478 24.0032794
OS 15.66332148 24.02084604
OS 15.66794428 24.03748812
OS 15.67256708 24.05135652
OS 15.67811444 24.0633758
OS 15.68181268 24.0726214
OS 15.68551092 24.07816876
OS 15.68643548 24.07909332
OS 15.68643548 24.08001788
OS 15.6975302 24.09481084
OS 15.70862492 24.10775468
OS 15.7206442 24.1188494
OS 15.73173892 24.12717044
OS 15.74190908 24.13364236
OS 15.75023012 24.1373406
OS 15.75577748 24.14011428
OS 15.75670204 24.14103884
OS 15.7576266 24.14103884
OS 15.76594764 24.14381252
OS 15.7761178 24.1465862
OS 15.79645812 24.151209
OS 15.81864756 24.15398268
OS 15.83898788 24.15675636
OS 15.85840364 24.15768092
OS 15.86672468 24.15768092
OE
OB 15.31938516 24.1604546 I
OS 15.32493252 24.16137916
OS 15.332329 24.16137916
OS 15.3508202 24.1604546
OS 15.36838684 24.15860548
OS 15.38502892 24.15490724
OS 15.40074644 24.15028444
OS 15.41461484 24.14381252
OS 15.42848324 24.13826516
OS 15.44050252 24.13086868
OS 15.45159724 24.12439676
OS 15.46084284 24.11792484
OS 15.47008844 24.11052836
OS 15.47748492 24.104981
OS 15.48303228 24.09943364
OS 15.48765508 24.09388628
OS 15.49135332 24.09018804
OS 15.49320244 24.08833892
OS 15.494127 24.08741436
OS 15.50614628 24.07077228
OS 15.51631644 24.05135652
OS 15.52556204 24.0310162
OS 15.53388308 24.00975132
OS 15.540355 23.98756188
OS 15.54590236 23.96537244
OS 15.55052516 23.94225844
OS 15.5542234 23.92099356
OS 15.55699708 23.89972868
OS 15.5588462 23.88031292
OS 15.56069532 23.86274628
OS 15.56161988 23.84795332
OS 15.56161988 23.83500948
OS 15.56254444 23.82576388
OS 15.56254444 23.82206564
OS 15.56254444 23.81929196
OS 15.56254444 23.8183674
OS 15.56254444 23.81744284
OS 15.56161988 23.78785692
OS 15.55977076 23.76012012
OS 15.55699708 23.73423244
OS 15.55237428 23.71019388
OS 15.54775148 23.688929
OS 15.54312868 23.66951324
OS 15.53758132 23.6519466
OS 15.5311094 23.63622908
OS 15.52556204 23.62328524
OS 15.52001468 23.61126596
OS 15.51539188 23.60202036
OS 15.50984452 23.59369932
OS 15.50614628 23.5872274
OS 15.5033726 23.58352916
OS 15.50152348 23.58075548
OS 15.50059892 23.57983092
OS 15.48857964 23.56688708
OS 15.4756358 23.55579236
OS 15.46269196 23.54654676
OS 15.44974812 23.53822572
OS 15.43587972 23.53082924
OS 15.42293588 23.52528188
OS 15.40999204 23.52065908
OS 15.3970482 23.51696084
OS 15.38595348 23.51418716
OS 15.37485876 23.51141348
OS 15.36561316 23.50956436
OS 15.35729212 23.5086398
OS 15.34989564 23.5086398
OS 15.34527284 23.50771524
OS 15.34065004 23.50771524
OS 15.31938516 23.5086398
OS 15.2999694 23.51233804
OS 15.28240276 23.51603628
OS 15.26668524 23.52158364
OS 15.25466596 23.52620644
OS 15.24542036 23.53082924
OS 15.24172212 23.5317538
OS 15.23894844 23.53360292
OS 15.23802388 23.53452748
OS 15.23709932 23.53452748
OS 15.2213818 23.5456222
OS 15.20658884 23.55856604
OS 15.19456956 23.57150988
OS 15.1843994 23.58445372
OS 15.17607836 23.596473
OS 15.170531 23.6057186
OS 15.16868188 23.60941684
OS 15.16683276 23.61219052
OS 15.1659082 23.61311508
OS 15.1659082 23.61403964
OS 15.1566626 23.6334554
OS 15.15019068 23.65379572
OS 15.14556788 23.67228692
OS 15.1427942 23.68985356
OS 15.14002052 23.70464652
OS 15.14002052 23.71019388
OS 15.13909596 23.71574124
OS 15.13909596 23.72036404
OS 15.13909596 23.72313772
OS 15.13909596 23.72498684
OS 15.13909596 23.7259114
OS 15.14002052 23.74255348
OS 15.14186964 23.758271
OS 15.14464332 23.77398852
OS 15.147417 23.78785692
OS 15.1520398 23.80080076
OS 15.1566626 23.8137446
OS 15.1612854 23.82483932
OS 15.16683276 23.83500948
OS 15.17238012 23.84425508
OS 15.17700292 23.85257612
OS 15.18162572 23.85904804
OS 15.18624852 23.86551996
OS 15.1890222 23.87014276
OS 15.19179588 23.87291644
OS 15.193645 23.87476556
OS 15.19456956 23.87569012
OS 15.20473972 23.88586028
OS 15.21583444 23.89510588
OS 15.22785372 23.90250236
OS 15.23894844 23.90897428
OS 15.25004316 23.9154462
OS 15.26113788 23.920069
OS 15.28240276 23.92654092
OS 15.29164836 23.9293146
OS 15.30089396 23.93116372
OS 15.30829044 23.93208828
OS 15.31568692 23.93301284
OS 15.32123428 23.9339374
OS 15.32863076 23.9339374
OS 15.34527284 23.93301284
OS 15.36099036 23.93023916
OS 15.37578332 23.92746548
OS 15.38872716 23.92376724
OS 15.39982188 23.91914444
OS 15.40814292 23.91637076
OS 15.41369028 23.91359708
OS 15.41461484 23.91267252
OS 15.4155394 23.91267252
OS 15.43033236 23.90342692
OS 15.4432762 23.89325676
OS 15.45529548 23.8830866
OS 15.46454108 23.87199188
OS 15.47286212 23.86274628
OS 15.47933404 23.8553498
OS 15.48303228 23.84980244
OS 15.48395684 23.84887788
OS 15.48395684 23.86551996
OS 15.48303228 23.88216204
OS 15.48210772 23.896955
OS 15.4802586 23.91174796
OS 15.47933404 23.9246918
OS 15.47748492 23.93671108
OS 15.4756358 23.9478058
OS 15.47286212 23.95797596
OS 15.471013 23.96722156
OS 15.46916388 23.97461804
OS 15.46731476 23.98108996
OS 15.4663902 23.98663732
OS 15.46454108 23.99033556
OS 15.46361652 23.99310924
OS 15.46269196 23.99495836
OS 15.46269196 23.99588292
OS 15.45344636 24.01437412
OS 15.44420076 24.0310162
OS 15.4340306 24.04396004
OS 15.424785 24.05505476
OS 15.41646396 24.06430036
OS 15.40999204 24.07077228
OS 15.40536924 24.07447052
OS 15.40352012 24.07539508
OS 15.3924254 24.08279156
OS 15.38133068 24.08741436
OS 15.37023596 24.0911126
OS 15.35914124 24.09388628
OS 15.3508202 24.0957354
OS 15.34342372 24.09665996
OS 15.3369518 24.09665996
OS 15.32030972 24.09481084
OS 15.3045922 24.0911126
OS 15.29164836 24.08556524
OS 15.27962908 24.08001788
OS 15.27038348 24.07354596
OS 15.26391156 24.0679986
OS 15.26021332 24.06430036
OS 15.2583642 24.06245124
OS 15.25189228 24.0541302
OS 15.24542036 24.04396004
OS 15.239873 24.03286532
OS 15.23617476 24.0217706
OS 15.23247652 24.01160044
OS 15.22970284 24.0032794
OS 15.22877828 23.99773204
OS 15.22785372 23.99680748
OS 15.22785372 23.99588292
OS 15.14926612 24.00235484
OS 15.15481348 24.02824252
OS 15.16313452 24.05135652
OS 15.17238012 24.07169684
OS 15.18255028 24.08833892
OS 15.19272044 24.10128276
OS 15.19641868 24.10683012
OS 15.20104148 24.11145292
OS 15.20381516 24.1142266
OS 15.20658884 24.11700028
OS 15.2075134 24.11792484
OS 15.20843796 24.1188494
OS 15.21768356 24.12624588
OS 15.22785372 24.1327178
OS 15.24819404 24.14381252
OS 15.26853436 24.151209
OS 15.28795012 24.1558318
OS 15.30551676 24.15953004
OS 15.31291324 24.1604546
OS 15.31938516 24.1604546
OE
OB 15.88429132 24.08741436 H
OS 15.8593282 24.0864898
OS 15.83806332 24.08279156
OS 15.81957212 24.07816876
OS 15.80570372 24.0726214
OS 15.79368444 24.06707404
OS 15.78628796 24.06245124
OS 15.78166516 24.058753
OS 15.77981604 24.05782844
OS 15.76872132 24.04580916
OS 15.76040028 24.03378988
OS 15.75485292 24.02084604
OS 15.75023012 24.00975132
OS 15.748381 23.9986566
OS 15.74745644 23.99033556
OS 15.74653188 23.9847882
OS 15.74653188 23.98386364
OS 15.74653188 23.98293908
OS 15.74745644 23.97184436
OS 15.74930556 23.96074964
OS 15.75207924 23.95150404
OS 15.75485292 23.943183
OS 15.75855116 23.93578652
OS 15.76132484 23.93023916
OS 15.76317396 23.92654092
OS 15.76409852 23.92561636
OS 15.77057044 23.91637076
OS 15.77889148 23.90804972
OS 15.78721252 23.9015778
OS 15.79553356 23.89603044
OS 15.80293004 23.8923322
OS 15.8084774 23.88955852
OS 15.81217564 23.8877094
OS 15.81402476 23.88678484
OS 15.8269686 23.8830866
OS 15.84176156 23.88031292
OS 15.85655452 23.8784638
OS 15.87134748 23.87753924
OS 15.88429132 23.87661468
OS 15.89538604 23.87569012
OS 16.0858454 23.87569012
OS 16.0858454 24.08741436
OS 15.88429132 24.08741436
OE
OB 15.34434828 23.8645954 H
OS 15.32493252 23.86274628
OS 15.30736588 23.85812348
OS 15.29257292 23.85257612
OS 15.27962908 23.84517964
OS 15.26945892 23.83778316
OS 15.26206244 23.8322358
OS 15.25743964 23.827613
OS 15.25559052 23.82576388
OS 15.24357124 23.81004636
OS 15.23432564 23.79340428
OS 15.22785372 23.77583764
OS 15.22415548 23.75919556
OS 15.2213818 23.7444026
OS 15.22045724 23.73793068
OS 15.22045724 23.73238332
OS 15.21953268 23.72776052
OS 15.21953268 23.72406228
OS 15.21953268 23.72221316
OS 15.21953268 23.7212886
OS 15.2213818 23.69632548
OS 15.22508004 23.6750606
OS 15.2306274 23.6565694
OS 15.23709932 23.64085188
OS 15.2444958 23.6288326
OS 15.25004316 23.619587
OS 15.2537414 23.61403964
OS 15.25559052 23.61311508
OS 15.25559052 23.61219052
OS 15.26206244 23.60479404
OS 15.26945892 23.59924668
OS 15.28425188 23.58907652
OS 15.29904484 23.5826046
OS 15.31198868 23.57705724
OS 15.32400796 23.57428356
OS 15.33325356 23.573359
OS 15.3369518 23.57243444
OS 15.3415746 23.57243444
OS 15.35451844 23.573359
OS 15.36653772 23.57520812
OS 15.37763244 23.57890636
OS 15.38687804 23.5826046
OS 15.39519908 23.58537828
OS 15.401671 23.58907652
OS 15.40536924 23.59092564
OS 15.40721836 23.5918502
OS 15.41831308 23.60017124
OS 15.42755868 23.60849228
OS 15.43587972 23.61866244
OS 15.44235164 23.62698348
OS 15.447899 23.63530452
OS 15.45159724 23.64177644
OS 15.45437092 23.64639924
OS 15.45529548 23.64824836
OS 15.46084284 23.66211676
OS 15.46454108 23.67598516
OS 15.46823932 23.688929
OS 15.47008844 23.70094828
OS 15.471013 23.71111844
OS 15.47193756 23.71943948
OS 15.47193756 23.72406228
OS 15.47193756 23.7259114
OS 15.47008844 23.74810084
OS 15.4663902 23.7675166
OS 15.45991828 23.78508324
OS 15.45344636 23.79895164
OS 15.44697444 23.81097092
OS 15.44050252 23.81929196
OS 15.43680428 23.82391476
OS 15.43495516 23.82576388
OS 15.4201622 23.83870772
OS 15.40536924 23.84795332
OS 15.38965172 23.8553498
OS 15.37578332 23.8599726
OS 15.36283948 23.86274628
OS 15.35359388 23.86367084
OS 15.34989564 23.8645954
OS 15.34434828 23.8645954
OE
SE
S P 0
OB 17.16903348 24.15906776 I
OS 17.17642996 24.15999232
OS 17.47321372 24.15999232
OS 17.47321372 23.5201968
OS 17.3881542 23.5201968
OS 17.3881542 23.80403672
OS 17.27905612 23.80403672
OS 17.26888596 23.80311216
OS 17.26148948 23.80311216
OS 17.25501756 23.8021876
OS 17.25039476 23.80126304
OS 17.24669652 23.80126304
OS 17.2448474 23.80033848
OS 17.24392284 23.80033848
OS 17.22912988 23.79571568
OS 17.22265796 23.792942
OS 17.2171106 23.79016832
OS 17.21156324 23.78739464
OS 17.207865 23.78554552
OS 17.20601588 23.78462096
OS 17.20509132 23.7836964
OS 17.19769484 23.77814904
OS 17.19029836 23.77167712
OS 17.17642996 23.75780872
OS 17.16995804 23.7513368
OS 17.16533524 23.74578944
OS 17.16256156 23.7420912
OS 17.161637 23.74116664
OS 17.1523914 23.7282228
OS 17.14222124 23.7143544
OS 17.13205108 23.69956144
OS 17.12188092 23.68569304
OS 17.11355988 23.6727492
OS 17.10708796 23.66257904
OS 17.10431428 23.6588808
OS 17.10246516 23.65610712
OS 17.10061604 23.654258
OS 17.10061604 23.65333344
OS 17.01648108 23.5201968
OS 16.91108124 23.5201968
OS 17.02110388 23.69401408
OS 17.03404772 23.71250528
OS 17.046067 23.72914736
OS 17.05808628 23.74301576
OS 17.06825644 23.7559596
OS 17.07750204 23.7652052
OS 17.08489852 23.77260168
OS 17.08952132 23.77722448
OS 17.09137044 23.7790736
OS 17.09876692 23.78462096
OS 17.10708796 23.79109288
OS 17.12373004 23.80126304
OS 17.13112652 23.80496128
OS 17.13667388 23.80865952
OS 17.14037212 23.81050864
OS 17.14222124 23.8114332
OS 17.12557916 23.81420688
OS 17.10986164 23.81698056
OS 17.09599324 23.82160336
OS 17.08212484 23.8253016
OS 17.07010556 23.8299244
OS 17.05901084 23.83547176
OS 17.04884068 23.84009456
OS 17.03959508 23.84471736
OS 17.0321986 23.85026472
OS 17.02480212 23.85488752
OS 17.01925476 23.85858576
OS 17.01463196 23.862284
OS 17.01093372 23.86505768
OS 17.00816004 23.86783136
OS 17.00723548 23.86875592
OS 17.00631092 23.86968048
OS 16.99891444 23.87892608
OS 16.99151796 23.88817168
OS 16.98042324 23.90758744
OS 16.97302676 23.9270032
OS 16.9674794 23.9454944
OS 16.96378116 23.96121192
OS 16.9628566 23.96768384
OS 16.9628566 23.97415576
OS 16.96193204 23.97877856
OS 16.96193204 23.9824768
OS 16.96193204 23.98432592
OS 16.96193204 23.98525048
OS 16.9628566 24.00466624
OS 16.96563028 24.02223288
OS 16.97025308 24.03887496
OS 16.97487588 24.05274336
OS 16.98042324 24.06476264
OS 16.98412148 24.07400824
OS 16.98781972 24.0795556
OS 16.98874428 24.08048016
OS 16.98874428 24.08140472
OS 16.999839 24.09619768
OS 17.01093372 24.10914152
OS 17.022953 24.12023624
OS 17.03404772 24.12855728
OS 17.04421788 24.1350292
OS 17.05253892 24.13872744
OS 17.05808628 24.14150112
OS 17.05901084 24.14242568
OS 17.0599354 24.14242568
OS 17.06825644 24.14519936
OS 17.0784266 24.14797304
OS 17.09876692 24.15259584
OS 17.12095636 24.15536952
OS 17.14129668 24.1581432
OS 17.16071244 24.15906776
OS 17.16903348 24.15906776
OE
OB 16.46729244 24.07678192 I
OS 16.46729244 24.15167128
OS 16.78534108 24.15167128
OS 16.8472866 23.82252792
OS 16.7733218 23.81235776
OS 16.76684988 23.82252792
OS 16.75852884 23.83084896
OS 16.75113236 23.83917
OS 16.74373588 23.84564192
OS 16.7363394 23.85026472
OS 16.73079204 23.85488752
OS 16.7270938 23.85673664
OS 16.72616924 23.8576612
OS 16.71414996 23.86320856
OS 16.70213068 23.86783136
OS 16.69103596 23.87060504
OS 16.67994124 23.87337872
OS 16.67069564 23.87430328
OS 16.66329916 23.87522784
OS 16.64573252 23.87522784
OS 16.6346378 23.87337872
OS 16.61522204 23.86875592
OS 16.59857996 23.862284
OS 16.583787 23.85581208
OS 16.57269228 23.8484156
OS 16.56437124 23.84194368
OS 16.55974844 23.83732088
OS 16.55789932 23.83639632
OS 16.55789932 23.83547176
OS 16.54495548 23.81975424
OS 16.53570988 23.80311216
OS 16.52923796 23.78554552
OS 16.52461516 23.76797888
OS 16.52184148 23.75318592
OS 16.52091692 23.746714
OS 16.52091692 23.74116664
OS 16.51999236 23.73654384
OS 16.51999236 23.7328456
OS 16.51999236 23.73099648
OS 16.51999236 23.73007192
OS 16.51999236 23.71712808
OS 16.52184148 23.7051088
OS 16.52646428 23.6819948
OS 16.5329362 23.66257904
OS 16.53940812 23.64686152
OS 16.5468046 23.63391768
OS 16.55327652 23.62374752
OS 16.5560502 23.62097384
OS 16.55789932 23.61820016
OS 16.55882388 23.6172756
OS 16.55974844 23.61635104
OS 16.56714492 23.60895456
OS 16.5745414 23.60248264
OS 16.59118348 23.59138792
OS 16.606901 23.58399144
OS 16.62261852 23.57936864
OS 16.63556236 23.5756704
OS 16.64665708 23.57474584
OS 16.65035532 23.57382128
OS 16.65590268 23.57382128
OS 16.67346932 23.57474584
OS 16.68918684 23.57844408
OS 16.70305524 23.58306688
OS 16.71414996 23.58861424
OS 16.72432012 23.5941616
OS 16.7317166 23.5987844
OS 16.73541484 23.60248264
OS 16.73726396 23.6034072
OS 16.74835868 23.61635104
OS 16.75760428 23.63021944
OS 16.76500076 23.64593696
OS 16.77054812 23.65980536
OS 16.77424636 23.67367376
OS 16.77702004 23.68384392
OS 16.7779446 23.68846672
OS 16.77886916 23.6912404
OS 16.77886916 23.69308952
OS 16.77886916 23.69401408
OS 16.861155 23.68754216
OS 16.85930588 23.6727492
OS 16.8565322 23.6588808
OS 16.84821116 23.63299312
OS 16.838041 23.61080368
OS 16.83249364 23.60063352
OS 16.82694628 23.59231248
OS 16.82232348 23.58399144
OS 16.81677612 23.57659496
OS 16.81215332 23.5710476
OS 16.80753052 23.5664248
OS 16.80383228 23.56272656
OS 16.80198316 23.55902832
OS 16.80013404 23.55810376
OS 16.79920948 23.5571792
OS 16.78811476 23.54885816
OS 16.77702004 23.54146168
OS 16.76500076 23.53498976
OS 16.75298148 23.5294424
OS 16.72986748 23.52112136
OS 16.70675348 23.515574
OS 16.69658332 23.51280032
OS 16.68641316 23.51187576
OS 16.67809212 23.5109512
OS 16.67069564 23.51002664
OS 16.66422372 23.50910208
OS 16.65590268 23.50910208
OS 16.63648692 23.51002664
OS 16.61799572 23.51280032
OS 16.60042908 23.51649856
OS 16.58471156 23.52112136
OS 16.5699186 23.52759328
OS 16.5560502 23.5340652
OS 16.54310636 23.54053712
OS 16.53201164 23.5479336
OS 16.52184148 23.55533008
OS 16.51259588 23.561802
OS 16.5051994 23.56919848
OS 16.49872748 23.57474584
OS 16.49410468 23.57936864
OS 16.49040644 23.58306688
OS 16.48855732 23.58584056
OS 16.48763276 23.58676512
OS 16.47838716 23.5987844
OS 16.47099068 23.61172824
OS 16.4635942 23.62374752
OS 16.45804684 23.63669136
OS 16.44880124 23.66165448
OS 16.44325388 23.68569304
OS 16.44140476 23.6958632
OS 16.43955564 23.70603336
OS 16.43863108 23.7143544
OS 16.43770652 23.72175088
OS 16.43678196 23.7282228
OS 16.43678196 23.7328456
OS 16.43678196 23.73561928
OS 16.43678196 23.73654384
OS 16.43770652 23.75318592
OS 16.43955564 23.76890344
OS 16.44232932 23.78462096
OS 16.44602756 23.79848936
OS 16.45065036 23.8114332
OS 16.45527316 23.82437704
OS 16.46082052 23.83547176
OS 16.46544332 23.84564192
OS 16.47099068 23.85488752
OS 16.47653804 23.86320856
OS 16.48116084 23.86968048
OS 16.48578364 23.8761524
OS 16.48948188 23.8807752
OS 16.49225556 23.88354888
OS 16.49410468 23.885398
OS 16.49502924 23.88632256
OS 16.50612396 23.89649272
OS 16.51721868 23.90573832
OS 16.52923796 23.9131348
OS 16.54125724 23.91960672
OS 16.55327652 23.92607864
OS 16.5652958 23.93070144
OS 16.58748524 23.93717336
OS 16.5976554 23.93994704
OS 16.606901 23.94179616
OS 16.61522204 23.94272072
OS 16.62261852 23.94364528
OS 16.62816588 23.94456984
OS 16.6485062 23.94456984
OS 16.65960092 23.94272072
OS 16.68179036 23.93809792
OS 16.70213068 23.931626
OS 16.72062188 23.92422952
OS 16.73541484 23.91683304
OS 16.74188676 23.9131348
OS 16.74743412 23.91036112
OS 16.75205692 23.90758744
OS 16.7548306 23.90573832
OS 16.75667972 23.90481376
OS 16.75760428 23.9038892
OS 16.72339556 24.07678192
OS 16.46729244 24.07678192
OE
OB 17.18660012 24.0888012 H
OS 17.161637 24.08787664
OS 17.14037212 24.0841784
OS 17.12188092 24.0795556
OS 17.10801252 24.07400824
OS 17.09599324 24.06846088
OS 17.08859676 24.06383808
OS 17.08397396 24.06013984
OS 17.08212484 24.05921528
OS 17.07103012 24.047196
OS 17.06270908 24.03517672
OS 17.05716172 24.02223288
OS 17.05253892 24.01113816
OS 17.0506898 24.00004344
OS 17.04976524 23.9917224
OS 17.04884068 23.98617504
OS 17.04884068 23.98525048
OS 17.04884068 23.98432592
OS 17.04976524 23.9732312
OS 17.05161436 23.96213648
OS 17.05438804 23.95289088
OS 17.05716172 23.94456984
OS 17.06085996 23.93717336
OS 17.06363364 23.931626
OS 17.06548276 23.92792776
OS 17.06640732 23.9270032
OS 17.07287924 23.9177576
OS 17.08120028 23.90943656
OS 17.08952132 23.90296464
OS 17.09784236 23.89741728
OS 17.10523884 23.89371904
OS 17.1107862 23.89094536
OS 17.11448444 23.88909624
OS 17.11633356 23.88817168
OS 17.1292774 23.88447344
OS 17.14407036 23.88169976
OS 17.15886332 23.87985064
OS 17.17365628 23.87892608
OS 17.18660012 23.87800152
OS 17.19769484 23.87707696
OS 17.3881542 23.87707696
OS 17.3881542 24.0888012
OS 17.18660012 24.0888012
OE
SE
S P 0
OB 17.16718436 25.09506792 I
OS 17.17365628 25.09599248
OS 17.18290188 25.09599248
OS 17.21341236 25.09414336
OS 17.24299828 25.08952056
OS 17.26888596 25.0839732
OS 17.28090524 25.08027496
OS 17.29199996 25.07657672
OS 17.30217012 25.07287848
OS 17.31141572 25.06918024
OS 17.3188122 25.06640656
OS 17.32620868 25.06363288
OS 17.33083148 25.0608592
OS 17.33452972 25.05901008
OS 17.3373034 25.05808552
OS 17.33822796 25.05716096
OS 17.36319108 25.04144344
OS 17.38445596 25.02295224
OS 17.40294716 25.00446104
OS 17.41866468 24.98596984
OS 17.43068396 24.96932776
OS 17.43530676 24.96193128
OS 17.439005 24.95545936
OS 17.44270324 24.95083656
OS 17.44455236 24.94713832
OS 17.44547692 24.94436464
OS 17.44640148 24.94344008
OS 17.45934532 24.91477872
OS 17.46859092 24.8851928
OS 17.47506284 24.85560688
OS 17.47968564 24.82879464
OS 17.48153476 24.81677536
OS 17.48245932 24.80475608
OS 17.48338388 24.79551048
OS 17.48338388 24.78626488
OS 17.48430844 24.77979296
OS 17.48430844 24.7742456
OS 17.48430844 24.77054736
OS 17.48430844 24.7696228
OS 17.48245932 24.73633864
OS 17.47876108 24.70397904
OS 17.47413828 24.67531768
OS 17.47044004 24.66144928
OS 17.46766636 24.64943
OS 17.46489268 24.63833528
OS 17.46119444 24.62816512
OS 17.45842076 24.61891952
OS 17.45657164 24.61152304
OS 17.45379796 24.60597568
OS 17.4528734 24.60135288
OS 17.45102428 24.5985792
OS 17.45102428 24.59765464
OS 17.43715588 24.56991784
OS 17.42143836 24.54495472
OS 17.40479628 24.52368984
OS 17.39647524 24.5153688
OS 17.38907876 24.50704776
OS 17.38168228 24.49965128
OS 17.3742858 24.49317936
OS 17.36781388 24.487632
OS 17.36226652 24.48393376
OS 17.35856828 24.48023552
OS 17.35487004 24.47746184
OS 17.35302092 24.47653728
OS 17.35209636 24.47561272
OS 17.33915252 24.46821624
OS 17.32620868 24.46174432
OS 17.29847188 24.45157416
OS 17.27073508 24.44417768
OS 17.24392284 24.43955488
OS 17.230979 24.43770576
OS 17.21988428 24.43585664
OS 17.20971412 24.43493208
OS 17.20139308 24.43493208
OS 17.1939966 24.43400752
OS 17.18382644 24.43400752
OS 17.16533524 24.43493208
OS 17.1477686 24.4367812
OS 17.13112652 24.43863032
OS 17.115409 24.44232856
OS 17.10061604 24.44695136
OS 17.08674764 24.45157416
OS 17.0738038 24.45619696
OS 17.06178452 24.46174432
OS 17.05161436 24.46636712
OS 17.0414442 24.47098992
OS 17.03404772 24.47561272
OS 17.02665124 24.48023552
OS 17.02202844 24.48393376
OS 17.01740564 24.48578288
OS 17.01555652 24.487632
OS 17.01463196 24.48855656
OS 17.00168812 24.49965128
OS 16.9905934 24.510746
OS 16.98042324 24.52368984
OS 16.97025308 24.53663368
OS 16.953611 24.56252136
OS 16.94066716 24.58840904
OS 16.9351198 24.60042832
OS 16.930497 24.61152304
OS 16.92679876 24.6216932
OS 16.92402508 24.63001424
OS 16.9212514 24.63741072
OS 16.91940228 24.64295808
OS 16.91847772 24.64665632
OS 16.91847772 24.64758088
OS 17.00353724 24.66884576
OS 17.00723548 24.6540528
OS 17.01185828 24.6401844
OS 17.01648108 24.62724056
OS 17.02110388 24.61522128
OS 17.02665124 24.60412656
OS 17.0321986 24.59488096
OS 17.03867052 24.58563536
OS 17.04421788 24.57731432
OS 17.04884068 24.56991784
OS 17.05438804 24.56437048
OS 17.05901084 24.55882312
OS 17.06270908 24.55420032
OS 17.06640732 24.55142664
OS 17.069181 24.54865296
OS 17.07010556 24.5477284
OS 17.07103012 24.54680384
OS 17.08027572 24.53940736
OS 17.09044588 24.53386
OS 17.1107862 24.52368984
OS 17.13020196 24.51629336
OS 17.14961772 24.51167056
OS 17.1662598 24.50797232
OS 17.17273172 24.50704776
OS 17.17920364 24.50704776
OS 17.184751 24.5061232
OS 17.19122292 24.5061232
OS 17.2124878 24.50704776
OS 17.23282812 24.510746
OS 17.25131932 24.5153688
OS 17.2679614 24.52091616
OS 17.28090524 24.52646352
OS 17.2864526 24.5292372
OS 17.2910754 24.53108632
OS 17.29477364 24.53293544
OS 17.29754732 24.53478456
OS 17.29939644 24.53570912
OS 17.300321 24.53570912
OS 17.31788764 24.54865296
OS 17.3326806 24.56252136
OS 17.34562444 24.57823888
OS 17.3557946 24.59303184
OS 17.36411564 24.60597568
OS 17.369663 24.6170704
OS 17.37151212 24.6216932
OS 17.37336124 24.62446688
OS 17.3742858 24.626316
OS 17.3742858 24.62724056
OS 17.38168228 24.65127912
OS 17.38722964 24.67531768
OS 17.39185244 24.69935624
OS 17.39462612 24.72154568
OS 17.39555068 24.73171584
OS 17.39647524 24.74096144
OS 17.39647524 24.74928248
OS 17.3973998 24.7557544
OS 17.3973998 24.76130176
OS 17.3973998 24.76592456
OS 17.3973998 24.76869824
OS 17.3973998 24.7696228
OS 17.39647524 24.79366136
OS 17.39462612 24.8158508
OS 17.39092788 24.83619112
OS 17.38722964 24.85468232
OS 17.38445596 24.87039984
OS 17.38260684 24.87687176
OS 17.38075772 24.88241912
OS 17.37983316 24.88704192
OS 17.3789086 24.8898156
OS 17.37798404 24.89166472
OS 17.37798404 24.89258928
OS 17.36873844 24.91385416
OS 17.35856828 24.93326992
OS 17.34747356 24.94898744
OS 17.33545428 24.96285584
OS 17.32528412 24.97395056
OS 17.31696308 24.98134704
OS 17.31049116 24.98596984
OS 17.3095666 24.98781896
OS 17.30864204 24.98781896
OS 17.28922628 24.99983824
OS 17.2679614 25.00908384
OS 17.24762108 25.01555576
OS 17.22820532 25.019254
OS 17.21063868 25.02202768
OS 17.2032422 25.02295224
OS 17.19677028 25.02295224
OS 17.19214748 25.0238768
OS 17.184751 25.0238768
OS 17.161637 25.02295224
OS 17.14037212 25.019254
OS 17.12280548 25.01370664
OS 17.10708796 25.00815928
OS 17.09506868 25.00168736
OS 17.08582308 24.99706456
OS 17.08027572 24.99336632
OS 17.0784266 24.9915172
OS 17.06363364 24.9776488
OS 17.04976524 24.96193128
OS 17.03867052 24.9452892
OS 17.02942492 24.92864712
OS 17.02202844 24.91385416
OS 17.01925476 24.90645768
OS 17.01740564 24.90091032
OS 17.01555652 24.89628752
OS 17.0137074 24.89258928
OS 17.01278284 24.89074016
OS 17.01278284 24.8898156
OS 16.92957244 24.90923136
OS 16.9351198 24.92587344
OS 16.94066716 24.9406664
OS 16.94806364 24.9545348
OS 16.95453556 24.9684032
OS 16.96193204 24.98042248
OS 16.97025308 24.9915172
OS 16.97764956 25.00261192
OS 16.98504604 25.01185752
OS 16.99244252 25.019254
OS 16.99891444 25.02665048
OS 17.00538636 25.0331224
OS 17.01000916 25.0377452
OS 17.01463196 25.042368
OS 17.0183302 25.04514168
OS 17.02017932 25.04606624
OS 17.02110388 25.0469908
OS 17.03404772 25.05531184
OS 17.04699156 25.06363288
OS 17.0599354 25.0701048
OS 17.0738038 25.07565216
OS 17.1015406 25.0839732
OS 17.12650372 25.08952056
OS 17.138523 25.09229424
OS 17.14869316 25.0932188
OS 17.15886332 25.09414336
OS 17.16718436 25.09506792
OE
OB 16.6346378 25.08674688 I
OS 16.6392606 25.08767144
OS 16.64573252 25.08767144
OS 16.66145004 25.08674688
OS 16.676243 25.08489776
OS 16.69103596 25.08212408
OS 16.7039798 25.07842584
OS 16.72894292 25.06825568
OS 16.74003764 25.06363288
OS 16.74928324 25.05808552
OS 16.75852884 25.0516136
OS 16.76592532 25.0469908
OS 16.7733218 25.04144344
OS 16.77886916 25.03682064
OS 16.78349196 25.0331224
OS 16.78626564 25.03034872
OS 16.78811476 25.0284996
OS 16.78903932 25.02757504
OS 16.79920948 25.01648032
OS 16.80753052 25.00353648
OS 16.81585156 24.9915172
OS 16.82232348 24.97857336
OS 16.82787084 24.96470496
OS 16.83249364 24.95176112
OS 16.83896556 24.92772256
OS 16.84173924 24.91570328
OS 16.84358836 24.90553312
OS 16.84451292 24.89536296
OS 16.84543748 24.88704192
OS 16.84636204 24.88057
OS 16.84636204 24.8759472
OS 16.84636204 24.87224896
OS 16.84636204 24.8713244
OS 16.84543748 24.85375776
OS 16.84358836 24.83804024
OS 16.84173924 24.82232272
OS 16.838041 24.80752976
OS 16.8334182 24.79458592
OS 16.8287954 24.78164208
OS 16.8241726 24.77054736
OS 16.81862524 24.7603772
OS 16.81400244 24.7511316
OS 16.80937964 24.74281056
OS 16.80475684 24.73633864
OS 16.80013404 24.72986672
OS 16.7964358 24.72524392
OS 16.79458668 24.72247024
OS 16.79273756 24.72062112
OS 16.791813 24.71969656
OS 16.78164284 24.7095264
OS 16.77054812 24.70120536
OS 16.7594534 24.69288432
OS 16.74743412 24.6864124
OS 16.7363394 24.68086504
OS 16.72524468 24.67624224
OS 16.7039798 24.66977032
OS 16.6947342 24.66699664
OS 16.6854886 24.66514752
OS 16.67809212 24.66422296
OS 16.67069564 24.6632984
OS 16.66514828 24.66237384
OS 16.6577518 24.66237384
OS 16.64018516 24.6632984
OS 16.62354308 24.66607208
OS 16.60875012 24.66977032
OS 16.59488172 24.67439312
OS 16.58471156 24.67809136
OS 16.57639052 24.6817896
OS 16.57084316 24.68456328
OS 16.56899404 24.68548784
OS 16.55420108 24.69473344
OS 16.54125724 24.7049036
OS 16.53016252 24.71507376
OS 16.52091692 24.72431936
OS 16.514445 24.73356496
OS 16.50889764 24.74003688
OS 16.5051994 24.74465968
OS 16.50427484 24.7465088
OS 16.50427484 24.73911232
OS 16.50427484 24.73448952
OS 16.50427484 24.73171584
OS 16.50427484 24.73079128
OS 16.5051994 24.71230008
OS 16.50612396 24.69473344
OS 16.50797308 24.67901592
OS 16.5098222 24.66422296
OS 16.51259588 24.65220368
OS 16.514445 24.64295808
OS 16.51536956 24.63925984
OS 16.51536956 24.63648616
OS 16.51629412 24.6355616
OS 16.51629412 24.63463704
OS 16.52091692 24.61799496
OS 16.52553972 24.603202
OS 16.53016252 24.59025816
OS 16.53478532 24.57916344
OS 16.53848356 24.5708424
OS 16.5421818 24.56437048
OS 16.54403092 24.55974768
OS 16.54495548 24.55882312
OS 16.55235196 24.54865296
OS 16.55974844 24.54033192
OS 16.56714492 24.53293544
OS 16.5745414 24.52646352
OS 16.58008876 24.52091616
OS 16.58563612 24.51721792
OS 16.58933436 24.5153688
OS 16.59025892 24.51444424
OS 16.60042908 24.50889688
OS 16.6115238 24.50519864
OS 16.62169396 24.50242496
OS 16.63186412 24.50057584
OS 16.64018516 24.49965128
OS 16.64665708 24.49872672
OS 16.653129 24.49872672
OS 16.66792196 24.49965128
OS 16.68179036 24.50242496
OS 16.69380964 24.5061232
OS 16.7039798 24.510746
OS 16.71137628 24.51444424
OS 16.7178482 24.51814248
OS 16.72154644 24.52091616
OS 16.722471 24.52184072
OS 16.7317166 24.53201088
OS 16.73911308 24.54403016
OS 16.745585 24.556974
OS 16.7502078 24.56991784
OS 16.75390604 24.58101256
OS 16.75667972 24.59118272
OS 16.75760428 24.59488096
OS 16.75760428 24.59673008
OS 16.75852884 24.5985792
OS 16.75852884 24.59950376
OS 16.83434276 24.59303184
OS 16.8287954 24.5662196
OS 16.82139892 24.5431056
OS 16.81215332 24.52276528
OS 16.80290772 24.5061232
OS 16.79366212 24.49317936
OS 16.78903932 24.487632
OS 16.78534108 24.4830092
OS 16.7825674 24.48023552
OS 16.77979372 24.47746184
OS 16.77886916 24.47653728
OS 16.7779446 24.47561272
OS 16.768699 24.46821624
OS 16.75852884 24.46174432
OS 16.73818852 24.45157416
OS 16.7178482 24.44417768
OS 16.69843244 24.43955488
OS 16.6808658 24.43585664
OS 16.67346932 24.43493208
OS 16.6669974 24.43493208
OS 16.6623746 24.43400752
OS 16.65497812 24.43400752
OS 16.62909044 24.43585664
OS 16.60597644 24.43955488
OS 16.58471156 24.4460268
OS 16.56714492 24.45342328
OS 16.55974844 24.45619696
OS 16.55235196 24.4598952
OS 16.5468046 24.46359344
OS 16.54125724 24.46636712
OS 16.537559 24.46821624
OS 16.53478532 24.47006536
OS 16.5329362 24.47191448
OS 16.53201164 24.47191448
OS 16.51352044 24.487632
OS 16.49687836 24.50519864
OS 16.48393452 24.52368984
OS 16.4728398 24.54125648
OS 16.4635942 24.556974
OS 16.45989596 24.56437048
OS 16.45712228 24.56991784
OS 16.45527316 24.5754652
OS 16.45342404 24.57916344
OS 16.45249948 24.58101256
OS 16.45249948 24.58193712
OS 16.44787668 24.59580552
OS 16.44325388 24.61152304
OS 16.43678196 24.64295808
OS 16.43215916 24.67624224
OS 16.42938548 24.70767728
OS 16.42753636 24.72154568
OS 16.4266118 24.73541408
OS 16.4266118 24.74743336
OS 16.42568724 24.75760352
OS 16.42568724 24.76592456
OS 16.42568724 24.77239648
OS 16.42568724 24.77701928
OS 16.42568724 24.77794384
OS 16.42568724 24.79920872
OS 16.4266118 24.81954904
OS 16.42846092 24.83804024
OS 16.43031004 24.85560688
OS 16.43215916 24.8713244
OS 16.43400828 24.88611736
OS 16.43678196 24.89998576
OS 16.43955564 24.91200504
OS 16.44232932 24.9221752
OS 16.44417844 24.9314208
OS 16.44695212 24.93974184
OS 16.44880124 24.94621376
OS 16.45065036 24.95083656
OS 16.45249948 24.9545348
OS 16.45342404 24.95638392
OS 16.45342404 24.95730848
OS 16.46451876 24.97949792
OS 16.47653804 24.99891368
OS 16.49040644 25.01555576
OS 16.50242572 25.02942416
OS 16.514445 25.03959432
OS 16.5236906 25.0469908
OS 16.52738884 25.04976448
OS 16.53016252 25.0516136
OS 16.53108708 25.05346272
OS 16.53201164 25.05346272
OS 16.5514274 25.06455744
OS 16.57084316 25.07287848
OS 16.59025892 25.0793504
OS 16.60782556 25.08304864
OS 16.62354308 25.08582232
OS 16.630015 25.08674688
OS 16.6346378 25.08674688
OE
OB 16.62631676 25.02295224 H
OS 16.61707116 25.02110312
OS 16.60042908 25.01648032
OS 16.58563612 25.0100084
OS 16.57269228 25.00353648
OS 16.56252212 24.99614
OS 16.55512564 24.98966808
OS 16.55050284 24.98504528
OS 16.54865372 24.98412072
OS 16.54865372 24.98319616
OS 16.53663444 24.96747864
OS 16.52738884 24.949912
OS 16.52091692 24.9314208
OS 16.51721868 24.91385416
OS 16.514445 24.8990612
OS 16.51352044 24.89258928
OS 16.51352044 24.88611736
OS 16.51259588 24.88149456
OS 16.51259588 24.87779632
OS 16.51259588 24.8759472
OS 16.51259588 24.87502264
OS 16.514445 24.85098408
OS 16.51814324 24.8297192
OS 16.5236906 24.81215256
OS 16.53016252 24.7973596
OS 16.537559 24.78534032
OS 16.54310636 24.77701928
OS 16.5468046 24.77147192
OS 16.54865372 24.7696228
OS 16.56252212 24.75667896
OS 16.57731508 24.74743336
OS 16.59210804 24.74096144
OS 16.606901 24.73633864
OS 16.61892028 24.73356496
OS 16.62909044 24.7326404
OS 16.63278868 24.73171584
OS 16.63833604 24.73171584
OS 16.6577518 24.73356496
OS 16.67531844 24.7372632
OS 16.69103596 24.74373512
OS 16.70490436 24.7511316
OS 16.71507452 24.75760352
OS 16.72339556 24.76407544
OS 16.72801836 24.76777368
OS 16.72986748 24.7696228
OS 16.74188676 24.78441576
OS 16.75113236 24.80105784
OS 16.75667972 24.81769992
OS 16.76130252 24.83341744
OS 16.7640762 24.84728584
OS 16.76500076 24.8528332
OS 16.76500076 24.85838056
OS 16.76592532 24.86300336
OS 16.76592532 24.86577704
OS 16.76592532 24.86762616
OS 16.76592532 24.86855072
OS 16.7640762 24.89258928
OS 16.76037796 24.91477872
OS 16.75390604 24.93419448
OS 16.74650956 24.949912
OS 16.74003764 24.96285584
OS 16.73356572 24.97210144
OS 16.7317166 24.97487512
OS 16.72986748 24.9776488
OS 16.72801836 24.97857336
OS 16.72801836 24.97949792
OS 16.72062188 24.9868944
OS 16.7132254 24.99429088
OS 16.69750788 25.00446104
OS 16.68179036 25.01278208
OS 16.6669974 25.01740488
OS 16.65497812 25.02110312
OS 16.64480796 25.02202768
OS 16.64110972 25.02295224
OS 16.62631676 25.02295224
OE
SE
S P 0
OB 19.33922472 22.53186756 I
OS 19.34569664 22.53279212
OS 19.35494224 22.53279212
OS 19.38545272 22.530943
OS 19.41503864 22.5263202
OS 19.44092632 22.52077284
OS 19.4529456 22.5170746
OS 19.46404032 22.51337636
OS 19.47421048 22.50967812
OS 19.48345608 22.50597988
OS 19.49085256 22.5032062
OS 19.49824904 22.50043252
OS 19.50287184 22.49765884
OS 19.50657008 22.49580972
OS 19.50934376 22.49488516
OS 19.51026832 22.4939606
OS 19.53523144 22.47824308
OS 19.55649632 22.45975188
OS 19.57498752 22.44126068
OS 19.59070504 22.42276948
OS 19.60272432 22.4061274
OS 19.60734712 22.39873092
OS 19.61104536 22.392259
OS 19.6147436 22.3876362
OS 19.61659272 22.38393796
OS 19.61751728 22.38116428
OS 19.61844184 22.38023972
OS 19.63138568 22.35157836
OS 19.64063128 22.32199244
OS 19.6471032 22.29240652
OS 19.651726 22.26559428
OS 19.65357512 22.253575
OS 19.65449968 22.24155572
OS 19.65542424 22.23231012
OS 19.65542424 22.22306452
OS 19.6563488 22.2165926
OS 19.6563488 22.21104524
OS 19.6563488 22.207347
OS 19.6563488 22.20642244
OS 19.65449968 22.17313828
OS 19.65080144 22.14077868
OS 19.64617864 22.11211732
OS 19.6424804 22.09824892
OS 19.63970672 22.08622964
OS 19.63693304 22.07513492
OS 19.6332348 22.06496476
OS 19.63046112 22.05571916
OS 19.628612 22.04832268
OS 19.62583832 22.04277532
OS 19.62491376 22.03815252
OS 19.62306464 22.03537884
OS 19.62306464 22.03445428
OS 19.60919624 22.00671748
OS 19.59347872 21.98175436
OS 19.57683664 21.96048948
OS 19.5685156 21.95216844
OS 19.56111912 21.9438474
OS 19.55372264 21.93645092
OS 19.54632616 21.929979
OS 19.53985424 21.92443164
OS 19.53430688 21.9207334
OS 19.53060864 21.91703516
OS 19.5269104 21.91426148
OS 19.52506128 21.91333692
OS 19.52413672 21.91241236
OS 19.51119288 21.90501588
OS 19.49824904 21.89854396
OS 19.47051224 21.8883738
OS 19.44277544 21.88097732
OS 19.4159632 21.87635452
OS 19.40301936 21.8745054
OS 19.39192464 21.87265628
OS 19.38175448 21.87173172
OS 19.37343344 21.87173172
OS 19.36603696 21.87080716
OS 19.3558668 21.87080716
OS 19.3373756 21.87173172
OS 19.31980896 21.87358084
OS 19.30316688 21.87542996
OS 19.28744936 21.8791282
OS 19.2726564 21.883751
OS 19.258788 21.8883738
OS 19.24584416 21.8929966
OS 19.23382488 21.89854396
OS 19.22365472 21.90316676
OS 19.21348456 21.90778956
OS 19.20608808 21.91241236
OS 19.1986916 21.91703516
OS 19.1940688 21.9207334
OS 19.189446 21.92258252
OS 19.18759688 21.92443164
OS 19.18667232 21.9253562
OS 19.17372848 21.93645092
OS 19.16263376 21.94754564
OS 19.1524636 21.96048948
OS 19.14229344 21.97343332
OS 19.12565136 21.999321
OS 19.11270752 22.02520868
OS 19.10716016 22.03722796
OS 19.10253736 22.04832268
OS 19.09883912 22.05849284
OS 19.09606544 22.06681388
OS 19.09329176 22.07421036
OS 19.09144264 22.07975772
OS 19.09051808 22.08345596
OS 19.09051808 22.08438052
OS 19.1755776 22.1056454
OS 19.17927584 22.09085244
OS 19.18389864 22.07698404
OS 19.18852144 22.0640402
OS 19.19314424 22.05202092
OS 19.1986916 22.0409262
OS 19.20423896 22.0316806
OS 19.21071088 22.022435
OS 19.21625824 22.01411396
OS 19.22088104 22.00671748
OS 19.2264284 22.00117012
OS 19.2310512 21.99562276
OS 19.23474944 21.99099996
OS 19.23844768 21.98822628
OS 19.24122136 21.9854526
OS 19.24214592 21.98452804
OS 19.24307048 21.98360348
OS 19.25231608 21.976207
OS 19.26248624 21.97065964
OS 19.28282656 21.96048948
OS 19.30224232 21.953093
OS 19.32165808 21.9484702
OS 19.33830016 21.94477196
OS 19.34477208 21.9438474
OS 19.351244 21.9438474
OS 19.35679136 21.94292284
OS 19.36326328 21.94292284
OS 19.38452816 21.9438474
OS 19.40486848 21.94754564
OS 19.42335968 21.95216844
OS 19.44000176 21.9577158
OS 19.4529456 21.96326316
OS 19.45849296 21.96603684
OS 19.46311576 21.96788596
OS 19.466814 21.96973508
OS 19.46958768 21.9715842
OS 19.4714368 21.97250876
OS 19.47236136 21.97250876
OS 19.489928 21.9854526
OS 19.50472096 21.999321
OS 19.5176648 22.01503852
OS 19.52783496 22.02983148
OS 19.536156 22.04277532
OS 19.54170336 22.05387004
OS 19.54355248 22.05849284
OS 19.5454016 22.06126652
OS 19.54632616 22.06311564
OS 19.54632616 22.0640402
OS 19.55372264 22.08807876
OS 19.55927 22.11211732
OS 19.5638928 22.13615588
OS 19.56666648 22.15834532
OS 19.56759104 22.16851548
OS 19.5685156 22.17776108
OS 19.5685156 22.18608212
OS 19.56944016 22.19255404
OS 19.56944016 22.1981014
OS 19.56944016 22.2027242
OS 19.56944016 22.20549788
OS 19.56944016 22.20642244
OS 19.5685156 22.230461
OS 19.56666648 22.25265044
OS 19.56296824 22.27299076
OS 19.55927 22.29148196
OS 19.55649632 22.30719948
OS 19.5546472 22.3136714
OS 19.55279808 22.31921876
OS 19.55187352 22.32384156
OS 19.55094896 22.32661524
OS 19.5500244 22.32846436
OS 19.5500244 22.32938892
OS 19.5407788 22.3506538
OS 19.53060864 22.37006956
OS 19.51951392 22.38578708
OS 19.50749464 22.39965548
OS 19.49732448 22.4107502
OS 19.48900344 22.41814668
OS 19.48253152 22.42276948
OS 19.48160696 22.4246186
OS 19.4806824 22.4246186
OS 19.46126664 22.43663788
OS 19.44000176 22.44588348
OS 19.41966144 22.4523554
OS 19.40024568 22.45605364
OS 19.38267904 22.45882732
OS 19.37528256 22.45975188
OS 19.36881064 22.45975188
OS 19.36418784 22.46067644
OS 19.35679136 22.46067644
OS 19.33367736 22.45975188
OS 19.31241248 22.45605364
OS 19.29484584 22.45050628
OS 19.27912832 22.44495892
OS 19.26710904 22.438487
OS 19.25786344 22.4338642
OS 19.25231608 22.43016596
OS 19.25046696 22.42831684
OS 19.235674 22.41444844
OS 19.2218056 22.39873092
OS 19.21071088 22.38208884
OS 19.20146528 22.36544676
OS 19.1940688 22.3506538
OS 19.19129512 22.34325732
OS 19.189446 22.33770996
OS 19.18759688 22.33308716
OS 19.18574776 22.32938892
OS 19.1848232 22.3275398
OS 19.1848232 22.32661524
OS 19.1016128 22.346031
OS 19.10716016 22.36267308
OS 19.11270752 22.37746604
OS 19.120104 22.39133444
OS 19.12657592 22.40520284
OS 19.1339724 22.41722212
OS 19.14229344 22.42831684
OS 19.14968992 22.43941156
OS 19.1570864 22.44865716
OS 19.16448288 22.45605364
OS 19.1709548 22.46345012
OS 19.17742672 22.46992204
OS 19.18204952 22.47454484
OS 19.18667232 22.47916764
OS 19.19037056 22.48194132
OS 19.19221968 22.48286588
OS 19.19314424 22.48379044
OS 19.20608808 22.49211148
OS 19.21903192 22.50043252
OS 19.23197576 22.50690444
OS 19.24584416 22.5124518
OS 19.27358096 22.52077284
OS 19.29854408 22.5263202
OS 19.31056336 22.52909388
OS 19.32073352 22.53001844
OS 19.33090368 22.530943
OS 19.33922472 22.53186756
OE
OB 18.79835712 22.52354652 I
OS 18.80852728 22.52447108
OS 18.83164128 22.52447108
OS 18.84458512 22.52262196
OS 18.86954824 22.51799916
OS 18.89081312 22.51060268
OS 18.90930432 22.5032062
OS 18.91762536 22.4985834
OS 18.92409728 22.49488516
OS 18.9305692 22.49118692
OS 18.935192 22.48748868
OS 18.93889024 22.484715
OS 18.94166392 22.48286588
OS 18.94351304 22.48194132
OS 18.9444376 22.48101676
OS 18.96200424 22.46345012
OS 18.97587264 22.44403436
OS 18.98696736 22.42369404
OS 18.99621296 22.40335372
OS 19.00176032 22.38578708
OS 19.004534 22.3783906
OS 19.00638312 22.37191868
OS 19.00730768 22.36637132
OS 19.00823224 22.36267308
OS 19.0091568 22.3598994
OS 19.0091568 22.35897484
OS 18.9305692 22.34510644
OS 18.92687096 22.36544676
OS 18.9213236 22.3830134
OS 18.91485168 22.39780636
OS 18.90837976 22.40982564
OS 18.90190784 22.41907124
OS 18.89636048 22.42554316
OS 18.89266224 22.43016596
OS 18.89173768 22.43109052
OS 18.8797184 22.44033612
OS 18.86677456 22.4477326
OS 18.85475528 22.4523554
OS 18.842736 22.45605364
OS 18.83164128 22.45790276
OS 18.82332024 22.45975188
OS 18.81592376 22.45975188
OS 18.79928168 22.45882732
OS 18.78448872 22.45512908
OS 18.77154488 22.45050628
OS 18.76045016 22.44588348
OS 18.75212912 22.44033612
OS 18.7456572 22.43571332
OS 18.7410344 22.43201508
OS 18.74010984 22.43109052
OS 18.72993968 22.4199958
OS 18.7225432 22.40797652
OS 18.7179204 22.39595724
OS 18.71422216 22.38486252
OS 18.71237304 22.37469236
OS 18.71052392 22.36729588
OS 18.71052392 22.36174852
OS 18.71052392 22.36082396
OS 18.71052392 22.3598994
OS 18.71052392 22.34972924
OS 18.71237304 22.34048364
OS 18.71699584 22.32476612
OS 18.72346776 22.31089772
OS 18.73086424 22.29887844
OS 18.73826072 22.2905574
OS 18.74473264 22.28408548
OS 18.74935544 22.28038724
OS 18.75028 22.27946268
OS 18.75120456 22.27946268
OS 18.76692208 22.27114164
OS 18.78171504 22.26466972
OS 18.79743256 22.26004692
OS 18.81130096 22.25727324
OS 18.82332024 22.25542412
OS 18.8334904 22.253575
OS 18.84550968 22.253575
OS 18.84920792 22.25449956
OS 18.85383072 22.25449956
OS 18.86307632 22.18515756
OS 18.85105704 22.18793124
OS 18.83996232 22.18978036
OS 18.83071672 22.19162948
OS 18.82239568 22.19255404
OS 18.81592376 22.1934786
OS 18.80760272 22.1934786
OS 18.78818696 22.19162948
OS 18.77062032 22.18793124
OS 18.7549028 22.18238388
OS 18.74195896 22.17591196
OS 18.7317888 22.16944004
OS 18.72439232 22.16389268
OS 18.71976952 22.16019444
OS 18.7179204 22.15834532
OS 18.70590112 22.14447692
OS 18.69665552 22.12968396
OS 18.6901836 22.114891
OS 18.68648536 22.10009804
OS 18.68371168 22.08807876
OS 18.68278712 22.0779086
OS 18.68186256 22.07421036
OS 18.68186256 22.07143668
OS 18.68186256 22.06958756
OS 18.68186256 22.068663
OS 18.68371168 22.04832268
OS 18.68833448 22.02983148
OS 18.69388184 22.01411396
OS 18.70127832 22.00024556
OS 18.7086748 21.98915084
OS 18.71422216 21.9808298
OS 18.71884496 21.97528244
OS 18.72069408 21.97343332
OS 18.73548704 21.96048948
OS 18.75120456 21.95124388
OS 18.76692208 21.94477196
OS 18.78171504 21.94014916
OS 18.79465888 21.93737548
OS 18.80482904 21.93645092
OS 18.80852728 21.93552636
OS 18.81407464 21.93552636
OS 18.83071672 21.93645092
OS 18.84643424 21.94014916
OS 18.86030264 21.94477196
OS 18.87139736 21.95031932
OS 18.88064296 21.95494212
OS 18.88803944 21.95956492
OS 18.89173768 21.96326316
OS 18.8935868 21.96418772
OS 18.90468152 21.97713156
OS 18.91392712 21.99192452
OS 18.92224816 22.00764204
OS 18.92872008 22.02428412
OS 18.93334288 22.03815252
OS 18.935192 22.04462444
OS 18.93611656 22.0501718
OS 18.93704112 22.0547946
OS 18.93796568 22.05849284
OS 18.93889024 22.06034196
OS 18.93889024 22.06126652
OS 19.01747784 22.05109636
OS 19.01562872 22.0363034
OS 19.01285504 22.022435
OS 19.004534 21.99654732
OS 18.99436384 21.97435788
OS 18.98881648 21.96511228
OS 18.98326912 21.95586668
OS 18.97772176 21.94754564
OS 18.9721744 21.94107372
OS 18.9675516 21.9346018
OS 18.9629288 21.929979
OS 18.96015512 21.92628076
OS 18.95738144 21.92350708
OS 18.95553232 21.92165796
OS 18.95460776 21.9207334
OS 18.94351304 21.91241236
OS 18.93241832 21.90409132
OS 18.9213236 21.8976194
OS 18.90930432 21.89207204
OS 18.88619032 21.88282644
OS 18.86400088 21.87727908
OS 18.85383072 21.87542996
OS 18.84458512 21.87358084
OS 18.83626408 21.87265628
OS 18.8288676 21.87173172
OS 18.82332024 21.87080716
OS 18.8149992 21.87080716
OS 18.79743256 21.87173172
OS 18.78171504 21.87358084
OS 18.76599752 21.87635452
OS 18.75120456 21.88005276
OS 18.73733616 21.88467556
OS 18.72531688 21.88929836
OS 18.7132976 21.89484572
OS 18.70312744 21.90039308
OS 18.69295728 21.90501588
OS 18.68463624 21.91056324
OS 18.67723976 21.91518604
OS 18.6716924 21.91980884
OS 18.6670696 21.92350708
OS 18.66337136 21.92628076
OS 18.66152224 21.92812988
OS 18.66059768 21.92905444
OS 18.64950296 21.94014916
OS 18.64025736 21.95216844
OS 18.63193632 21.96418772
OS 18.62453984 21.976207
OS 18.61899248 21.98730172
OS 18.61344512 21.999321
OS 18.60604864 22.02151044
OS 18.60419952 22.0316806
OS 18.6023504 22.0409262
OS 18.60050128 22.04924724
OS 18.59957672 22.05664372
OS 18.59865216 22.06219108
OS 18.59865216 22.06681388
OS 18.59865216 22.06958756
OS 18.59865216 22.07051212
OS 18.59957672 22.09270156
OS 18.60327496 22.11304188
OS 18.60882232 22.13060852
OS 18.61436968 22.14540148
OS 18.61991704 22.15742076
OS 18.6254644 22.16666636
OS 18.62916264 22.17221372
OS 18.6300872 22.17406284
OS 18.64303104 22.18793124
OS 18.65689944 22.19995052
OS 18.6716924 22.20919612
OS 18.68648536 22.2165926
OS 18.6994292 22.22213996
OS 18.70959936 22.2258382
OS 18.7132976 22.22676276
OS 18.71607128 22.22768732
OS 18.7179204 22.22861188
OS 18.71884496 22.22861188
OS 18.70312744 22.23693292
OS 18.6901836 22.24525396
OS 18.67908888 22.25449956
OS 18.66984328 22.2628206
OS 18.6624468 22.27021708
OS 18.65689944 22.276689
OS 18.65412576 22.28038724
OS 18.6532012 22.28223636
OS 18.64580472 22.2951802
OS 18.64025736 22.30812404
OS 18.63563456 22.32106788
OS 18.63286088 22.33308716
OS 18.63101176 22.34325732
OS 18.6300872 22.3506538
OS 18.6300872 22.35620116
OS 18.6300872 22.35805028
OS 18.63101176 22.3737678
OS 18.63378544 22.38948532
OS 18.63748368 22.40335372
OS 18.64210648 22.415373
OS 18.64672928 22.42554316
OS 18.65042752 22.4338642
OS 18.6532012 22.438487
OS 18.65412576 22.44033612
OS 18.66337136 22.45420452
OS 18.67446608 22.4662238
OS 18.6855608 22.47639396
OS 18.69665552 22.48563956
OS 18.70590112 22.49211148
OS 18.71422216 22.49765884
OS 18.71976952 22.50043252
OS 18.72069408 22.50135708
OS 18.72161864 22.50135708
OS 18.73826072 22.50875356
OS 18.7549028 22.51430092
OS 18.77154488 22.51892372
OS 18.78633784 22.5216974
OS 18.79835712 22.52354652
OE
SE
S P 0
OB 20.32367284 38.3026666 I
OS 20.32367284 38.73905892
OS 20.40873236 38.73905892
OS 20.40873236 38.2980438
OS 20.40873236 38.27862804
OS 20.41058148 38.26198596
OS 20.41150604 38.24811756
OS 20.41335516 38.23702284
OS 20.41520428 38.2287018
OS 20.41612884 38.22222988
OS 20.41797796 38.21853164
OS 20.41797796 38.21760708
OS 20.4216762 38.20836148
OS 20.426299 38.200965
OS 20.43184636 38.19449308
OS 20.43646916 38.18802116
OS 20.44201652 38.18432292
OS 20.44571476 38.18062468
OS 20.44848844 38.17877556
OS 20.449413 38.177851
OS 20.4586586 38.1732282
OS 20.4679042 38.16952996
OS 20.4771498 38.16768084
OS 20.48547084 38.16583172
OS 20.49379188 38.16490716
OS 20.49933924 38.1639826
OS 20.5048866 38.1639826
OS 20.51967956 38.16490716
OS 20.53354796 38.1686054
OS 20.54464268 38.17230364
OS 20.55481284 38.177851
OS 20.56220932 38.1824738
OS 20.56775668 38.1870966
OS 20.57145492 38.18987028
OS 20.57237948 38.19079484
OS 20.57700228 38.1963422
OS 20.58070052 38.20281412
OS 20.58624788 38.21760708
OS 20.59179524 38.23424916
OS 20.59456892 38.25089124
OS 20.5973426 38.26660876
OS 20.5973426 38.27308068
OS 20.59826716 38.27862804
OS 20.59919172 38.2841754
OS 20.59919172 38.28787364
OS 20.59919172 38.28972276
OS 20.59919172 38.29064732
OS 20.6759302 38.2795526
OS 20.6759302 38.26198596
OS 20.67500564 38.24626844
OS 20.67223196 38.23055092
OS 20.67038284 38.21668252
OS 20.6666846 38.20373868
OS 20.66298636 38.19264396
OS 20.65928812 38.18154924
OS 20.65558988 38.17230364
OS 20.65096708 38.1639826
OS 20.64726884 38.15658612
OS 20.6435706 38.1501142
OS 20.63987236 38.1454914
OS 20.63709868 38.14179316
OS 20.63524956 38.13809492
OS 20.634325 38.13717036
OS 20.63340044 38.1362458
OS 20.62415484 38.12792476
OS 20.61490924 38.12052828
OS 20.60473908 38.11405636
OS 20.59364436 38.108509
OS 20.57237948 38.10018796
OS 20.55203916 38.0946406
OS 20.5326234 38.09094236
OS 20.52522692 38.0900178
OS 20.51783044 38.08909324
OS 20.51228308 38.08816868
OS 20.50396204 38.08816868
OS 20.48362172 38.08909324
OS 20.46513052 38.09186692
OS 20.44848844 38.09556516
OS 20.43369548 38.10018796
OS 20.4216762 38.1038862
OS 20.41335516 38.10758444
OS 20.4078078 38.11035812
OS 20.40595868 38.11128268
OS 20.39116572 38.12052828
OS 20.37822188 38.131623
OS 20.36805172 38.14271772
OS 20.35880612 38.15288788
OS 20.3523342 38.16305804
OS 20.3477114 38.17045452
OS 20.34493772 38.17600188
OS 20.34401316 38.17692644
OS 20.34401316 38.177851
OS 20.33754124 38.1963422
OS 20.33199388 38.21575796
OS 20.32829564 38.23702284
OS 20.32644652 38.25736316
OS 20.3245974 38.2749298
OS 20.3245974 38.28232628
OS 20.32367284 38.28972276
OS 20.32367284 38.29527012
OS 20.32367284 38.29896836
OS 20.32367284 38.30174204
OS 20.32367284 38.3026666
OE
OB 19.98990668 38.74090804 I
OS 19.9963786 38.7418326
OS 20.0056242 38.7418326
OS 20.02226628 38.74090804
OS 20.0379838 38.73998348
OS 20.05277676 38.7372098
OS 20.06664516 38.73443612
OS 20.079589 38.73073788
OS 20.09160828 38.72703964
OS 20.102703 38.72241684
OS 20.11287316 38.71779404
OS 20.12211876 38.71317124
OS 20.12951524 38.70854844
OS 20.13598716 38.7048502
OS 20.14153452 38.70115196
OS 20.14615732 38.69837828
OS 20.148931 38.6956046
OS 20.15078012 38.69468004
OS 20.15170468 38.69375548
OS 20.16095028 38.68450988
OS 20.16927132 38.67433972
OS 20.17759236 38.663245
OS 20.18406428 38.65215028
OS 20.195159 38.62996084
OS 20.20255548 38.6077714
OS 20.20532916 38.59760124
OS 20.20810284 38.58743108
OS 20.20995196 38.57911004
OS 20.21180108 38.57171356
OS 20.21272564 38.56524164
OS 20.21272564 38.56061884
OS 20.2136502 38.55784516
OS 20.2136502 38.5569206
OS 20.13321348 38.54859956
OS 20.13136436 38.56986444
OS 20.12766612 38.58835564
OS 20.12211876 38.60499772
OS 20.11564684 38.61794156
OS 20.11009948 38.62903628
OS 20.10455212 38.63643276
OS 20.10085388 38.64105556
OS 20.09900476 38.64290468
OS 20.08513636 38.6539994
OS 20.0703434 38.66232044
OS 20.05462588 38.66879236
OS 20.04075748 38.6724906
OS 20.02781364 38.67526428
OS 20.01671892 38.67618884
OS 20.01302068 38.6771134
OS 20.00747332 38.6771134
OS 19.98805756 38.67618884
OS 19.97049092 38.6724906
OS 19.95569796 38.66694324
OS 19.94275412 38.66139588
OS 19.93258396 38.65492396
OS 19.92611204 38.65030116
OS 19.92148924 38.64660292
OS 19.91964012 38.6447538
OS 19.9085454 38.63180996
OS 19.90022436 38.61886612
OS 19.89375244 38.60592228
OS 19.8900542 38.59297844
OS 19.88728052 38.58280828
OS 19.88635596 38.57356268
OS 19.8854314 38.56801532
OS 19.8854314 38.56709076
OS 19.8854314 38.5661662
OS 19.88728052 38.54952412
OS 19.89097876 38.53195748
OS 19.89745068 38.51623996
OS 19.9039226 38.501447
OS 19.91131908 38.48942772
OS 19.917791 38.47925756
OS 19.91964012 38.47555932
OS 19.92148924 38.47278564
OS 19.92333836 38.47186108
OS 19.92333836 38.47093652
OS 19.93073484 38.46076636
OS 19.93998044 38.4505962
OS 19.9501506 38.43950148
OS 19.96124532 38.42840676
OS 19.98435932 38.40621732
OS 20.00747332 38.38402788
OS 20.0194926 38.37385772
OS 20.02966276 38.36461212
OS 20.03983292 38.35629108
OS 20.04815396 38.3488946
OS 20.05462588 38.34334724
OS 20.06017324 38.33872444
OS 20.06387148 38.33595076
OS 20.06479604 38.3350262
OS 20.08791004 38.31561044
OS 20.10917492 38.29711924
OS 20.12674156 38.28047716
OS 20.14060996 38.26660876
OS 20.15262924 38.25458948
OS 20.16095028 38.24626844
OS 20.16557308 38.24072108
OS 20.1674222 38.23979652
OS 20.1674222 38.23887196
OS 20.18036604 38.22315444
OS 20.1905362 38.20836148
OS 20.1997818 38.19356852
OS 20.20717828 38.18062468
OS 20.21272564 38.16952996
OS 20.21642388 38.16120892
OS 20.218273 38.15566156
OS 20.21919756 38.154737
OS 20.21919756 38.15381244
OS 20.2228958 38.14364228
OS 20.22474492 38.13439668
OS 20.22659404 38.12515108
OS 20.2275186 38.11683004
OS 20.22844316 38.10943356
OS 20.22844316 38.1038862
OS 20.22844316 38.10018796
OS 20.22844316 38.0992634
OS 19.80407012 38.0992634
OS 19.80407012 38.17507732
OS 20.11934508 38.17507732
OS 20.10825036 38.19079484
OS 20.102703 38.19726676
OS 20.0980802 38.20373868
OS 20.0934574 38.20928604
OS 20.08975916 38.21298428
OS 20.08698548 38.21575796
OS 20.08606092 38.21668252
OS 20.08143812 38.22130532
OS 20.07589076 38.22592812
OS 20.06294692 38.2379474
OS 20.04815396 38.2518158
OS 20.03243644 38.2656842
OS 20.01764348 38.27770348
OS 20.01117156 38.28325084
OS 20.0056242 38.2887982
OS 20.0010014 38.29249644
OS 19.99730316 38.29527012
OS 19.99545404 38.29711924
OS 19.99452948 38.2980438
OS 19.97973652 38.31098764
OS 19.96494356 38.32300692
OS 19.95199972 38.3350262
OS 19.93998044 38.34519636
OS 19.92888572 38.35536652
OS 19.91964012 38.36461212
OS 19.91039452 38.37293316
OS 19.90299804 38.38032964
OS 19.89560156 38.38772612
OS 19.8900542 38.39327348
OS 19.8854314 38.39789628
OS 19.8808086 38.40251908
OS 19.8761858 38.40806644
OS 19.87433668 38.40991556
OS 19.86139284 38.42563308
OS 19.85029812 38.43950148
OS 19.84105252 38.45336988
OS 19.83365604 38.4644646
OS 19.82810868 38.47463476
OS 19.82441044 38.48203124
OS 19.82256132 38.48665404
OS 19.82163676 38.48850316
OS 19.8160894 38.50237156
OS 19.81239116 38.51623996
OS 19.80869292 38.5291838
OS 19.8068438 38.54027852
OS 19.80591924 38.55044868
OS 19.80499468 38.55784516
OS 19.80499468 38.56246796
OS 19.80499468 38.56431708
OS 19.80591924 38.57818548
OS 19.80776836 38.59112932
OS 19.80961748 38.60407316
OS 19.81331572 38.61516788
OS 19.82256132 38.63735732
OS 19.83180692 38.65492396
OS 19.83735428 38.663245
OS 19.84197708 38.66971692
OS 19.84659988 38.67618884
OS 19.85122268 38.68081164
OS 19.85492092 38.68450988
OS 19.85677004 38.68820812
OS 19.85861916 38.68913268
OS 19.85954372 38.69005724
OS 19.86971388 38.69930284
OS 19.8808086 38.70762388
OS 19.89282788 38.7140958
OS 19.90484716 38.71964316
OS 19.92888572 38.72888876
OS 19.95292428 38.73536068
OS 19.96309444 38.7372098
OS 19.9732646 38.73905892
OS 19.9825102 38.73998348
OS 19.98990668 38.74090804
OE
SE
S P 0
OB 20.46496288 2.62766556 I
OS 20.46496288 3.06405788
OS 20.5500224 3.06405788
OS 20.5500224 2.62304276
OS 20.5500224 2.603627
OS 20.55187152 2.58698492
OS 20.55279608 2.57311652
OS 20.5546452 2.5620218
OS 20.55649432 2.55370076
OS 20.55741888 2.54722884
OS 20.559268 2.5435306
OS 20.559268 2.54260604
OS 20.56296624 2.53336044
OS 20.56758904 2.52596396
OS 20.5731364 2.51949204
OS 20.5777592 2.51302012
OS 20.58330656 2.50932188
OS 20.5870048 2.50562364
OS 20.58977848 2.50377452
OS 20.59070304 2.50284996
OS 20.59994864 2.49822716
OS 20.60919424 2.49452892
OS 20.61843984 2.4926798
OS 20.62676088 2.49083068
OS 20.63508192 2.48990612
OS 20.64062928 2.48898156
OS 20.64617664 2.48898156
OS 20.6609696 2.48990612
OS 20.674838 2.49360436
OS 20.68593272 2.4973026
OS 20.69610288 2.50284996
OS 20.70349936 2.50747276
OS 20.70904672 2.51209556
OS 20.71274496 2.51486924
OS 20.71366952 2.5157938
OS 20.71829232 2.52134116
OS 20.72199056 2.52781308
OS 20.72753792 2.54260604
OS 20.73308528 2.55924812
OS 20.73585896 2.5758902
OS 20.73863264 2.59160772
OS 20.73863264 2.59807964
OS 20.7395572 2.603627
OS 20.74048176 2.60917436
OS 20.74048176 2.6128726
OS 20.74048176 2.61472172
OS 20.74048176 2.61564628
OS 20.81722024 2.60455156
OS 20.81722024 2.58698492
OS 20.81629568 2.5712674
OS 20.813522 2.55554988
OS 20.81167288 2.54168148
OS 20.80797464 2.52873764
OS 20.8042764 2.51764292
OS 20.80057816 2.5065482
OS 20.79687992 2.4973026
OS 20.79225712 2.48898156
OS 20.78855888 2.48158508
OS 20.78486064 2.47511316
OS 20.7811624 2.47049036
OS 20.77838872 2.46679212
OS 20.7765396 2.46309388
OS 20.77561504 2.46216932
OS 20.77469048 2.46124476
OS 20.76544488 2.45292372
OS 20.75619928 2.44552724
OS 20.74602912 2.43905532
OS 20.7349344 2.43350796
OS 20.71366952 2.42518692
OS 20.6933292 2.41963956
OS 20.67391344 2.41594132
OS 20.66651696 2.41501676
OS 20.65912048 2.4140922
OS 20.65357312 2.41316764
OS 20.64525208 2.41316764
OS 20.62491176 2.4140922
OS 20.60642056 2.41686588
OS 20.58977848 2.42056412
OS 20.57498552 2.42518692
OS 20.56296624 2.42888516
OS 20.5546452 2.4325834
OS 20.54909784 2.43535708
OS 20.54724872 2.43628164
OS 20.53245576 2.44552724
OS 20.51951192 2.45662196
OS 20.50934176 2.46771668
OS 20.50009616 2.47788684
OS 20.49362424 2.488057
OS 20.48900144 2.49545348
OS 20.48622776 2.50100084
OS 20.4853032 2.5019254
OS 20.4853032 2.50284996
OS 20.47883128 2.52134116
OS 20.47328392 2.54075692
OS 20.46958568 2.5620218
OS 20.46773656 2.58236212
OS 20.46588744 2.59992876
OS 20.46588744 2.60732524
OS 20.46496288 2.61472172
OS 20.46496288 2.62026908
OS 20.46496288 2.62396732
OS 20.46496288 2.626741
OS 20.46496288 2.62766556
OE
OB 20.06277928 2.42426236 I
OS 20.06277928 3.06683156
OS 20.11363008 3.06683156
OS 20.12287568 3.05111404
OS 20.13304584 3.03632108
OS 20.14506512 3.02152812
OS 20.15615984 3.00858428
OS 20.16725456 2.99748956
OS 20.1755756 2.98824396
OS 20.17927384 2.98547028
OS 20.18204752 2.9826966
OS 20.18297208 2.98177204
OS 20.18389664 2.98084748
OS 20.2033124 2.96512996
OS 20.22272816 2.950337
OS 20.24121936 2.93739316
OS 20.25971056 2.927223
OS 20.27542808 2.9179774
OS 20.2819 2.91427916
OS 20.28744736 2.91150548
OS 20.29207016 2.9087318
OS 20.2957684 2.90780724
OS 20.29761752 2.90595812
OS 20.29854208 2.90595812
OS 20.29854208 2.8301442
OS 20.28467368 2.83569156
OS 20.27080528 2.84216348
OS 20.25693688 2.8486354
OS 20.24399304 2.85510732
OS 20.23289832 2.86065468
OS 20.22365272 2.86527748
OS 20.21810536 2.86897572
OS 20.2171808 2.86990028
OS 20.21625624 2.86990028
OS 20.19961416 2.88007044
OS 20.1848212 2.8902406
OS 20.17187736 2.8994862
OS 20.1617072 2.90780724
OS 20.1524616 2.91427916
OS 20.14691424 2.91982652
OS 20.14229144 2.92352476
OS 20.14136688 2.92444932
OS 20.14136688 2.42426236
OS 20.06277928 2.42426236
OE
SE
S P 0
OB 26.66511558 8.12007012 I
OS 26.6715875 8.12099468
OS 26.6808331 8.12099468
OS 26.71134358 8.11914556
OS 26.7409295 8.11452276
OS 26.76681718 8.1089754
OS 26.77883646 8.10527716
OS 26.78993118 8.10157892
OS 26.80010134 8.09788068
OS 26.80934694 8.09418244
OS 26.81674342 8.09140876
OS 26.8241399 8.08863508
OS 26.8287627 8.0858614
OS 26.83246094 8.08401228
OS 26.83523462 8.08308772
OS 26.83615918 8.08216316
OS 26.8611223 8.06644564
OS 26.88238718 8.04795444
OS 26.90087838 8.02946324
OS 26.9165959 8.01097204
OS 26.92861518 7.99432996
OS 26.93323798 7.98693348
OS 26.93693622 7.98046156
OS 26.94063446 7.97583876
OS 26.94248358 7.97214052
OS 26.94340814 7.96936684
OS 26.9443327 7.96844228
OS 26.95727654 7.93978092
OS 26.96652214 7.910195
OS 26.97299406 7.88060908
OS 26.97761686 7.85379684
OS 26.97946598 7.84177756
OS 26.98039054 7.82975828
OS 26.9813151 7.82051268
OS 26.9813151 7.81126708
OS 26.98223966 7.80479516
OS 26.98223966 7.7992478
OS 26.98223966 7.79554956
OS 26.98223966 7.794625
OS 26.98039054 7.76134084
OS 26.9766923 7.72898124
OS 26.9720695 7.70031988
OS 26.96837126 7.68645148
OS 26.96559758 7.6744322
OS 26.9628239 7.66333748
OS 26.95912566 7.65316732
OS 26.95635198 7.64392172
OS 26.95450286 7.63652524
OS 26.95172918 7.63097788
OS 26.95080462 7.62635508
OS 26.9489555 7.6235814
OS 26.9489555 7.62265684
OS 26.9350871 7.59492004
OS 26.91936958 7.56995692
OS 26.9027275 7.54869204
OS 26.89440646 7.540371
OS 26.88700998 7.53204996
OS 26.8796135 7.52465348
OS 26.87221702 7.51818156
OS 26.8657451 7.5126342
OS 26.86019774 7.50893596
OS 26.8564995 7.50523772
OS 26.85280126 7.50246404
OS 26.85095214 7.50153948
OS 26.85002758 7.50061492
OS 26.83708374 7.49321844
OS 26.8241399 7.48674652
OS 26.7964031 7.47657636
OS 26.7686663 7.46917988
OS 26.74185406 7.46455708
OS 26.72891022 7.46270796
OS 26.7178155 7.46085884
OS 26.70764534 7.45993428
OS 26.6993243 7.45993428
OS 26.69192782 7.45900972
OS 26.68175766 7.45900972
OS 26.66326646 7.45993428
OS 26.64569982 7.4617834
OS 26.62905774 7.46363252
OS 26.61334022 7.46733076
OS 26.59854726 7.47195356
OS 26.58467886 7.47657636
OS 26.57173502 7.48119916
OS 26.55971574 7.48674652
OS 26.54954558 7.49136932
OS 26.53937542 7.49599212
OS 26.53197894 7.50061492
OS 26.52458246 7.50523772
OS 26.51995966 7.50893596
OS 26.51533686 7.51078508
OS 26.51348774 7.5126342
OS 26.51256318 7.51355876
OS 26.49961934 7.52465348
OS 26.48852462 7.5357482
OS 26.47835446 7.54869204
OS 26.4681843 7.56163588
OS 26.45154222 7.58752356
OS 26.43859838 7.61341124
OS 26.43305102 7.62543052
OS 26.42842822 7.63652524
OS 26.42472998 7.6466954
OS 26.4219563 7.65501644
OS 26.41918262 7.66241292
OS 26.4173335 7.66796028
OS 26.41640894 7.67165852
OS 26.41640894 7.67258308
OS 26.50146846 7.69384796
OS 26.5051667 7.679055
OS 26.5097895 7.6651866
OS 26.5144123 7.65224276
OS 26.5190351 7.64022348
OS 26.52458246 7.62912876
OS 26.53012982 7.61988316
OS 26.53660174 7.61063756
OS 26.5421491 7.60231652
OS 26.5467719 7.59492004
OS 26.55231926 7.58937268
OS 26.55694206 7.58382532
OS 26.5606403 7.57920252
OS 26.56433854 7.57642884
OS 26.56711222 7.57365516
OS 26.56803678 7.5727306
OS 26.56896134 7.57180604
OS 26.57820694 7.56440956
OS 26.5883771 7.5588622
OS 26.60871742 7.54869204
OS 26.62813318 7.54129556
OS 26.64754894 7.53667276
OS 26.66419102 7.53297452
OS 26.67066294 7.53204996
OS 26.67713486 7.53204996
OS 26.68268222 7.5311254
OS 26.68915414 7.5311254
OS 26.71041902 7.53204996
OS 26.73075934 7.5357482
OS 26.74925054 7.540371
OS 26.76589262 7.54591836
OS 26.77883646 7.55146572
OS 26.78438382 7.5542394
OS 26.78900662 7.55608852
OS 26.79270486 7.55793764
OS 26.79547854 7.55978676
OS 26.79732766 7.56071132
OS 26.79825222 7.56071132
OS 26.81581886 7.57365516
OS 26.83061182 7.58752356
OS 26.84355566 7.60324108
OS 26.85372582 7.61803404
OS 26.86204686 7.63097788
OS 26.86759422 7.6420726
OS 26.86944334 7.6466954
OS 26.87129246 7.64946908
OS 26.87221702 7.6513182
OS 26.87221702 7.65224276
OS 26.8796135 7.67628132
OS 26.88516086 7.70031988
OS 26.88978366 7.72435844
OS 26.89255734 7.74654788
OS 26.8934819 7.75671804
OS 26.89440646 7.76596364
OS 26.89440646 7.77428468
OS 26.89533102 7.7807566
OS 26.89533102 7.78630396
OS 26.89533102 7.79092676
OS 26.89533102 7.79370044
OS 26.89533102 7.794625
OS 26.89440646 7.81866356
OS 26.89255734 7.840853
OS 26.8888591 7.86119332
OS 26.88516086 7.87968452
OS 26.88238718 7.89540204
OS 26.88053806 7.90187396
OS 26.87868894 7.90742132
OS 26.87776438 7.91204412
OS 26.87683982 7.9148178
OS 26.87591526 7.91666692
OS 26.87591526 7.91759148
OS 26.86666966 7.93885636
OS 26.8564995 7.95827212
OS 26.84540478 7.97398964
OS 26.8333855 7.98785804
OS 26.82321534 7.99895276
OS 26.8148943 8.00634924
OS 26.80842238 8.01097204
OS 26.80749782 8.01282116
OS 26.80657326 8.01282116
OS 26.7871575 8.02484044
OS 26.76589262 8.03408604
OS 26.7455523 8.04055796
OS 26.72613654 8.0442562
OS 26.7085699 8.04702988
OS 26.70117342 8.04795444
OS 26.6947015 8.04795444
OS 26.6900787 8.048879
OS 26.68268222 8.048879
OS 26.65956822 8.04795444
OS 26.63830334 8.0442562
OS 26.6207367 8.03870884
OS 26.60501918 8.03316148
OS 26.5929999 8.02668956
OS 26.5837543 8.02206676
OS 26.57820694 8.01836852
OS 26.57635782 8.0165194
OS 26.56156486 8.002651
OS 26.54769646 7.98693348
OS 26.53660174 7.9702914
OS 26.52735614 7.95364932
OS 26.51995966 7.93885636
OS 26.51718598 7.93145988
OS 26.51533686 7.92591252
OS 26.51348774 7.92128972
OS 26.51163862 7.91759148
OS 26.51071406 7.91574236
OS 26.51071406 7.9148178
OS 26.42750366 7.93423356
OS 26.43305102 7.95087564
OS 26.43859838 7.9656686
OS 26.44599486 7.979537
OS 26.45246678 7.9934054
OS 26.45986326 8.00542468
OS 26.4681843 8.0165194
OS 26.47558078 8.02761412
OS 26.48297726 8.03685972
OS 26.49037374 8.0442562
OS 26.49684566 8.05165268
OS 26.50331758 8.0581246
OS 26.50794038 8.0627474
OS 26.51256318 8.0673702
OS 26.51626142 8.07014388
OS 26.51811054 8.07106844
OS 26.5190351 8.071993
OS 26.53197894 8.08031404
OS 26.54492278 8.08863508
OS 26.55786662 8.095107
OS 26.57173502 8.10065436
OS 26.59947182 8.1089754
OS 26.62443494 8.11452276
OS 26.63645422 8.11729644
OS 26.64662438 8.118221
OS 26.65679454 8.11914556
OS 26.66511558 8.12007012
OE
OB 26.04843406 7.47010444 I
OS 26.04843406 8.11267364
OS 26.09928486 8.11267364
OS 26.10853046 8.09695612
OS 26.11870062 8.08216316
OS 26.1307199 8.0673702
OS 26.14181462 8.05442636
OS 26.15290934 8.04333164
OS 26.16123038 8.03408604
OS 26.16492862 8.03131236
OS 26.1677023 8.02853868
OS 26.16862686 8.02761412
OS 26.16955142 8.02668956
OS 26.18896718 8.01097204
OS 26.20838294 7.99617908
OS 26.22687414 7.98323524
OS 26.24536534 7.97306508
OS 26.26108286 7.96381948
OS 26.26755478 7.96012124
OS 26.27310214 7.95734756
OS 26.27772494 7.95457388
OS 26.28142318 7.95364932
OS 26.2832723 7.9518002
OS 26.28419686 7.9518002
OS 26.28419686 7.87598628
OS 26.27032846 7.88153364
OS 26.25646006 7.88800556
OS 26.24259166 7.89447748
OS 26.22964782 7.9009494
OS 26.2185531 7.90649676
OS 26.2093075 7.91111956
OS 26.20376014 7.9148178
OS 26.20283558 7.91574236
OS 26.20191102 7.91574236
OS 26.18526894 7.92591252
OS 26.17047598 7.93608268
OS 26.15753214 7.94532828
OS 26.14736198 7.95364932
OS 26.13811638 7.96012124
OS 26.13256902 7.9656686
OS 26.12794622 7.96936684
OS 26.12702166 7.9702914
OS 26.12702166 7.47010444
OS 26.04843406 7.47010444
OE
OB 25.55102078 7.47010444 I
OS 25.55102078 8.11267364
OS 25.60187158 8.11267364
OS 25.61111718 8.09695612
OS 25.62128734 8.08216316
OS 25.63330662 8.0673702
OS 25.64440134 8.05442636
OS 25.65549606 8.04333164
OS 25.6638171 8.03408604
OS 25.66751534 8.03131236
OS 25.67028902 8.02853868
OS 25.67121358 8.02761412
OS 25.67213814 8.02668956
OS 25.6915539 8.01097204
OS 25.71096966 7.99617908
OS 25.72946086 7.98323524
OS 25.74795206 7.97306508
OS 25.76366958 7.96381948
OS 25.7701415 7.96012124
OS 25.77568886 7.95734756
OS 25.78031166 7.95457388
OS 25.7840099 7.95364932
OS 25.78585902 7.9518002
OS 25.78678358 7.9518002
OS 25.78678358 7.87598628
OS 25.77291518 7.88153364
OS 25.75904678 7.88800556
OS 25.74517838 7.89447748
OS 25.73223454 7.9009494
OS 25.72113982 7.90649676
OS 25.71189422 7.91111956
OS 25.70634686 7.9148178
OS 25.7054223 7.91574236
OS 25.70449774 7.91574236
OS 25.68785566 7.92591252
OS 25.6730627 7.93608268
OS 25.66011886 7.94532828
OS 25.6499487 7.95364932
OS 25.6407031 7.96012124
OS 25.63515574 7.9656686
OS 25.63053294 7.96936684
OS 25.62960838 7.9702914
OS 25.62960838 7.47010444
OS 25.55102078 7.47010444
OE
SE
S P 0
OB 26.72382514 12.62006874 I
OS 26.73029706 12.6209933
OS 26.73954266 12.6209933
OS 26.77005314 12.61914418
OS 26.79963906 12.61452138
OS 26.82552674 12.60897402
OS 26.83754602 12.60527578
OS 26.84864074 12.60157754
OS 26.8588109 12.5978793
OS 26.8680565 12.59418106
OS 26.87545298 12.59140738
OS 26.88284946 12.5886337
OS 26.88747226 12.58586002
OS 26.8911705 12.5840109
OS 26.89394418 12.58308634
OS 26.89486874 12.58216178
OS 26.91983186 12.56644426
OS 26.94109674 12.54795306
OS 26.95958794 12.52946186
OS 26.97530546 12.51097066
OS 26.98732474 12.49432858
OS 26.99194754 12.4869321
OS 26.99564578 12.48046018
OS 26.99934402 12.47583738
OS 27.00119314 12.47213914
OS 27.0021177 12.46936546
OS 27.00304226 12.4684409
OS 27.0159861 12.43977954
OS 27.0252317 12.41019362
OS 27.03170362 12.3806077
OS 27.03632642 12.35379546
OS 27.03817554 12.34177618
OS 27.0391001 12.3297569
OS 27.04002466 12.3205113
OS 27.04002466 12.3112657
OS 27.04094922 12.30479378
OS 27.04094922 12.29924642
OS 27.04094922 12.29554818
OS 27.04094922 12.29462362
OS 27.0391001 12.26133946
OS 27.03540186 12.22897986
OS 27.03077906 12.2003185
OS 27.02708082 12.1864501
OS 27.02430714 12.17443082
OS 27.02153346 12.1633361
OS 27.01783522 12.15316594
OS 27.01506154 12.14392034
OS 27.01321242 12.13652386
OS 27.01043874 12.1309765
OS 27.00951418 12.1263537
OS 27.00766506 12.12358002
OS 27.00766506 12.12265546
OS 26.99379666 12.09491866
OS 26.97807914 12.06995554
OS 26.96143706 12.04869066
OS 26.95311602 12.04036962
OS 26.94571954 12.03204858
OS 26.93832306 12.0246521
OS 26.93092658 12.01818018
OS 26.92445466 12.01263282
OS 26.9189073 12.00893458
OS 26.91520906 12.00523634
OS 26.91151082 12.00246266
OS 26.9096617 12.0015381
OS 26.90873714 12.00061354
OS 26.8957933 11.99321706
OS 26.88284946 11.98674514
OS 26.85511266 11.97657498
OS 26.82737586 11.9691785
OS 26.80056362 11.9645557
OS 26.78761978 11.96270658
OS 26.77652506 11.96085746
OS 26.7663549 11.9599329
OS 26.75803386 11.9599329
OS 26.75063738 11.95900834
OS 26.74046722 11.95900834
OS 26.72197602 11.9599329
OS 26.70440938 11.96178202
OS 26.6877673 11.96363114
OS 26.67204978 11.96732938
OS 26.65725682 11.97195218
OS 26.64338842 11.97657498
OS 26.63044458 11.98119778
OS 26.6184253 11.98674514
OS 26.60825514 11.99136794
OS 26.59808498 11.99599074
OS 26.5906885 12.00061354
OS 26.58329202 12.00523634
OS 26.57866922 12.00893458
OS 26.57404642 12.0107837
OS 26.5721973 12.01263282
OS 26.57127274 12.01355738
OS 26.5583289 12.0246521
OS 26.54723418 12.03574682
OS 26.53706402 12.04869066
OS 26.52689386 12.0616345
OS 26.51025178 12.08752218
OS 26.49730794 12.11340986
OS 26.49176058 12.12542914
OS 26.48713778 12.13652386
OS 26.48343954 12.14669402
OS 26.48066586 12.15501506
OS 26.47789218 12.16241154
OS 26.47604306 12.1679589
OS 26.4751185 12.17165714
OS 26.4751185 12.1725817
OS 26.56017802 12.19384658
OS 26.56387626 12.17905362
OS 26.56849906 12.16518522
OS 26.57312186 12.15224138
OS 26.57774466 12.1402221
OS 26.58329202 12.12912738
OS 26.58883938 12.11988178
OS 26.5953113 12.11063618
OS 26.60085866 12.10231514
OS 26.60548146 12.09491866
OS 26.61102882 12.0893713
OS 26.61565162 12.08382394
OS 26.61934986 12.07920114
OS 26.6230481 12.07642746
OS 26.62582178 12.07365378
OS 26.62674634 12.07272922
OS 26.6276709 12.07180466
OS 26.6369165 12.06440818
OS 26.64708666 12.05886082
OS 26.66742698 12.04869066
OS 26.68684274 12.04129418
OS 26.7062585 12.03667138
OS 26.72290058 12.03297314
OS 26.7293725 12.03204858
OS 26.73584442 12.03204858
OS 26.74139178 12.03112402
OS 26.7478637 12.03112402
OS 26.76912858 12.03204858
OS 26.7894689 12.03574682
OS 26.8079601 12.04036962
OS 26.82460218 12.04591698
OS 26.83754602 12.05146434
OS 26.84309338 12.05423802
OS 26.84771618 12.05608714
OS 26.85141442 12.05793626
OS 26.8541881 12.05978538
OS 26.85603722 12.06070994
OS 26.85696178 12.06070994
OS 26.87452842 12.07365378
OS 26.88932138 12.08752218
OS 26.90226522 12.1032397
OS 26.91243538 12.11803266
OS 26.92075642 12.1309765
OS 26.92630378 12.14207122
OS 26.9281529 12.14669402
OS 26.93000202 12.1494677
OS 26.93092658 12.15131682
OS 26.93092658 12.15224138
OS 26.93832306 12.17627994
OS 26.94387042 12.2003185
OS 26.94849322 12.22435706
OS 26.9512669 12.2465465
OS 26.95219146 12.25671666
OS 26.95311602 12.26596226
OS 26.95311602 12.2742833
OS 26.95404058 12.28075522
OS 26.95404058 12.28630258
OS 26.95404058 12.29092538
OS 26.95404058 12.29369906
OS 26.95404058 12.29462362
OS 26.95311602 12.31866218
OS 26.9512669 12.34085162
OS 26.94756866 12.36119194
OS 26.94387042 12.37968314
OS 26.94109674 12.39540066
OS 26.93924762 12.40187258
OS 26.9373985 12.40741994
OS 26.93647394 12.41204274
OS 26.93554938 12.41481642
OS 26.93462482 12.41666554
OS 26.93462482 12.4175901
OS 26.92537922 12.43885498
OS 26.91520906 12.45827074
OS 26.90411434 12.47398826
OS 26.89209506 12.48785666
OS 26.8819249 12.49895138
OS 26.87360386 12.50634786
OS 26.86713194 12.51097066
OS 26.86620738 12.51281978
OS 26.86528282 12.51281978
OS 26.84586706 12.52483906
OS 26.82460218 12.53408466
OS 26.80426186 12.54055658
OS 26.7848461 12.54425482
OS 26.76727946 12.5470285
OS 26.75988298 12.54795306
OS 26.75341106 12.54795306
OS 26.74878826 12.54887762
OS 26.74139178 12.54887762
OS 26.71827778 12.54795306
OS 26.6970129 12.54425482
OS 26.67944626 12.53870746
OS 26.66372874 12.5331601
OS 26.65170946 12.52668818
OS 26.64246386 12.52206538
OS 26.6369165 12.51836714
OS 26.63506738 12.51651802
OS 26.62027442 12.50264962
OS 26.60640602 12.4869321
OS 26.5953113 12.47029002
OS 26.5860657 12.45364794
OS 26.57866922 12.43885498
OS 26.57589554 12.4314585
OS 26.57404642 12.42591114
OS 26.5721973 12.42128834
OS 26.57034818 12.4175901
OS 26.56942362 12.41574098
OS 26.56942362 12.41481642
OS 26.48621322 12.43423218
OS 26.49176058 12.45087426
OS 26.49730794 12.46566722
OS 26.50470442 12.47953562
OS 26.51117634 12.49340402
OS 26.51857282 12.5054233
OS 26.52689386 12.51651802
OS 26.53429034 12.52761274
OS 26.54168682 12.53685834
OS 26.5490833 12.54425482
OS 26.55555522 12.5516513
OS 26.56202714 12.55812322
OS 26.56664994 12.56274602
OS 26.57127274 12.56736882
OS 26.57497098 12.5701425
OS 26.5768201 12.57106706
OS 26.57774466 12.57199162
OS 26.5906885 12.58031266
OS 26.60363234 12.5886337
OS 26.61657618 12.59510562
OS 26.63044458 12.60065298
OS 26.65818138 12.60897402
OS 26.6831445 12.61452138
OS 26.69516378 12.61729506
OS 26.70533394 12.61821962
OS 26.7155041 12.61914418
OS 26.72382514 12.62006874
OE
OB 26.10714362 11.97010306 I
OS 26.10714362 12.61267226
OS 26.15799442 12.61267226
OS 26.16724002 12.59695474
OS 26.17741018 12.58216178
OS 26.18942946 12.56736882
OS 26.20052418 12.55442498
OS 26.2116189 12.54333026
OS 26.21993994 12.53408466
OS 26.22363818 12.53131098
OS 26.22641186 12.5285373
OS 26.22733642 12.52761274
OS 26.22826098 12.52668818
OS 26.24767674 12.51097066
OS 26.2670925 12.4961777
OS 26.2855837 12.48323386
OS 26.3040749 12.4730637
OS 26.31979242 12.4638181
OS 26.32626434 12.46011986
OS 26.3318117 12.45734618
OS 26.3364345 12.4545725
OS 26.34013274 12.45364794
OS 26.34198186 12.45179882
OS 26.34290642 12.45179882
OS 26.34290642 12.3759849
OS 26.32903802 12.38153226
OS 26.31516962 12.38800418
OS 26.30130122 12.3944761
OS 26.28835738 12.40094802
OS 26.27726266 12.40649538
OS 26.26801706 12.41111818
OS 26.2624697 12.41481642
OS 26.26154514 12.41574098
OS 26.26062058 12.41574098
OS 26.2439785 12.42591114
OS 26.22918554 12.4360813
OS 26.2162417 12.4453269
OS 26.20607154 12.45364794
OS 26.19682594 12.46011986
OS 26.19127858 12.46566722
OS 26.18665578 12.46936546
OS 26.18573122 12.47029002
OS 26.18573122 11.97010306
OS 26.10714362 11.97010306
OE
OB 25.67814778 12.6117477 I
OS 25.6846197 12.61267226
OS 25.6938653 12.61267226
OS 25.71050738 12.6117477
OS 25.7262249 12.61082314
OS 25.74101786 12.60804946
OS 25.75488626 12.60527578
OS 25.7678301 12.60157754
OS 25.77984938 12.5978793
OS 25.7909441 12.5932565
OS 25.80111426 12.5886337
OS 25.81035986 12.5840109
OS 25.81775634 12.5793881
OS 25.82422826 12.57568986
OS 25.82977562 12.57199162
OS 25.83439842 12.56921794
OS 25.8371721 12.56644426
OS 25.83902122 12.5655197
OS 25.83994578 12.56459514
OS 25.84919138 12.55534954
OS 25.85751242 12.54517938
OS 25.86583346 12.53408466
OS 25.87230538 12.52298994
OS 25.8834001 12.5008005
OS 25.89079658 12.47861106
OS 25.89357026 12.4684409
OS 25.89634394 12.45827074
OS 25.89819306 12.4499497
OS 25.90004218 12.44255322
OS 25.90096674 12.4360813
OS 25.90096674 12.4314585
OS 25.9018913 12.42868482
OS 25.9018913 12.42776026
OS 25.82145458 12.41943922
OS 25.81960546 12.4407041
OS 25.81590722 12.4591953
OS 25.81035986 12.47583738
OS 25.80388794 12.48878122
OS 25.79834058 12.49987594
OS 25.79279322 12.50727242
OS 25.78909498 12.51189522
OS 25.78724586 12.51374434
OS 25.77337746 12.52483906
OS 25.7585845 12.5331601
OS 25.74286698 12.53963202
OS 25.72899858 12.54333026
OS 25.71605474 12.54610394
OS 25.70496002 12.5470285
OS 25.70126178 12.54795306
OS 25.69571442 12.54795306
OS 25.67629866 12.5470285
OS 25.65873202 12.54333026
OS 25.64393906 12.5377829
OS 25.63099522 12.53223554
OS 25.62082506 12.52576362
OS 25.61435314 12.52114082
OS 25.60973034 12.51744258
OS 25.60788122 12.51559346
OS 25.5967865 12.50264962
OS 25.58846546 12.48970578
OS 25.58199354 12.47676194
OS 25.5782953 12.4638181
OS 25.57552162 12.45364794
OS 25.57459706 12.44440234
OS 25.5736725 12.43885498
OS 25.5736725 12.43793042
OS 25.5736725 12.43700586
OS 25.57552162 12.42036378
OS 25.57921986 12.40279714
OS 25.58569178 12.38707962
OS 25.5921637 12.37228666
OS 25.59956018 12.36026738
OS 25.6060321 12.35009722
OS 25.60788122 12.34639898
OS 25.60973034 12.3436253
OS 25.61157946 12.34270074
OS 25.61157946 12.34177618
OS 25.61897594 12.33160602
OS 25.62822154 12.32143586
OS 25.6383917 12.31034114
OS 25.64948642 12.29924642
OS 25.67260042 12.27705698
OS 25.69571442 12.25486754
OS 25.7077337 12.24469738
OS 25.71790386 12.23545178
OS 25.72807402 12.22713074
OS 25.73639506 12.21973426
OS 25.74286698 12.2141869
OS 25.74841434 12.2095641
OS 25.75211258 12.20679042
OS 25.75303714 12.20586586
OS 25.77615114 12.1864501
OS 25.79741602 12.1679589
OS 25.81498266 12.15131682
OS 25.82885106 12.13744842
OS 25.84087034 12.12542914
OS 25.84919138 12.1171081
OS 25.85381418 12.11156074
OS 25.8556633 12.11063618
OS 25.8556633 12.10971162
OS 25.86860714 12.0939941
OS 25.8787773 12.07920114
OS 25.8880229 12.06440818
OS 25.89541938 12.05146434
OS 25.90096674 12.04036962
OS 25.90466498 12.03204858
OS 25.9065141 12.02650122
OS 25.90743866 12.02557666
OS 25.90743866 12.0246521
OS 25.9111369 12.01448194
OS 25.91298602 12.00523634
OS 25.91483514 11.99599074
OS 25.9157597 11.9876697
OS 25.91668426 11.98027322
OS 25.91668426 11.97472586
OS 25.91668426 11.97102762
OS 25.91668426 11.97010306
OS 25.49231122 11.97010306
OS 25.49231122 12.04591698
OS 25.80758618 12.04591698
OS 25.79649146 12.0616345
OS 25.7909441 12.06810642
OS 25.7863213 12.07457834
OS 25.7816985 12.0801257
OS 25.77800026 12.08382394
OS 25.77522658 12.08659762
OS 25.77430202 12.08752218
OS 25.76967922 12.09214498
OS 25.76413186 12.09676778
OS 25.75118802 12.10878706
OS 25.73639506 12.12265546
OS 25.72067754 12.13652386
OS 25.70588458 12.14854314
OS 25.69941266 12.1540905
OS 25.6938653 12.15963786
OS 25.6892425 12.1633361
OS 25.68554426 12.16610978
OS 25.68369514 12.1679589
OS 25.68277058 12.16888346
OS 25.66797762 12.1818273
OS 25.65318466 12.19384658
OS 25.64024082 12.20586586
OS 25.62822154 12.21603602
OS 25.61712682 12.22620618
OS 25.60788122 12.23545178
OS 25.59863562 12.24377282
OS 25.59123914 12.2511693
OS 25.58384266 12.25856578
OS 25.5782953 12.26411314
OS 25.5736725 12.26873594
OS 25.5690497 12.27335874
OS 25.5644269 12.2789061
OS 25.56257778 12.28075522
OS 25.54963394 12.29647274
OS 25.53853922 12.31034114
OS 25.52929362 12.32420954
OS 25.52189714 12.33530426
OS 25.51634978 12.34547442
OS 25.51265154 12.3528709
OS 25.51080242 12.3574937
OS 25.50987786 12.35934282
OS 25.5043305 12.37321122
OS 25.50063226 12.38707962
OS 25.49693402 12.40002346
OS 25.4950849 12.41111818
OS 25.49416034 12.42128834
OS 25.49323578 12.42868482
OS 25.49323578 12.43330762
OS 25.49323578 12.43515674
OS 25.49416034 12.44902514
OS 25.49600946 12.46196898
OS 25.49785858 12.47491282
OS 25.50155682 12.48600754
OS 25.51080242 12.50819698
OS 25.52004802 12.52576362
OS 25.52559538 12.53408466
OS 25.53021818 12.54055658
OS 25.53484098 12.5470285
OS 25.53946378 12.5516513
OS 25.54316202 12.55534954
OS 25.54501114 12.55904778
OS 25.54686026 12.55997234
OS 25.54778482 12.5608969
OS 25.55795498 12.5701425
OS 25.5690497 12.57846354
OS 25.58106898 12.58493546
OS 25.59308826 12.59048282
OS 25.61712682 12.59972842
OS 25.64116538 12.60620034
OS 25.65133554 12.60804946
OS 25.6615057 12.60989858
OS 25.6707513 12.61082314
OS 25.67814778 12.6117477
OE
SE
S P 0
OB 26.10945502 9.97010452 I
OS 26.10945502 10.61267372
OS 26.16030582 10.61267372
OS 26.16955142 10.5969562
OS 26.17972158 10.58216324
OS 26.19174086 10.56737028
OS 26.20283558 10.55442644
OS 26.2139303 10.54333172
OS 26.22225134 10.53408612
OS 26.22594958 10.53131244
OS 26.22872326 10.52853876
OS 26.22964782 10.5276142
OS 26.23057238 10.52668964
OS 26.24998814 10.51097212
OS 26.2694039 10.49617916
OS 26.2878951 10.48323532
OS 26.3063863 10.47306516
OS 26.32210382 10.46381956
OS 26.32857574 10.46012132
OS 26.3341231 10.45734764
OS 26.3387459 10.45457396
OS 26.34244414 10.4536494
OS 26.34429326 10.45180028
OS 26.34521782 10.45180028
OS 26.34521782 10.37598636
OS 26.33134942 10.38153372
OS 26.31748102 10.38800564
OS 26.30361262 10.39447756
OS 26.29066878 10.40094948
OS 26.27957406 10.40649684
OS 26.27032846 10.41111964
OS 26.2647811 10.41481788
OS 26.26385654 10.41574244
OS 26.26293198 10.41574244
OS 26.2462899 10.4259126
OS 26.23149694 10.43608276
OS 26.2185531 10.44532836
OS 26.20838294 10.4536494
OS 26.19913734 10.46012132
OS 26.19358998 10.46566868
OS 26.18896718 10.46936692
OS 26.18804262 10.47029148
OS 26.18804262 9.97010452
OS 26.10945502 9.97010452
OE
OB 26.72613654 10.6200702 I
OS 26.73260846 10.62099476
OS 26.74185406 10.62099476
OS 26.77236454 10.61914564
OS 26.80195046 10.61452284
OS 26.82783814 10.60897548
OS 26.83985742 10.60527724
OS 26.85095214 10.601579
OS 26.8611223 10.59788076
OS 26.8703679 10.59418252
OS 26.87776438 10.59140884
OS 26.88516086 10.58863516
OS 26.88978366 10.58586148
OS 26.8934819 10.58401236
OS 26.89625558 10.5830878
OS 26.89718014 10.58216324
OS 26.92214326 10.56644572
OS 26.94340814 10.54795452
OS 26.96189934 10.52946332
OS 26.97761686 10.51097212
OS 26.98963614 10.49433004
OS 26.99425894 10.48693356
OS 26.99795718 10.48046164
OS 27.00165542 10.47583884
OS 27.00350454 10.4721406
OS 27.0044291 10.46936692
OS 27.00535366 10.46844236
OS 27.0182975 10.439781
OS 27.0275431 10.41019508
OS 27.03401502 10.38060916
OS 27.03863782 10.35379692
OS 27.04048694 10.34177764
OS 27.0414115 10.32975836
OS 27.04233606 10.32051276
OS 27.04233606 10.31126716
OS 27.04326062 10.30479524
OS 27.04326062 10.29924788
OS 27.04326062 10.29554964
OS 27.04326062 10.29462508
OS 27.0414115 10.26134092
OS 27.03771326 10.22898132
OS 27.03309046 10.20031996
OS 27.02939222 10.18645156
OS 27.02661854 10.17443228
OS 27.02384486 10.16333756
OS 27.02014662 10.1531674
OS 27.01737294 10.1439218
OS 27.01552382 10.13652532
OS 27.01275014 10.13097796
OS 27.01182558 10.12635516
OS 27.00997646 10.12358148
OS 27.00997646 10.12265692
OS 26.99610806 10.09492012
OS 26.98039054 10.069957
OS 26.96374846 10.04869212
OS 26.95542742 10.04037108
OS 26.94803094 10.03205004
OS 26.94063446 10.02465356
OS 26.93323798 10.01818164
OS 26.92676606 10.01263428
OS 26.9212187 10.00893604
OS 26.91752046 10.0052378
OS 26.91382222 10.00246412
OS 26.9119731 10.00153956
OS 26.91104854 10.000615
OS 26.8981047 9.99321852
OS 26.88516086 9.9867466
OS 26.85742406 9.97657644
OS 26.82968726 9.96917996
OS 26.80287502 9.96455716
OS 26.78993118 9.96270804
OS 26.77883646 9.96085892
OS 26.7686663 9.95993436
OS 26.76034526 9.95993436
OS 26.75294878 9.9590098
OS 26.74277862 9.9590098
OS 26.72428742 9.95993436
OS 26.70672078 9.96178348
OS 26.6900787 9.9636326
OS 26.67436118 9.96733084
OS 26.65956822 9.97195364
OS 26.64569982 9.97657644
OS 26.63275598 9.98119924
OS 26.6207367 9.9867466
OS 26.61056654 9.9913694
OS 26.60039638 9.9959922
OS 26.5929999 10.000615
OS 26.58560342 10.0052378
OS 26.58098062 10.00893604
OS 26.57635782 10.01078516
OS 26.5745087 10.01263428
OS 26.57358414 10.01355884
OS 26.5606403 10.02465356
OS 26.54954558 10.03574828
OS 26.53937542 10.04869212
OS 26.52920526 10.06163596
OS 26.51256318 10.08752364
OS 26.49961934 10.11341132
OS 26.49407198 10.1254306
OS 26.48944918 10.13652532
OS 26.48575094 10.14669548
OS 26.48297726 10.15501652
OS 26.48020358 10.162413
OS 26.47835446 10.16796036
OS 26.4774299 10.1716586
OS 26.4774299 10.17258316
OS 26.56248942 10.19384804
OS 26.56618766 10.17905508
OS 26.57081046 10.16518668
OS 26.57543326 10.15224284
OS 26.58005606 10.14022356
OS 26.58560342 10.12912884
OS 26.59115078 10.11988324
OS 26.5976227 10.11063764
OS 26.60317006 10.1023166
OS 26.60779286 10.09492012
OS 26.61334022 10.08937276
OS 26.61796302 10.0838254
OS 26.62166126 10.0792026
OS 26.6253595 10.07642892
OS 26.62813318 10.07365524
OS 26.62905774 10.07273068
OS 26.6299823 10.07180612
OS 26.6392279 10.06440964
OS 26.64939806 10.05886228
OS 26.66973838 10.04869212
OS 26.68915414 10.04129564
OS 26.7085699 10.03667284
OS 26.72521198 10.0329746
OS 26.7316839 10.03205004
OS 26.73815582 10.03205004
OS 26.74370318 10.03112548
OS 26.7501751 10.03112548
OS 26.77143998 10.03205004
OS 26.7917803 10.03574828
OS 26.8102715 10.04037108
OS 26.82691358 10.04591844
OS 26.83985742 10.0514658
OS 26.84540478 10.05423948
OS 26.85002758 10.0560886
OS 26.85372582 10.05793772
OS 26.8564995 10.05978684
OS 26.85834862 10.0607114
OS 26.85927318 10.0607114
OS 26.87683982 10.07365524
OS 26.89163278 10.08752364
OS 26.90457662 10.10324116
OS 26.91474678 10.11803412
OS 26.92306782 10.13097796
OS 26.92861518 10.14207268
OS 26.9304643 10.14669548
OS 26.93231342 10.14946916
OS 26.93323798 10.15131828
OS 26.93323798 10.15224284
OS 26.94063446 10.1762814
OS 26.94618182 10.20031996
OS 26.95080462 10.22435852
OS 26.9535783 10.24654796
OS 26.95450286 10.25671812
OS 26.95542742 10.26596372
OS 26.95542742 10.27428476
OS 26.95635198 10.28075668
OS 26.95635198 10.28630404
OS 26.95635198 10.29092684
OS 26.95635198 10.29370052
OS 26.95635198 10.29462508
OS 26.95542742 10.31866364
OS 26.9535783 10.34085308
OS 26.94988006 10.3611934
OS 26.94618182 10.3796846
OS 26.94340814 10.39540212
OS 26.94155902 10.40187404
OS 26.9397099 10.4074214
OS 26.93878534 10.4120442
OS 26.93786078 10.41481788
OS 26.93693622 10.416667
OS 26.93693622 10.41759156
OS 26.92769062 10.43885644
OS 26.91752046 10.4582722
OS 26.90642574 10.47398972
OS 26.89440646 10.48785812
OS 26.8842363 10.49895284
OS 26.87591526 10.50634932
OS 26.86944334 10.51097212
OS 26.86851878 10.51282124
OS 26.86759422 10.51282124
OS 26.84817846 10.52484052
OS 26.82691358 10.53408612
OS 26.80657326 10.54055804
OS 26.7871575 10.54425628
OS 26.76959086 10.54702996
OS 26.76219438 10.54795452
OS 26.75572246 10.54795452
OS 26.75109966 10.54887908
OS 26.74370318 10.54887908
OS 26.72058918 10.54795452
OS 26.6993243 10.54425628
OS 26.68175766 10.53870892
OS 26.66604014 10.53316156
OS 26.65402086 10.52668964
OS 26.64477526 10.52206684
OS 26.6392279 10.5183686
OS 26.63737878 10.51651948
OS 26.62258582 10.50265108
OS 26.60871742 10.48693356
OS 26.5976227 10.47029148
OS 26.5883771 10.4536494
OS 26.58098062 10.43885644
OS 26.57820694 10.43145996
OS 26.57635782 10.4259126
OS 26.5745087 10.4212898
OS 26.57265958 10.41759156
OS 26.57173502 10.41574244
OS 26.57173502 10.41481788
OS 26.48852462 10.43423364
OS 26.49407198 10.45087572
OS 26.49961934 10.46566868
OS 26.50701582 10.47953708
OS 26.51348774 10.49340548
OS 26.52088422 10.50542476
OS 26.52920526 10.51651948
OS 26.53660174 10.5276142
OS 26.54399822 10.5368598
OS 26.5513947 10.54425628
OS 26.55786662 10.55165276
OS 26.56433854 10.55812468
OS 26.56896134 10.56274748
OS 26.57358414 10.56737028
OS 26.57728238 10.57014396
OS 26.5791315 10.57106852
OS 26.58005606 10.57199308
OS 26.5929999 10.58031412
OS 26.60594374 10.58863516
OS 26.61888758 10.59510708
OS 26.63275598 10.60065444
OS 26.66049278 10.60897548
OS 26.6854559 10.61452284
OS 26.69747518 10.61729652
OS 26.70764534 10.61822108
OS 26.7178155 10.61914564
OS 26.72613654 10.6200702
OE
OB 25.68045918 10.61174916 I
OS 25.69062934 10.61267372
OS 25.69895038 10.61267372
OS 25.7239135 10.6108246
OS 25.7470275 10.60712636
OS 25.76644326 10.60065444
OS 25.78308534 10.59418252
OS 25.79695374 10.58678604
OS 25.8025011 10.58401236
OS 25.8071239 10.58031412
OS 25.81082214 10.578465
OS 25.81359582 10.57661588
OS 25.81452038 10.57476676
OS 25.81544494 10.57476676
OS 25.83208702 10.5599738
OS 25.84595542 10.54240716
OS 25.8579747 10.52484052
OS 25.8672203 10.50819844
OS 25.87461678 10.49248092
OS 25.87831502 10.486009
OS 25.88016414 10.47953708
OS 25.88201326 10.47491428
OS 25.88386238 10.47121604
OS 25.88478694 10.46936692
OS 25.88478694 10.46844236
OS 25.88848518 10.45457396
OS 25.89218342 10.44070556
OS 25.89773078 10.41019508
OS 25.90235358 10.3796846
OS 25.90512726 10.35102324
OS 25.90605182 10.33715484
OS 25.90697638 10.32513556
OS 25.90697638 10.31404084
OS 25.90790094 10.30387068
OS 25.90790094 10.2964742
OS 25.90790094 10.29000228
OS 25.90790094 10.28630404
OS 25.90790094 10.28537948
OS 25.90697638 10.25301988
OS 25.90512726 10.2225094
OS 25.90235358 10.1947726
OS 25.89773078 10.16888492
OS 25.89310798 10.14484636
OS 25.88756062 10.12358148
OS 25.88201326 10.10416572
OS 25.8764659 10.08752364
OS 25.87091854 10.07273068
OS 25.86444662 10.05978684
OS 25.85982382 10.04869212
OS 25.85520102 10.04037108
OS 25.85057822 10.0329746
OS 25.84780454 10.0283518
OS 25.84595542 10.02557812
OS 25.84503086 10.02465356
OS 25.8348607 10.01355884
OS 25.82376598 10.00338868
OS 25.8117467 9.99414308
OS 25.79972742 9.9867466
OS 25.78770814 9.98027468
OS 25.77568886 9.97472732
OS 25.76366958 9.97102908
OS 25.75257486 9.96733084
OS 25.74148014 9.96455716
OS 25.73130998 9.96270804
OS 25.72206438 9.96085892
OS 25.7146679 9.95993436
OS 25.70819598 9.9590098
OS 25.69895038 9.9590098
OS 25.67398726 9.96085892
OS 25.65087326 9.96455716
OS 25.6314575 9.97102908
OS 25.61481542 9.977501
OS 25.60094702 9.98397292
OS 25.59632422 9.98767116
OS 25.59170142 9.99044484
OS 25.58800318 9.99229396
OS 25.5852295 9.99414308
OS 25.58430494 9.9959922
OS 25.58338038 9.9959922
OS 25.5667383 10.01170972
OS 25.5528699 10.0283518
OS 25.54085062 10.046843
OS 25.53160502 10.06348508
OS 25.52420854 10.0792026
OS 25.5205103 10.08567452
OS 25.51866118 10.09214644
OS 25.51681206 10.09676924
OS 25.51496294 10.10046748
OS 25.51403838 10.1023166
OS 25.51403838 10.10324116
OS 25.50941558 10.11710956
OS 25.50571734 10.13097796
OS 25.50016998 10.16056388
OS 25.49554718 10.19107436
OS 25.4927735 10.22066028
OS 25.49184894 10.23360412
OS 25.49092438 10.2456234
OS 25.49092438 10.25671812
OS 25.48999982 10.26688828
OS 25.48999982 10.27428476
OS 25.48999982 10.28075668
OS 25.48999982 10.28445492
OS 25.48999982 10.28537948
OS 25.48999982 10.30294612
OS 25.49092438 10.3195882
OS 25.49092438 10.33438116
OS 25.49184894 10.34917412
OS 25.49369806 10.36211796
OS 25.49462262 10.3750618
OS 25.49554718 10.38615652
OS 25.4973963 10.39632668
OS 25.49832086 10.40557228
OS 25.50016998 10.41389332
OS 25.50109454 10.42036524
OS 25.5020191 10.4259126
OS 25.50294366 10.4305354
OS 25.50386822 10.43330908
OS 25.50479278 10.4351582
OS 25.50479278 10.43608276
OS 25.51034014 10.45642308
OS 25.51681206 10.47491428
OS 25.52420854 10.4906318
OS 25.5297559 10.5045002
OS 25.53622782 10.51651948
OS 25.53992606 10.52484052
OS 25.5436243 10.52946332
OS 25.54454886 10.53131244
OS 25.55471902 10.54518084
OS 25.56488918 10.55720012
OS 25.5759839 10.56737028
OS 25.58615406 10.57661588
OS 25.59539966 10.5830878
OS 25.60279614 10.5877106
OS 25.60741894 10.59048428
OS 25.6083435 10.59140884
OS 25.60926806 10.59140884
OS 25.62406102 10.59880532
OS 25.63977854 10.60342812
OS 25.6545715 10.60712636
OS 25.6684399 10.60990004
OS 25.68045918 10.61174916
OE
OB 25.69987494 10.54795452 H
OS 25.68970478 10.54702996
OS 25.67953462 10.5461054
OS 25.67028902 10.54333172
OS 25.66196798 10.53963348
OS 25.64625046 10.53131244
OS 25.63238206 10.52206684
OS 25.6222119 10.51189668
OS 25.61389086 10.50357564
OS 25.61111718 10.4998774
OS 25.60926806 10.49710372
OS 25.60741894 10.49617916
OS 25.60741894 10.4952546
OS 25.60094702 10.48415988
OS 25.59539966 10.47121604
OS 25.5898523 10.45642308
OS 25.58615406 10.44070556
OS 25.58245582 10.42406348
OS 25.57968214 10.40649684
OS 25.57505934 10.37136356
OS 25.57321022 10.35379692
OS 25.57228566 10.3380794
OS 25.5713611 10.32328644
OS 25.5713611 10.31126716
OS 25.57043654 10.30017244
OS 25.57043654 10.2918514
OS 25.57043654 10.2872286
OS 25.57043654 10.28630404
OS 25.57043654 10.28537948
OS 25.57043654 10.25671812
OS 25.57228566 10.23083044
OS 25.57413478 10.20771644
OS 25.5759839 10.185527
OS 25.57875758 10.1670358
OS 25.58245582 10.14946916
OS 25.58615406 10.1346762
OS 25.58892774 10.1208078
OS 25.59262598 10.10971308
OS 25.59632422 10.10046748
OS 25.5990979 10.09214644
OS 25.60279614 10.08567452
OS 25.60464526 10.08105172
OS 25.60649438 10.07827804
OS 25.6083435 10.07642892
OS 25.6083435 10.07550436
OS 25.61573998 10.06625876
OS 25.62313646 10.05886228
OS 25.63053294 10.0514658
OS 25.63792942 10.04591844
OS 25.65364694 10.03667284
OS 25.66751534 10.03020092
OS 25.68045918 10.02650268
OS 25.68970478 10.02465356
OS 25.69340302 10.023729
OS 25.69895038 10.023729
OS 25.70912054 10.02465356
OS 25.71836614 10.02557812
OS 25.73593278 10.03205004
OS 25.7516503 10.04037108
OS 25.7655187 10.04961668
OS 25.77568886 10.05886228
OS 25.7840099 10.06718332
OS 25.7886327 10.07365524
OS 25.79048182 10.0745798
OS 25.79048182 10.07550436
OS 25.79695374 10.08659908
OS 25.8025011 10.09954292
OS 25.80804846 10.11433588
OS 25.8117467 10.1300534
OS 25.81544494 10.14669548
OS 25.81821862 10.16426212
OS 25.82284142 10.20031996
OS 25.82469054 10.21696204
OS 25.8256151 10.23267956
OS 25.82653966 10.24747252
OS 25.82653966 10.2594918
OS 25.82746422 10.27058652
OS 25.82746422 10.27890756
OS 25.82746422 10.28353036
OS 25.82746422 10.28537948
OS 25.82653966 10.31404084
OS 25.8256151 10.33992852
OS 25.82376598 10.36396708
OS 25.8209923 10.38615652
OS 25.81821862 10.40557228
OS 25.81452038 10.42313892
OS 25.81082214 10.43885644
OS 25.8071239 10.45272484
OS 25.80342566 10.46474412
OS 25.80065198 10.47491428
OS 25.79695374 10.48323532
OS 25.79418006 10.4906318
OS 25.79140638 10.4952546
OS 25.78955726 10.49895284
OS 25.78770814 10.50080196
OS 25.78770814 10.50172652
OS 25.78123622 10.51004756
OS 25.7747643 10.51744404
OS 25.76736782 10.5229914
OS 25.75997134 10.52853876
OS 25.74517838 10.5368598
OS 25.73130998 10.54240716
OS 25.7192907 10.54518084
OS 25.70912054 10.54702996
OS 25.7054223 10.54795452
OS 25.69987494 10.54795452
OE
SE
S P 0
OB 28.83724484 16.54452876 I
OS 28.83724484 17.10851036
OS 28.92230436 17.10851036
OS 28.92230436 16.46871484
OS 28.52196988 16.46871484
OS 28.52196988 16.54452876
OS 28.83724484 16.54452876
OE
OB 28.15769324 16.46871484 I
OS 28.15769324 17.11128404
OS 28.20854404 17.11128404
OS 28.21778964 17.09556652
OS 28.2279598 17.08077356
OS 28.23997908 17.0659806
OS 28.2510738 17.05303676
OS 28.26216852 17.04194204
OS 28.27048956 17.03269644
OS 28.2741878 17.02992276
OS 28.27696148 17.02714908
OS 28.27788604 17.02622452
OS 28.2788106 17.02529996
OS 28.29822636 17.00958244
OS 28.31764212 16.99478948
OS 28.33613332 16.98184564
OS 28.35462452 16.97167548
OS 28.37034204 16.96242988
OS 28.37681396 16.95873164
OS 28.38236132 16.95595796
OS 28.38698412 16.95318428
OS 28.39068236 16.95225972
OS 28.39253148 16.9504106
OS 28.39345604 16.9504106
OS 28.39345604 16.87459668
OS 28.37958764 16.88014404
OS 28.36571924 16.88661596
OS 28.35185084 16.89308788
OS 28.338907 16.8995598
OS 28.32781228 16.90510716
OS 28.31856668 16.90972996
OS 28.31301932 16.9134282
OS 28.31209476 16.91435276
OS 28.3111702 16.91435276
OS 28.29452812 16.92452292
OS 28.27973516 16.93469308
OS 28.26679132 16.94393868
OS 28.25662116 16.95225972
OS 28.24737556 16.95873164
OS 28.2418282 16.964279
OS 28.2372054 16.96797724
OS 28.23628084 16.9689018
OS 28.23628084 16.46871484
OS 28.15769324 16.46871484
OE
SE
S P 0
OB 35.73690338 -37.45999874 I
OS 35.61486146 -37.45999874
OS 35.61486146 -36.65701838
OS 35.33471978 -37.45999874
OS 35.2209989 -37.45999874
OS 34.9436309 -36.64314998
OS 34.9436309 -37.45999874
OS 34.82158898 -37.45999874
OS 34.82158898 -36.50030546
OS 35.01158606 -36.50030546
OS 35.23902782 -37.1812439
OS 35.23902782 -37.18263074
OS 35.24041466 -37.18540442
OS 35.2418015 -37.18956494
OS 35.24457518 -37.19649914
OS 35.25012254 -37.21314122
OS 35.25705674 -37.23394382
OS 35.26399094 -37.2575201
OS 35.27231198 -37.28109638
OS 35.27924618 -37.30328582
OS 35.28479354 -37.32270158
OS 35.28618038 -37.3199279
OS 35.28756722 -37.3129937
OS 35.29172774 -37.30051214
OS 35.2972751 -37.28387006
OS 35.3042093 -37.26168062
OS 35.31391718 -37.23533066
OS 35.32362506 -37.20482018
OS 35.33610662 -37.16876234
OS 35.56632206 -36.50030546
OS 35.73690338 -36.50030546
OS 35.73690338 -37.45999874
OE
OB 34.61356298 -37.05504146 I
OS 34.61356298 -37.0564283
OS 34.61356298 -37.06197566
OS 34.61356298 -37.06890986
OS 34.61356298 -37.07861774
OS 34.61217614 -37.0910993
OS 34.61217614 -37.1049677
OS 34.6107893 -37.12160978
OS 34.60940246 -37.13825186
OS 34.60524194 -37.17569654
OS 34.59969458 -37.21452806
OS 34.59137354 -37.25197274
OS 34.58582618 -37.27000166
OS 34.58027882 -37.28664374
OS 34.58027882 -37.28803058
OS 34.57889198 -37.29080426
OS 34.5761183 -37.29496478
OS 34.57334462 -37.30051214
OS 34.56502358 -37.31576738
OS 34.55254202 -37.33518314
OS 34.53589994 -37.35737258
OS 34.51648418 -37.37956202
OS 34.49152106 -37.4031383
OS 34.46101058 -37.4239409
OS 34.45962374 -37.4239409
OS 34.45685006 -37.42671458
OS 34.45268954 -37.42810142
OS 34.44575534 -37.43226194
OS 34.4374343 -37.43642246
OS 34.42633958 -37.44058298
OS 34.41524486 -37.4447435
OS 34.40137646 -37.45029086
OS 34.38612122 -37.45583822
OS 34.36947914 -37.45999874
OS 34.35145022 -37.46415926
OS 34.33064762 -37.46831978
OS 34.30984502 -37.47109346
OS 34.28765558 -37.47386714
OS 34.23772934 -37.47664082
OS 34.22524778 -37.47664082
OS 34.2155399 -37.47525398
OS 34.20444518 -37.47525398
OS 34.19057678 -37.47386714
OS 34.17532154 -37.4724803
OS 34.1600663 -37.47109346
OS 34.1253953 -37.4655461
OS 34.08795062 -37.45722506
OS 34.05189278 -37.44613034
OS 34.01722178 -37.4308751
OS 34.01583494 -37.4308751
OS 34.01306126 -37.42810142
OS 34.00890074 -37.42532774
OS 34.00335338 -37.42255406
OS 33.98809814 -37.41145934
OS 33.97006922 -37.3962041
OS 33.94926662 -37.37678834
OS 33.92985086 -37.3545989
OS 33.9104351 -37.3268621
OS 33.89517986 -37.29635162
OS 33.89517986 -37.29496478
OS 33.89379302 -37.2921911
OS 33.89240618 -37.28664374
OS 33.8896325 -37.27970954
OS 33.88685882 -37.2713885
OS 33.88408514 -37.26029378
OS 33.87992462 -37.24781222
OS 33.87715094 -37.23255698
OS 33.87437726 -37.2159149
OS 33.87021674 -37.19788598
OS 33.86744306 -37.17847022
OS 33.86466938 -37.15766762
OS 33.8618957 -37.13409134
OS 33.86050886 -37.10912822
OS 33.85912202 -37.08277826
OS 33.85912202 -37.05504146
OS 33.85912202 -36.50030546
OS 33.9867113 -36.50030546
OS 33.9867113 -37.05504146
OS 33.9867113 -37.0564283
OS 33.9867113 -37.06058882
OS 33.9867113 -37.06752302
OS 33.9867113 -37.07584406
OS 33.98809814 -37.08555194
OS 33.98809814 -37.0980335
OS 33.98948498 -37.12438346
OS 33.99225866 -37.15489394
OS 33.99641918 -37.18540442
OS 34.00196654 -37.21452806
OS 34.00474022 -37.22700962
OS 34.00890074 -37.23949118
OS 34.01028758 -37.24226486
OS 34.01306126 -37.24919906
OS 34.01999546 -37.25890694
OS 34.0283165 -37.27277534
OS 34.03802438 -37.28664374
OS 34.05189278 -37.30189898
OS 34.06853486 -37.31715422
OS 34.08795062 -37.32963578
OS 34.0907243 -37.33102262
OS 34.0976585 -37.33518314
OS 34.11014006 -37.33934366
OS 34.12678214 -37.34489102
OS 34.1461979 -37.35182522
OS 34.17116102 -37.35598574
OS 34.19751098 -37.36014626
OS 34.22663462 -37.3615331
OS 34.24050302 -37.3615331
OS 34.24882406 -37.36014626
OS 34.26130562 -37.36014626
OS 34.27378718 -37.35875942
OS 34.30429766 -37.35321206
OS 34.33758182 -37.34627786
OS 34.36947914 -37.33518314
OS 34.39998962 -37.3199279
OS 34.41385802 -37.31022002
OS 34.42633958 -37.2991253
OS 34.42772642 -37.29773846
OS 34.42911326 -37.29635162
OS 34.43188694 -37.2921911
OS 34.43604746 -37.28664374
OS 34.44020798 -37.2783227
OS 34.44575534 -37.27000166
OS 34.4513027 -37.2575201
OS 34.45685006 -37.24503854
OS 34.46239742 -37.2297833
OS 34.46655794 -37.21175438
OS 34.4721053 -37.19095178
OS 34.47626582 -37.16876234
OS 34.48042634 -37.14379922
OS 34.48320002 -37.11744926
OS 34.4859737 -37.08693878
OS 34.4859737 -37.05504146
OS 34.4859737 -36.50030546
OS 34.61356298 -36.50030546
OS 34.61356298 -37.05504146
OE
OB 33.64416182 -37.45999874 I
OS 33.51241202 -37.45999874
OS 33.01037594 -36.70694462
OS 33.01037594 -37.45999874
OS 32.88833402 -37.45999874
OS 32.88833402 -36.50030546
OS 33.01869698 -36.50030546
OS 33.5221199 -37.25474642
OS 33.5221199 -36.50030546
OS 33.64416182 -36.50030546
OS 33.64416182 -37.45999874
OE
OB 38.19022334 -36.5016923 I
OS 38.2027049 -36.5016923
OS 38.23182854 -36.50307914
OS 38.26233902 -36.50723966
OS 38.29562318 -36.51140018
OS 38.32613366 -36.51833438
OS 38.3413889 -36.5224949
OS 38.35387046 -36.52665542
OS 38.3552573 -36.52665542
OS 38.35664414 -36.52804226
OS 38.36496518 -36.53220278
OS 38.37744674 -36.53775014
OS 38.39270198 -36.54745802
OS 38.40934406 -36.55993958
OS 38.42737298 -36.57658166
OS 38.44401506 -36.59599742
OS 38.46065714 -36.61818686
OS 38.46065714 -36.6195737
OS 38.46204398 -36.62096054
OS 38.46759134 -36.62928158
OS 38.4731387 -36.64314998
OS 38.48145974 -36.6611789
OS 38.48839394 -36.6819815
OS 38.49532814 -36.70694462
OS 38.49948866 -36.73329458
OS 38.5008755 -36.76241822
OS 38.5008755 -36.76380506
OS 38.5008755 -36.76657874
OS 38.5008755 -36.7721261
OS 38.49948866 -36.7790603
OS 38.49948866 -36.78876818
OS 38.49810182 -36.79847606
OS 38.49255446 -36.82205234
OS 38.48423342 -36.84978914
OS 38.4731387 -36.87891278
OS 38.45649662 -36.90803642
OS 38.4454019 -36.92190482
OS 38.43430718 -36.93577322
OS 38.43292034 -36.93716006
OS 38.4315335 -36.9385469
OS 38.42737298 -36.94270742
OS 38.42182562 -36.94686794
OS 38.41489142 -36.9524153
OS 38.40657038 -36.95796266
OS 38.39547566 -36.96489686
OS 38.38438094 -36.9732179
OS 38.37051254 -36.9801521
OS 38.3552573 -36.9870863
OS 38.33861522 -36.99540734
OS 38.3205863 -37.00234154
OS 38.2997837 -37.0078889
OS 38.2789811 -37.0148231
OS 38.25540482 -37.01898362
OS 38.2304417 -37.02314414
OS 38.23321538 -37.02453098
OS 38.23876274 -37.02730466
OS 38.24708378 -37.03285202
OS 38.2581785 -37.03839938
OS 38.28314162 -37.05365462
OS 38.29562318 -37.0633625
OS 38.3067179 -37.07168354
OS 38.30949158 -37.07445722
OS 38.31642578 -37.08139142
OS 38.3275205 -37.09248614
OS 38.3413889 -37.10635454
OS 38.35664414 -37.1257703
OS 38.37467306 -37.1465729
OS 38.39270198 -37.17153602
OS 38.41211774 -37.19927282
OS 38.5771517 -37.45999874
OS 38.41905194 -37.45999874
OS 38.2928495 -37.26029378
OS 38.2928495 -37.25890694
OS 38.29007582 -37.25613326
OS 38.28730214 -37.25197274
OS 38.28314162 -37.24642538
OS 38.27343374 -37.23117014
OS 38.26095218 -37.21175438
OS 38.24569694 -37.19095178
OS 38.2304417 -37.16876234
OS 38.21518646 -37.14795974
OS 38.20131806 -37.12854398
OS 38.19993122 -37.12715714
OS 38.1957707 -37.12160978
OS 38.1888365 -37.11328874
OS 38.17912862 -37.10358086
OS 38.15832602 -37.08277826
OS 38.1472313 -37.07307038
OS 38.13613658 -37.06474934
OS 38.13474974 -37.0633625
OS 38.13197606 -37.06197566
OS 38.1264287 -37.05920198
OS 38.11810766 -37.05504146
OS 38.10978662 -37.05088094
OS 38.10007874 -37.04672042
OS 38.0778893 -37.03978622
OS 38.07650246 -37.03978622
OS 38.07372878 -37.03839938
OS 38.06818142 -37.03839938
OS 38.06124722 -37.03701254
OS 38.05153934 -37.0356257
OS 38.04044462 -37.0356257
OS 38.02518938 -37.03423886
OS 37.86154226 -37.03423886
OS 37.86154226 -37.45999874
OS 37.73395298 -37.45999874
OS 37.73395298 -36.50030546
OS 38.17912862 -36.50030546
OS 38.19022334 -36.5016923
OE
OB 37.53424802 -36.61402634 I
OS 36.96703046 -36.61402634
OS 36.96703046 -36.90664958
OS 37.49819018 -36.90664958
OS 37.49819018 -37.02037046
OS 36.96703046 -37.02037046
OS 36.96703046 -37.34627786
OS 37.55643746 -37.34627786
OS 37.55643746 -37.45999874
OS 36.83944118 -37.45999874
OS 36.83944118 -36.50030546
OS 37.53424802 -36.50030546
OS 37.53424802 -36.61402634
OE
OB 36.32492354 -36.5016923 I
OS 36.33601826 -36.5016923
OS 36.36098138 -36.50446598
OS 36.38871818 -36.50723966
OS 36.41784182 -36.51278702
OS 36.44696546 -36.51972122
OS 36.47331542 -36.5294291
OS 36.47470226 -36.5294291
OS 36.4760891 -36.53081594
OS 36.48441014 -36.53497646
OS 36.4968917 -36.54191066
OS 36.5107601 -36.55161854
OS 36.52740218 -36.5641001
OS 36.5454311 -36.57935534
OS 36.56207318 -36.5987711
OS 36.57732842 -36.6195737
OS 36.57871526 -36.62234738
OS 36.58287578 -36.63066842
OS 36.58980998 -36.64176314
OS 36.59674418 -36.65840522
OS 36.60367838 -36.67782098
OS 36.61061258 -36.69862358
OS 36.6147731 -36.72219986
OS 36.61615994 -36.74577614
OS 36.61615994 -36.74854982
OS 36.61615994 -36.75548402
OS 36.6147731 -36.76796558
OS 36.61199942 -36.78322082
OS 36.6078389 -36.80124974
OS 36.6009047 -36.8206655
OS 36.59258366 -36.84008126
OS 36.58148894 -36.86088386
OS 36.5801021 -36.86365754
OS 36.57594158 -36.8692049
OS 36.56762054 -36.88029962
OS 36.55652582 -36.89139434
OS 36.54265742 -36.90526274
OS 36.52601534 -36.92051798
OS 36.50521274 -36.93438638
OS 36.48163646 -36.94825478
OS 36.4830233 -36.94825478
OS 36.48579698 -36.94964162
OS 36.4899575 -36.95102846
OS 36.49550486 -36.95380214
OS 36.51214694 -36.9593495
OS 36.5315627 -36.96905738
OS 36.5523653 -36.98153894
OS 36.57594158 -36.99679418
OS 36.59674418 -37.0148231
OS 36.61615994 -37.03701254
OS 36.61754678 -37.03978622
OS 36.62309414 -37.04810726
OS 36.63141518 -37.06058882
OS 36.63973622 -37.0772309
OS 36.64805726 -37.09942034
OS 36.6563783 -37.12299662
OS 36.66192566 -37.15073342
OS 36.6633125 -37.1812439
OS 36.6633125 -37.18263074
OS 36.6633125 -37.18401758
OS 36.6633125 -37.19233862
OS 36.66192566 -37.20620702
OS 36.65915198 -37.2228491
OS 36.6563783 -37.24226486
OS 36.65083094 -37.26306746
OS 36.64389674 -37.2852569
OS 36.63418886 -37.30744634
OS 36.63280202 -37.31022002
OS 36.6286415 -37.31715422
OS 36.62309414 -37.3268621
OS 36.6147731 -37.3407305
OS 36.60367838 -37.3545989
OS 36.59258366 -37.36985414
OS 36.57871526 -37.38510938
OS 36.56346002 -37.39759094
OS 36.56207318 -37.39897778
OS 36.55652582 -37.4031383
OS 36.54681794 -37.40868566
OS 36.53433638 -37.41423302
OS 36.51908114 -37.42255406
OS 36.50105222 -37.4308751
OS 36.48163646 -37.4378093
OS 36.45806018 -37.4447435
OS 36.4552865 -37.4447435
OS 36.44696546 -37.44751718
OS 36.43309706 -37.44890402
OS 36.41506814 -37.4516777
OS 36.3928787 -37.45445138
OS 36.36652874 -37.45722506
OS 36.3374051 -37.4586119
OS 36.30412094 -37.45999874
OS 35.93799518 -37.45999874
OS 35.93799518 -36.50030546
OS 36.31521566 -36.50030546
OS 36.32492354 -36.5016923
OE
OB 32.3849111 -36.61402634 I
OS 32.06871158 -36.61402634
OS 32.06871158 -37.45999874
OS 31.9411223 -37.45999874
OS 31.9411223 -36.61402634
OS 31.62492278 -36.61402634
OS 31.62492278 -36.50030546
OS 32.3849111 -36.50030546
OS 32.3849111 -36.61402634
OE
OB 30.62639798 -37.45999874 I
OS 30.48216662 -37.45999874
OS 30.36983258 -37.16876234
OS 29.96764898 -37.16876234
OS 29.86363598 -37.45999874
OS 29.7291125 -37.45999874
OS 30.09523826 -36.50030546
OS 30.23392226 -36.50030546
OS 30.62639798 -37.45999874
OE
OB 29.3546657 -36.5016923 I
OS 29.37824198 -36.50307914
OS 29.4032051 -36.50446598
OS 29.42678138 -36.50723966
OS 29.44758398 -36.51001334
OS 29.45035766 -36.51001334
OS 29.46006554 -36.51278702
OS 29.4725471 -36.5155607
OS 29.48918918 -36.51972122
OS 29.5072181 -36.52665542
OS 29.52663386 -36.53497646
OS 29.54743646 -36.54468434
OS 29.56546538 -36.55577906
OS 29.56823906 -36.5571659
OS 29.57378642 -36.56132642
OS 29.58210746 -36.56964746
OS 29.59320218 -36.57935534
OS 29.60568374 -36.5918369
OS 29.6181653 -36.60847898
OS 29.6320337 -36.6265079
OS 29.64312842 -36.6473105
OS 29.64451526 -36.65008418
OS 29.64728894 -36.65701838
OS 29.6528363 -36.66949994
OS 29.65838366 -36.68614202
OS 29.66254418 -36.70555778
OS 29.66809154 -36.72774722
OS 29.67086522 -36.75271034
OS 29.67225206 -36.7790603
OS 29.67225206 -36.78044714
OS 29.67225206 -36.78460766
OS 29.67225206 -36.79015502
OS 29.67086522 -36.7998629
OS 29.66947838 -36.80957078
OS 29.66809154 -36.82205234
OS 29.66531786 -36.83592074
OS 29.66254418 -36.85117598
OS 29.6528363 -36.8830733
OS 29.64728894 -36.89971538
OS 29.6389679 -36.9177443
OS 29.62926002 -36.93577322
OS 29.61955214 -36.9524153
OS 29.60707058 -36.96905738
OS 29.59320218 -36.98569946
OS 29.59181534 -36.9870863
OS 29.58904166 -36.98985998
OS 29.58488114 -36.9940205
OS 29.57794694 -36.99818102
OS 29.5696259 -37.00511522
OS 29.55853118 -37.01204942
OS 29.54466278 -37.02037046
OS 29.52940754 -37.02730466
OS 29.51137862 -37.0356257
OS 29.49057602 -37.04394674
OS 29.46838658 -37.05088094
OS 29.44203662 -37.0564283
OS 29.41429982 -37.06197566
OS 29.38378934 -37.06613618
OS 29.34911834 -37.06890986
OS 29.3130605 -37.0702967
OS 29.06758982 -37.0702967
OS 29.06758982 -37.45999874
OS 28.94000054 -37.45999874
OS 28.94000054 -36.50030546
OS 29.3338631 -36.50030546
OS 29.3546657 -36.5016923
OE
OB 31.18668134 -36.5016923 I
OS 31.1991629 -36.5016923
OS 31.22828654 -36.50307914
OS 31.25879702 -36.50723966
OS 31.29208118 -36.51140018
OS 31.32259166 -36.51833438
OS 31.3378469 -36.5224949
OS 31.35032846 -36.52665542
OS 31.3517153 -36.52665542
OS 31.35310214 -36.52804226
OS 31.36142318 -36.53220278
OS 31.37390474 -36.53775014
OS 31.38915998 -36.54745802
OS 31.40580206 -36.55993958
OS 31.42383098 -36.57658166
OS 31.44047306 -36.59599742
OS 31.45711514 -36.61818686
OS 31.45711514 -36.6195737
OS 31.45850198 -36.62096054
OS 31.46404934 -36.62928158
OS 31.4695967 -36.64314998
OS 31.47791774 -36.6611789
OS 31.48485194 -36.6819815
OS 31.49178614 -36.70694462
OS 31.49594666 -36.73329458
OS 31.4973335 -36.76241822
OS 31.4973335 -36.76380506
OS 31.4973335 -36.76657874
OS 31.4973335 -36.7721261
OS 31.49594666 -36.7790603
OS 31.49594666 -36.78876818
OS 31.49455982 -36.79847606
OS 31.48901246 -36.82205234
OS 31.48069142 -36.84978914
OS 31.4695967 -36.87891278
OS 31.45295462 -36.90803642
OS 31.4418599 -36.92190482
OS 31.43076518 -36.93577322
OS 31.42937834 -36.93716006
OS 31.4279915 -36.9385469
OS 31.42383098 -36.94270742
OS 31.41828362 -36.94686794
OS 31.41134942 -36.9524153
OS 31.40302838 -36.95796266
OS 31.39193366 -36.96489686
OS 31.38083894 -36.9732179
OS 31.36697054 -36.9801521
OS 31.3517153 -36.9870863
OS 31.33507322 -36.99540734
OS 31.3170443 -37.00234154
OS 31.2962417 -37.0078889
OS 31.2754391 -37.0148231
OS 31.25186282 -37.01898362
OS 31.2268997 -37.02314414
OS 31.22967338 -37.02453098
OS 31.23522074 -37.02730466
OS 31.24354178 -37.03285202
OS 31.2546365 -37.03839938
OS 31.27959962 -37.05365462
OS 31.29208118 -37.0633625
OS 31.3031759 -37.07168354
OS 31.30594958 -37.07445722
OS 31.31288378 -37.08139142
OS 31.3239785 -37.09248614
OS 31.3378469 -37.10635454
OS 31.35310214 -37.1257703
OS 31.37113106 -37.1465729
OS 31.38915998 -37.17153602
OS 31.40857574 -37.19927282
OS 31.5736097 -37.45999874
OS 31.41550994 -37.45999874
OS 31.2893075 -37.26029378
OS 31.2893075 -37.25890694
OS 31.28653382 -37.25613326
OS 31.28376014 -37.25197274
OS 31.27959962 -37.24642538
OS 31.26989174 -37.23117014
OS 31.25741018 -37.21175438
OS 31.24215494 -37.19095178
OS 31.2268997 -37.16876234
OS 31.21164446 -37.14795974
OS 31.19777606 -37.12854398
OS 31.19638922 -37.12715714
OS 31.1922287 -37.12160978
OS 31.1852945 -37.11328874
OS 31.17558662 -37.10358086
OS 31.15478402 -37.08277826
OS 31.1436893 -37.07307038
OS 31.13259458 -37.06474934
OS 31.13120774 -37.0633625
OS 31.12843406 -37.06197566
OS 31.1228867 -37.05920198
OS 31.11456566 -37.05504146
OS 31.10624462 -37.05088094
OS 31.09653674 -37.04672042
OS 31.0743473 -37.03978622
OS 31.07296046 -37.03978622
OS 31.07018678 -37.03839938
OS 31.06463942 -37.03839938
OS 31.05770522 -37.03701254
OS 31.04799734 -37.0356257
OS 31.03690262 -37.0356257
OS 31.02164738 -37.03423886
OS 30.85800026 -37.03423886
OS 30.85800026 -37.45999874
OS 30.73041098 -37.45999874
OS 30.73041098 -36.50030546
OS 31.17558662 -36.50030546
OS 31.18668134 -36.5016923
OE
OB 38.16387338 -36.60709214 H
OS 37.86154226 -36.60709214
OS 37.86154226 -36.9246785
OS 38.1472313 -36.9246785
OS 38.16387338 -36.92329166
OS 38.18328914 -36.92190482
OS 38.20547858 -36.92051798
OS 38.22766802 -36.9177443
OS 38.24985746 -36.91358378
OS 38.26927322 -36.90803642
OS 38.2720469 -36.90664958
OS 38.27759426 -36.9038759
OS 38.2859153 -36.89971538
OS 38.29701002 -36.89416802
OS 38.30949158 -36.88584698
OS 38.32197314 -36.8761391
OS 38.3344547 -36.86365754
OS 38.34416258 -36.84978914
OS 38.34554942 -36.8484023
OS 38.3483231 -36.84285494
OS 38.35248362 -36.8345339
OS 38.35803098 -36.82343918
OS 38.3621915 -36.81095762
OS 38.36635202 -36.79708922
OS 38.3691257 -36.78044714
OS 38.37051254 -36.76380506
OS 38.37051254 -36.76241822
OS 38.37051254 -36.76103138
OS 38.3691257 -36.75271034
OS 38.36773886 -36.74022878
OS 38.36496518 -36.7235867
OS 38.35803098 -36.70694462
OS 38.34970994 -36.68752886
OS 38.33722838 -36.66949994
OS 38.3205863 -36.65147102
OS 38.31781262 -36.65008418
OS 38.31087842 -36.64453682
OS 38.2997837 -36.63760262
OS 38.28175478 -36.62928158
OS 38.26095218 -36.62096054
OS 38.23321538 -36.61402634
OS 38.20131806 -36.60847898
OS 38.16387338 -36.60709214
OE
OB 29.34218414 -36.61402634 H
OS 29.06758982 -36.61402634
OS 29.06758982 -36.95657582
OS 29.32554206 -36.95657582
OS 29.33524994 -36.95518898
OS 29.34495782 -36.95518898
OS 29.35605254 -36.95380214
OS 29.3824025 -36.95102846
OS 29.41152614 -36.9454811
OS 29.44064978 -36.93716006
OS 29.46699974 -36.92606534
OS 29.4794813 -36.91913114
OS 29.48918918 -36.9108101
OS 29.49196286 -36.90803642
OS 29.49751022 -36.90248906
OS 29.50583126 -36.89139434
OS 29.51553914 -36.87752594
OS 29.52524702 -36.85949702
OS 29.53356806 -36.83730758
OS 29.53911542 -36.81234446
OS 29.5418891 -36.78322082
OS 29.5418891 -36.78183398
OS 29.5418891 -36.78044714
OS 29.5418891 -36.77351294
OS 29.54050226 -36.76103138
OS 29.53772858 -36.74716298
OS 29.5349549 -36.73190774
OS 29.52940754 -36.71387882
OS 29.5210865 -36.69723674
OS 29.51137862 -36.68059466
OS 29.50999178 -36.67920782
OS 29.50583126 -36.67366046
OS 29.49889706 -36.66672626
OS 29.49057602 -36.65701838
OS 29.47809446 -36.6473105
OS 29.46422606 -36.63898946
OS 29.44897082 -36.63066842
OS 29.4309419 -36.62373422
OS 29.42955506 -36.62373422
OS 29.4240077 -36.62234738
OS 29.41568666 -36.62096054
OS 29.40459194 -36.61818686
OS 29.38794986 -36.61680002
OS 29.36714726 -36.61541318
OS 29.34218414 -36.61402634
OE
OB 30.16180658 -36.60015794 H
OS 30.16180658 -36.60154478
OS 30.16041974 -36.60431846
OS 30.16041974 -36.60986582
OS 30.15764606 -36.61541318
OS 30.15625922 -36.62512106
OS 30.15348554 -36.63482894
OS 30.14793818 -36.65840522
OS 30.14100398 -36.68614202
OS 30.1312961 -36.7166525
OS 30.12158822 -36.74993666
OS 30.10910666 -36.78460766
OS 30.00509366 -37.06474934
OS 30.32961422 -37.06474934
OS 30.22976174 -36.80124974
OS 30.22976174 -36.7998629
OS 30.2283749 -36.79570238
OS 30.22560122 -36.78876818
OS 30.22282754 -36.78044714
OS 30.21866702 -36.77073926
OS 30.2145065 -36.7582577
OS 30.21034598 -36.7443893
OS 30.20479862 -36.7305209
OS 30.1937039 -36.69862358
OS 30.18260918 -36.66533942
OS 30.17151446 -36.63205526
OS 30.16180658 -36.60015794
OE
OB 31.16033138 -36.60709214 H
OS 30.85800026 -36.60709214
OS 30.85800026 -36.9246785
OS 31.1436893 -36.9246785
OS 31.16033138 -36.92329166
OS 31.17974714 -36.92190482
OS 31.20193658 -36.92051798
OS 31.22412602 -36.9177443
OS 31.24631546 -36.91358378
OS 31.26573122 -36.90803642
OS 31.2685049 -36.90664958
OS 31.27405226 -36.9038759
OS 31.2823733 -36.89971538
OS 31.29346802 -36.89416802
OS 31.30594958 -36.88584698
OS 31.31843114 -36.8761391
OS 31.3309127 -36.86365754
OS 31.34062058 -36.84978914
OS 31.34200742 -36.8484023
OS 31.3447811 -36.84285494
OS 31.34894162 -36.8345339
OS 31.35448898 -36.82343918
OS 31.3586495 -36.81095762
OS 31.36281002 -36.79708922
OS 31.3655837 -36.78044714
OS 31.36697054 -36.76380506
OS 31.36697054 -36.76241822
OS 31.36697054 -36.76103138
OS 31.3655837 -36.75271034
OS 31.36419686 -36.74022878
OS 31.36142318 -36.7235867
OS 31.35448898 -36.70694462
OS 31.34616794 -36.68752886
OS 31.33368638 -36.66949994
OS 31.3170443 -36.65147102
OS 31.31427062 -36.65008418
OS 31.30733642 -36.64453682
OS 31.2962417 -36.63760262
OS 31.27821278 -36.62928158
OS 31.25741018 -36.62096054
OS 31.22967338 -36.61402634
OS 31.19777606 -36.60847898
OS 31.16033138 -36.60709214
OE
OB 36.29302622 -36.61402634 H
OS 36.06558446 -36.61402634
OS 36.06558446 -36.90248906
OS 36.30134726 -36.90248906
OS 36.31937618 -36.90110222
OS 36.33879194 -36.89971538
OS 36.3582077 -36.89832854
OS 36.37762346 -36.89555486
OS 36.3928787 -36.89278118
OS 36.39565238 -36.89139434
OS 36.40119974 -36.8900075
OS 36.40952078 -36.88584698
OS 36.4206155 -36.88029962
OS 36.43171022 -36.87475226
OS 36.44419178 -36.86643122
OS 36.45667334 -36.8553365
OS 36.46638122 -36.84424178
OS 36.46776806 -36.84285494
OS 36.47054174 -36.83869442
OS 36.47470226 -36.83037338
OS 36.47886278 -36.8206655
OS 36.4830233 -36.80957078
OS 36.48718382 -36.79570238
OS 36.4899575 -36.7790603
OS 36.49134434 -36.76103138
OS 36.49134434 -36.7582577
OS 36.49134434 -36.75271034
OS 36.4899575 -36.7443893
OS 36.48857066 -36.73329458
OS 36.48579698 -36.71942618
OS 36.48163646 -36.70555778
OS 36.4760891 -36.69168938
OS 36.46776806 -36.67782098
OS 36.46638122 -36.67643414
OS 36.46360754 -36.67227362
OS 36.45806018 -36.66533942
OS 36.45112598 -36.65840522
OS 36.4414181 -36.65008418
OS 36.43032338 -36.64176314
OS 36.41645498 -36.6334421
OS 36.40119974 -36.62789474
OS 36.3998129 -36.62789474
OS 36.3928787 -36.62512106
OS 36.38317082 -36.62373422
OS 36.36791558 -36.62096054
OS 36.34711298 -36.61818686
OS 36.3235367 -36.61680002
OS 36.29302622 -36.61402634
OE
OB 36.31798934 -37.01620994 H
OS 36.06558446 -37.01620994
OS 36.06558446 -37.34627786
OS 36.33879194 -37.34627786
OS 36.36791558 -37.34489102
OS 36.38039714 -37.34350418
OS 36.39149186 -37.34211734
OS 36.3928787 -37.34211734
OS 36.39842606 -37.3407305
OS 36.4067471 -37.33934366
OS 36.41645498 -37.33656998
OS 36.44003126 -37.32824894
OS 36.46360754 -37.31715422
OS 36.46499438 -37.31576738
OS 36.4691549 -37.3129937
OS 36.47470226 -37.30883318
OS 36.48163646 -37.30328582
OS 36.48857066 -37.29496478
OS 36.49827854 -37.28664374
OS 36.50521274 -37.27554902
OS 36.51353378 -37.26306746
OS 36.51492062 -37.26168062
OS 36.51630746 -37.2575201
OS 36.51908114 -37.24919906
OS 36.52324166 -37.23949118
OS 36.52740218 -37.22839646
OS 36.53017586 -37.21452806
OS 36.5315627 -37.19788598
OS 36.53294954 -37.1812439
OS 36.53294954 -37.17847022
OS 36.53294954 -37.17292286
OS 36.5315627 -37.16182814
OS 36.52878902 -37.14934658
OS 36.52601534 -37.13547818
OS 36.52046798 -37.12022294
OS 36.51353378 -37.1049677
OS 36.5038259 -37.08971246
OS 36.50243906 -37.08832562
OS 36.49827854 -37.08277826
OS 36.49273118 -37.07584406
OS 36.48441014 -37.06752302
OS 36.47331542 -37.05781514
OS 36.45944702 -37.04810726
OS 36.44419178 -37.03978622
OS 36.42616286 -37.03285202
OS 36.42338918 -37.03146518
OS 36.41784182 -37.03007834
OS 36.40536026 -37.02730466
OS 36.39010502 -37.02453098
OS 36.37068926 -37.0217573
OS 36.34711298 -37.01898362
OS 36.31798934 -37.01620994
OE
SE
S P 0
OB 40.9056459 -38.32112732 I
OS 40.92136342 -38.32205188
OS 40.9380055 -38.32297644
OS 40.95372302 -38.32482556
OS 40.96759142 -38.32667468
OS 40.96944054 -38.32667468
OS 40.97591246 -38.3285238
OS 40.9842335 -38.33037292
OS 40.99532822 -38.3331466
OS 41.0073475 -38.3377694
OS 41.02029134 -38.34331676
OS 41.03415974 -38.34978868
OS 41.04617902 -38.35718516
OS 41.04802814 -38.35810972
OS 41.05172638 -38.3608834
OS 41.05727374 -38.36643076
OS 41.06467022 -38.37290268
OS 41.07299126 -38.38122372
OS 41.0813123 -38.39231844
OS 41.0905579 -38.40433772
OS 41.09795438 -38.41820612
OS 41.09887894 -38.42005524
OS 41.10072806 -38.42467804
OS 41.1044263 -38.43299908
OS 41.10812454 -38.4440938
OS 41.11089822 -38.45703764
OS 41.11459646 -38.4718306
OS 41.11644558 -38.48847268
OS 41.11737014 -38.50603932
OS 41.11737014 -38.50696388
OS 41.11737014 -38.50973756
OS 41.11737014 -38.5134358
OS 41.11644558 -38.51990772
OS 41.11552102 -38.52637964
OS 41.11459646 -38.53470068
OS 41.11274734 -38.54394628
OS 41.11089822 -38.55411644
OS 41.1044263 -38.57538132
OS 41.10072806 -38.58647604
OS 41.0951807 -38.59849532
OS 41.08870878 -38.6105146
OS 41.08223686 -38.62160932
OS 41.07391582 -38.63270404
OS 41.06467022 -38.64379876
OS 41.06374566 -38.64472332
OS 41.06189654 -38.64657244
OS 41.05912286 -38.64934612
OS 41.05450006 -38.6521198
OS 41.0489527 -38.6567426
OS 41.04155622 -38.6613654
OS 41.03231062 -38.66691276
OS 41.02214046 -38.67153556
OS 41.01012118 -38.67708292
OS 40.99625278 -38.68263028
OS 40.98145982 -38.68725308
OS 40.96389318 -38.69095132
OS 40.94540198 -38.69464956
OS 40.92506166 -38.69742324
OS 40.90194766 -38.69927236
OS 40.8779091 -38.70019692
OS 40.71426198 -38.70019692
OS 40.71426198 -38.95999828
OS 40.62920246 -38.95999828
OS 40.62920246 -38.32020276
OS 40.8917775 -38.32020276
OS 40.9056459 -38.32112732
OE
OB 40.49791494 -38.98403684 I
OS 40.49791494 -38.9849614
OS 40.49791494 -38.98773508
OS 40.49791494 -38.99235788
OS 40.49791494 -38.99790524
OS 40.49699038 -39.00530172
OS 40.49699038 -39.0126982
OS 40.49514126 -39.0311894
OS 40.49236758 -39.05060516
OS 40.48866934 -39.07094548
OS 40.48312198 -39.08851212
OS 40.47942374 -39.09683316
OS 40.4757255 -39.10330508
OS 40.4757255 -39.10422964
OS 40.47480094 -39.1051542
OS 40.47017814 -39.109777
OS 40.46278166 -39.11717348
OS 40.45353606 -39.12549452
OS 40.44059222 -39.13381556
OS 40.42395014 -39.14028748
OS 40.40453438 -39.14583484
OS 40.39343966 -39.1467594
OS 40.38142038 -39.14768396
OS 40.37587302 -39.14768396
OS 40.37032566 -39.1467594
OS 40.36200462 -39.1467594
OS 40.35275902 -39.14583484
OS 40.34258886 -39.14398572
OS 40.32039942 -39.13843836
OS 40.33519238 -39.07187004
OS 40.33611694 -39.07187004
OS 40.33889062 -39.0727946
OS 40.34351342 -39.07371916
OS 40.34813622 -39.07464372
OS 40.3601555 -39.0774174
OS 40.36570286 -39.07834196
OS 40.37494846 -39.07834196
OS 40.37957126 -39.0774174
OS 40.38511862 -39.07649284
OS 40.39066598 -39.07464372
OS 40.39621334 -39.07094548
OS 40.40268526 -39.06724724
OS 40.40730806 -39.06169988
OS 40.40823262 -39.06077532
OS 40.40915718 -39.05800164
OS 40.4110063 -39.05337884
OS 40.41377998 -39.04598236
OS 40.4156291 -39.0358122
OS 40.41655366 -39.02841572
OS 40.41747822 -39.0219438
OS 40.41840278 -39.01362276
OS 40.41840278 -39.0034526
OS 40.41932734 -38.99328244
OS 40.41932734 -38.98218772
OS 40.41932734 -38.49586916
OS 40.49791494 -38.49586916
OS 40.49791494 -38.98403684
OE
OB 41.51770462 -38.3100326 I
OS 41.52602566 -38.31095716
OS 41.53619582 -38.31188172
OS 41.54636598 -38.31280628
OS 41.55838526 -38.31557996
OS 41.58334838 -38.32112732
OS 41.61108518 -38.32944836
OS 41.62495358 -38.33499572
OS 41.63789742 -38.34146764
OS 41.65084126 -38.34978868
OS 41.6637851 -38.35810972
OS 41.66470966 -38.35903428
OS 41.66655878 -38.35995884
OS 41.67025702 -38.36273252
OS 41.67487982 -38.36735532
OS 41.67950262 -38.37197812
OS 41.68597454 -38.37845004
OS 41.69244646 -38.38584652
OS 41.69984294 -38.393243
OS 41.70723942 -38.4024886
OS 41.7146359 -38.41358332
OS 41.72295694 -38.42467804
OS 41.73035342 -38.43669732
OS 41.73682534 -38.45056572
OS 41.74422182 -38.46443412
OS 41.74976918 -38.47922708
OS 41.75531654 -38.49586916
OS 41.67210614 -38.51528492
OS 41.67210614 -38.51436036
OS 41.67118158 -38.51251124
OS 41.66933246 -38.508813
OS 41.66748334 -38.5041902
OS 41.66563422 -38.49864284
OS 41.66286054 -38.49124636
OS 41.65546406 -38.4764534
OS 41.64621846 -38.45981132
OS 41.63512374 -38.44316924
OS 41.62125534 -38.42745172
OS 41.60646238 -38.41358332
OS 41.60461326 -38.4117342
OS 41.5990659 -38.40803596
OS 41.5898203 -38.40341316
OS 41.57780102 -38.39694124
OS 41.5620835 -38.39139388
OS 41.54451686 -38.38584652
OS 41.52325198 -38.38214828
OS 41.50013798 -38.38122372
OS 41.4927415 -38.38122372
OS 41.4881187 -38.38214828
OS 41.48164678 -38.38214828
OS 41.4742503 -38.38307284
OS 41.45668366 -38.38584652
OS 41.4372679 -38.38954476
OS 41.41692758 -38.39601668
OS 41.3956627 -38.40526228
OS 41.37624694 -38.41728156
OS 41.37532238 -38.41728156
OS 41.37439782 -38.41913068
OS 41.3679259 -38.42375348
OS 41.35960486 -38.43114996
OS 41.3494347 -38.44224468
OS 41.33741542 -38.45611308
OS 41.3263207 -38.4718306
OS 41.31615054 -38.49124636
OS 41.30690494 -38.51251124
OS 41.30690494 -38.5134358
OS 41.30598038 -38.51528492
OS 41.30505582 -38.5180586
OS 41.30413126 -38.5226814
OS 41.30228214 -38.52822876
OS 41.30043302 -38.53470068
OS 41.29765934 -38.5504182
OS 41.2939611 -38.5689094
OS 41.29026286 -38.58924972
OS 41.28841374 -38.61143916
OS 41.28748918 -38.63547772
OS 41.28748918 -38.63640228
OS 41.28748918 -38.63917596
OS 41.28748918 -38.64379876
OS 41.28748918 -38.64934612
OS 41.28841374 -38.65581804
OS 41.28841374 -38.66413908
OS 41.2893383 -38.67338468
OS 41.29026286 -38.68355484
OS 41.29303654 -38.70574428
OS 41.29765934 -38.72978284
OS 41.3032067 -38.7538214
OS 41.31060318 -38.77785996
OS 41.31060318 -38.77878452
OS 41.31152774 -38.78063364
OS 41.31337686 -38.78340732
OS 41.31522598 -38.78803012
OS 41.32077334 -38.79912484
OS 41.32909438 -38.81206868
OS 41.33926454 -38.82686164
OS 41.35220838 -38.84257916
OS 41.36700134 -38.85644756
OS 41.38456798 -38.8693914
OS 41.38549254 -38.8693914
OS 41.38734166 -38.87031596
OS 41.39011534 -38.87216508
OS 41.39381358 -38.8740142
OS 41.39843638 -38.87586332
OS 41.40398374 -38.878637
OS 41.41692758 -38.88418436
OS 41.43356966 -38.88973172
OS 41.45206086 -38.89435452
OS 41.47240118 -38.89805276
OS 41.49366606 -38.89897732
OS 41.50013798 -38.89897732
OS 41.50568534 -38.89805276
OS 41.51215726 -38.89805276
OS 41.51862918 -38.8971282
OS 41.53527126 -38.89342996
OS 41.55468702 -38.88880716
OS 41.57410278 -38.88141068
OS 41.5944431 -38.87124052
OS 41.60461326 -38.86569316
OS 41.61385886 -38.85829668
OS 41.61478342 -38.85737212
OS 41.61570798 -38.85644756
OS 41.61848166 -38.85367388
OS 41.6221799 -38.8509002
OS 41.62587814 -38.8462774
OS 41.63050094 -38.84073004
OS 41.6360483 -38.83518268
OS 41.6406711 -38.8277862
OS 41.64621846 -38.81946516
OS 41.65269038 -38.81021956
OS 41.65823774 -38.80097396
OS 41.6637851 -38.78987924
OS 41.6684079 -38.77785996
OS 41.6730307 -38.76491612
OS 41.6776535 -38.75104772
OS 41.68135174 -38.73625476
OS 41.76641126 -38.75751964
OS 41.76641126 -38.7584442
OS 41.7654867 -38.76214244
OS 41.76363758 -38.7676898
OS 41.7608639 -38.77508628
OS 41.75809022 -38.78340732
OS 41.75439198 -38.79357748
OS 41.74976918 -38.8046722
OS 41.74422182 -38.81669148
OS 41.73127798 -38.84257916
OS 41.7146359 -38.86846684
OS 41.70446574 -38.88141068
OS 41.69429558 -38.89435452
OS 41.68320086 -38.90544924
OS 41.67025702 -38.91654396
OS 41.66933246 -38.91746852
OS 41.66748334 -38.91931764
OS 41.66286054 -38.92116676
OS 41.65823774 -38.924865
OS 41.65084126 -38.9294878
OS 41.64344478 -38.9341106
OS 41.63327462 -38.9387334
OS 41.62310446 -38.9433562
OS 41.61108518 -38.94890356
OS 41.59814134 -38.95352636
OS 41.58427294 -38.95814916
OS 41.56947998 -38.96277196
OS 41.55376246 -38.9664702
OS 41.53712038 -38.96831932
OS 41.51955374 -38.97016844
OS 41.50106254 -38.971093
OS 41.49089238 -38.971093
OS 41.4834959 -38.97016844
OS 41.47517486 -38.97016844
OS 41.4650047 -38.96924388
OS 41.45390998 -38.96739476
OS 41.44096614 -38.96554564
OS 41.4141539 -38.96092284
OS 41.3864171 -38.95352636
OS 41.3586803 -38.9433562
OS 41.34573646 -38.93688428
OS 41.33279262 -38.9294878
OS 41.33186806 -38.92856324
OS 41.33001894 -38.92763868
OS 41.3263207 -38.924865
OS 41.32262246 -38.92116676
OS 41.3170751 -38.91746852
OS 41.31060318 -38.91192116
OS 41.3032067 -38.90544924
OS 41.29581022 -38.89805276
OS 41.28841374 -38.88973172
OS 41.2800927 -38.88141068
OS 41.26345062 -38.8601458
OS 41.2477331 -38.83518268
OS 41.2338647 -38.80744588
OS 41.2338647 -38.80652132
OS 41.23201558 -38.80374764
OS 41.23109102 -38.79912484
OS 41.22831734 -38.79357748
OS 41.22646822 -38.786181
OS 41.22369454 -38.7769354
OS 41.2199963 -38.76676524
OS 41.21722262 -38.75567052
OS 41.21444894 -38.74365124
OS 41.2107507 -38.72978284
OS 41.2061279 -38.70112148
OS 41.20242966 -38.66876188
OS 41.20058054 -38.63547772
OS 41.20058054 -38.63455316
OS 41.20058054 -38.63085492
OS 41.20058054 -38.62530756
OS 41.2015051 -38.61883564
OS 41.2015051 -38.60959004
OS 41.20242966 -38.60034444
OS 41.20335422 -38.58832516
OS 41.20520334 -38.57630588
OS 41.20982614 -38.54949364
OS 41.21629806 -38.51990772
OS 41.22554366 -38.4903218
OS 41.2384875 -38.46166044
OS 41.23941206 -38.46073588
OS 41.24033662 -38.4579622
OS 41.24218574 -38.45426396
OS 41.24588398 -38.44964116
OS 41.24958222 -38.44316924
OS 41.25420502 -38.43577276
OS 41.2662243 -38.41913068
OS 41.28194182 -38.40063948
OS 41.30043302 -38.38214828
OS 41.3216979 -38.36365708
OS 41.34666102 -38.34793956
OS 41.34758558 -38.347015
OS 41.35035926 -38.34609044
OS 41.3540575 -38.34424132
OS 41.3586803 -38.34146764
OS 41.36607678 -38.33869396
OS 41.37347326 -38.33592028
OS 41.38271886 -38.33222204
OS 41.39288902 -38.3285238
OS 41.40398374 -38.32482556
OS 41.41600302 -38.32112732
OS 41.4418907 -38.31557996
OS 41.47147662 -38.31095716
OS 41.5019871 -38.30910804
OS 41.5112327 -38.30910804
OS 41.51770462 -38.3100326
OE
OB 42.90454462 -39.1375138 I
OS 42.38401734 -39.1375138
OS 42.38401734 -39.08111564
OS 42.90454462 -39.08111564
OS 42.90454462 -39.1375138
OE
OB 42.12514054 -38.32112732 I
OS 42.13253702 -38.32112732
OS 42.1491791 -38.32297644
OS 42.1676703 -38.32482556
OS 42.18708606 -38.3285238
OS 42.20650182 -38.3331466
OS 42.22406846 -38.33961852
OS 42.22499302 -38.33961852
OS 42.22591758 -38.34054308
OS 42.23146494 -38.34331676
OS 42.23978598 -38.34793956
OS 42.24903158 -38.35441148
OS 42.2601263 -38.36273252
OS 42.27214558 -38.37290268
OS 42.2832403 -38.38584652
OS 42.29341046 -38.39971492
OS 42.29433502 -38.40156404
OS 42.2971087 -38.4071114
OS 42.3017315 -38.41450788
OS 42.3063543 -38.4256026
OS 42.3109771 -38.43854644
OS 42.3155999 -38.45241484
OS 42.31837358 -38.46813236
OS 42.31929814 -38.48384988
OS 42.31929814 -38.485699
OS 42.31929814 -38.4903218
OS 42.31837358 -38.49864284
OS 42.31652446 -38.508813
OS 42.31375078 -38.52083228
OS 42.30912798 -38.53377612
OS 42.30358062 -38.54671996
OS 42.29618414 -38.56058836
OS 42.29525958 -38.56243748
OS 42.2924859 -38.56613572
OS 42.28693854 -38.5735322
OS 42.27954206 -38.58092868
OS 42.27029646 -38.59017428
OS 42.25920174 -38.60034444
OS 42.24533334 -38.60959004
OS 42.22961582 -38.61883564
OS 42.23054038 -38.61883564
OS 42.2323895 -38.6197602
OS 42.23516318 -38.62068476
OS 42.23886142 -38.62253388
OS 42.24995614 -38.62623212
OS 42.26289998 -38.63270404
OS 42.27676838 -38.64102508
OS 42.2924859 -38.65119524
OS 42.3063543 -38.66321452
OS 42.31929814 -38.67800748
OS 42.3202227 -38.6798566
OS 42.32392094 -38.68540396
OS 42.3294683 -38.693725
OS 42.33501566 -38.70481972
OS 42.34056302 -38.71961268
OS 42.34611038 -38.7353302
OS 42.34980862 -38.7538214
OS 42.35073318 -38.77416172
OS 42.35073318 -38.77508628
OS 42.35073318 -38.77601084
OS 42.35073318 -38.7815582
OS 42.34980862 -38.7908038
OS 42.3479595 -38.80189852
OS 42.34611038 -38.81484236
OS 42.34241214 -38.82871076
OS 42.33778934 -38.84350372
OS 42.33131742 -38.85829668
OS 42.33039286 -38.8601458
OS 42.32761918 -38.8647686
OS 42.32392094 -38.87124052
OS 42.31837358 -38.88048612
OS 42.3109771 -38.88973172
OS 42.30358062 -38.89990188
OS 42.29433502 -38.91007204
OS 42.28416486 -38.91839308
OS 42.2832403 -38.91931764
OS 42.27954206 -38.92209132
OS 42.27307014 -38.92578956
OS 42.2647491 -38.9294878
OS 42.25457894 -38.93503516
OS 42.24255966 -38.94058252
OS 42.22961582 -38.94520532
OS 42.2138983 -38.94982812
OS 42.21204918 -38.94982812
OS 42.20650182 -38.95167724
OS 42.19725622 -38.9526018
OS 42.18523694 -38.95445092
OS 42.17044398 -38.95630004
OS 42.15287734 -38.95814916
OS 42.13346158 -38.95907372
OS 42.11127214 -38.95999828
OS 41.8671883 -38.95999828
OS 41.8671883 -38.32020276
OS 42.11866862 -38.32020276
OS 42.12514054 -38.32112732
OE
OB 40.30745558 -38.48662356 I
OS 40.31762574 -38.48847268
OS 40.32964502 -38.49217092
OS 40.34258886 -38.49679372
OS 40.35738182 -38.50326564
OS 40.37309934 -38.51158668
OS 40.34443798 -38.58370236
OS 40.34351342 -38.5827778
OS 40.33981518 -38.58092868
OS 40.33426782 -38.578155
OS 40.32687134 -38.57538132
OS 40.3185503 -38.57260764
OS 40.30838014 -38.56983396
OS 40.29820998 -38.56798484
OS 40.28803982 -38.56706028
OS 40.28341702 -38.56706028
OS 40.27879422 -38.56798484
OS 40.2723223 -38.5689094
OS 40.26585038 -38.57075852
OS 40.25752934 -38.5735322
OS 40.2492083 -38.57723044
OS 40.24181182 -38.5827778
OS 40.24088726 -38.58370236
OS 40.23811358 -38.58555148
OS 40.2353399 -38.58924972
OS 40.2307171 -38.59387252
OS 40.2260943 -38.60034444
OS 40.2214715 -38.60774092
OS 40.2168487 -38.61606196
OS 40.21315046 -38.62623212
OS 40.2122259 -38.62808124
OS 40.21130134 -38.6336286
OS 40.20945222 -38.64194964
OS 40.20667854 -38.65304436
OS 40.20390486 -38.66691276
OS 40.20205574 -38.68263028
OS 40.20113118 -38.69927236
OS 40.20020662 -38.71776356
OS 40.20020662 -38.95999828
OS 40.12161902 -38.95999828
OS 40.12161902 -38.49586916
OS 40.19281014 -38.49586916
OS 40.19281014 -38.56613572
OS 40.1937347 -38.56521116
OS 40.19743294 -38.55873924
OS 40.20205574 -38.5504182
OS 40.20945222 -38.54024804
OS 40.2168487 -38.53007788
OS 40.22516974 -38.51898316
OS 40.23349078 -38.50973756
OS 40.24181182 -38.50234108
OS 40.24273638 -38.50141652
OS 40.24551006 -38.4995674
OS 40.25105742 -38.49679372
OS 40.25660478 -38.49402004
OS 40.26400126 -38.49124636
OS 40.27324686 -38.48847268
OS 40.28249246 -38.48662356
OS 40.29266262 -38.485699
OS 40.29913454 -38.485699
OS 40.30745558 -38.48662356
OE
OB 39.48829542 -38.95999828 I
OS 39.3986131 -38.95999828
OS 39.3986131 -38.87031596
OS 39.48829542 -38.87031596
OS 39.48829542 -38.95999828
OE
OB 38.6404739 -38.95999828 I
OS 38.55171614 -38.95999828
OS 38.30393406 -38.32020276
OS 38.39639006 -38.32020276
OS 38.56281086 -38.78525644
OS 38.56281086 -38.786181
OS 38.56373542 -38.78803012
OS 38.56465998 -38.7908038
OS 38.5665091 -38.79450204
OS 38.56743366 -38.8000494
OS 38.56928278 -38.80559676
OS 38.57390558 -38.81946516
OS 38.57945294 -38.83518268
OS 38.5850003 -38.85274932
OS 38.59609502 -38.88973172
OS 38.59609502 -38.88880716
OS 38.59701958 -38.88695804
OS 38.59794414 -38.88418436
OS 38.5988687 -38.88048612
OS 38.60164238 -38.87031596
OS 38.60626518 -38.85644756
OS 38.61088798 -38.84073004
OS 38.61643534 -38.8231634
OS 38.62290726 -38.8046722
OS 38.63030374 -38.78525644
OS 38.80412102 -38.32020276
OS 38.8901051 -38.32020276
OS 38.6404739 -38.95999828
OE
OB 39.27564662 -38.42745172 I
OS 39.25438174 -38.54671996
OS 39.20538006 -38.54671996
OS 39.1859643 -38.42745172
OS 39.1859643 -38.32020276
OS 39.27564662 -38.32020276
OS 39.27564662 -38.42745172
OE
OB 40.49791494 -38.4117342 I
OS 40.41932734 -38.4117342
OS 40.41932734 -38.32020276
OS 40.49791494 -38.32020276
OS 40.49791494 -38.4117342
OE
OB 39.84517558 -38.48662356 I
OS 39.8516475 -38.48754812
OS 39.8655159 -38.48939724
OS 39.88215798 -38.49309548
OS 39.89972462 -38.49864284
OS 39.91729126 -38.50696388
OS 39.9348579 -38.51713404
OS 39.93578246 -38.51713404
OS 39.93670702 -38.51898316
OS 39.94225438 -38.5226814
OS 39.95057542 -38.53007788
OS 39.96074558 -38.53932348
OS 39.9718403 -38.55134276
OS 39.98293502 -38.56613572
OS 39.99402974 -38.58370236
OS 40.00327534 -38.60311812
OS 40.00327534 -38.60404268
OS 40.0041999 -38.6058918
OS 40.00512446 -38.60866548
OS 40.00697358 -38.61236372
OS 40.0088227 -38.61791108
OS 40.01067182 -38.624383
OS 40.01529462 -38.63917596
OS 40.01991742 -38.65766716
OS 40.02361566 -38.67800748
OS 40.02638934 -38.70112148
OS 40.0273139 -38.72516004
OS 40.0273139 -38.7260846
OS 40.0273139 -38.72793372
OS 40.0273139 -38.73163196
OS 40.0273139 -38.73717932
OS 40.02638934 -38.74365124
OS 40.02638934 -38.75104772
OS 40.02454022 -38.7676898
OS 40.02084198 -38.78803012
OS 40.01621918 -38.809295
OS 40.00974726 -38.83148444
OS 40.00142622 -38.85367388
OS 40.00142622 -38.85459844
OS 40.00050166 -38.85644756
OS 39.99865254 -38.85922124
OS 39.99680342 -38.86291948
OS 39.9903315 -38.87308964
OS 39.98201046 -38.88603348
OS 39.9718403 -38.89990188
OS 39.95889646 -38.91377028
OS 39.9441035 -38.92763868
OS 39.92653686 -38.94058252
OS 39.9256123 -38.94058252
OS 39.92468774 -38.94150708
OS 39.92191406 -38.9433562
OS 39.91821582 -38.94520532
OS 39.90897022 -38.94982812
OS 39.89602638 -38.95537548
OS 39.88030886 -38.96092284
OS 39.86366678 -38.96554564
OS 39.84425102 -38.96924388
OS 39.82483526 -38.97016844
OS 39.81836334 -38.97016844
OS 39.81096686 -38.96924388
OS 39.80172126 -38.96831932
OS 39.79062654 -38.9664702
OS 39.77860726 -38.96369652
OS 39.76658798 -38.95999828
OS 39.7545687 -38.95445092
OS 39.75364414 -38.95352636
OS 39.74902134 -38.95167724
OS 39.74347398 -38.947979
OS 39.7360775 -38.94243164
OS 39.72868102 -38.93688428
OS 39.71943542 -38.9294878
OS 39.71111438 -38.92116676
OS 39.7037179 -38.91192116
OS 39.7037179 -39.1375138
OS 39.6251303 -39.1375138
OS 39.6251303 -38.49586916
OS 39.69632142 -38.49586916
OS 39.69632142 -38.55689012
OS 39.69724598 -38.555041
OS 39.70094422 -38.55134276
OS 39.70556702 -38.54487084
OS 39.7129635 -38.53747436
OS 39.72128454 -38.52822876
OS 39.73053014 -38.51990772
OS 39.74162486 -38.51158668
OS 39.75271958 -38.5041902
OS 39.7545687 -38.50326564
OS 39.75826694 -38.50141652
OS 39.76566342 -38.49864284
OS 39.77490902 -38.4949446
OS 39.78600374 -38.49124636
OS 39.79894758 -38.48847268
OS 39.81374054 -38.48662356
OS 39.83038262 -38.485699
OS 39.84055278 -38.485699
OS 39.84517558 -38.48662356
OE
OB 44.92193454 -38.40988508 I
OS 44.84334694 -38.40988508
OS 44.84334694 -38.32020276
OS 44.92193454 -38.32020276
OS 44.92193454 -38.40988508
OE
OB 45.24553054 -38.48662356 I
OS 45.25385158 -38.48754812
OS 45.26309718 -38.48939724
OS 45.27326734 -38.49124636
OS 45.28528662 -38.49309548
OS 45.31024974 -38.50141652
OS 45.32319358 -38.50603932
OS 45.33613742 -38.51251124
OS 45.34908126 -38.51898316
OS 45.3620251 -38.52822876
OS 45.37404438 -38.53747436
OS 45.38606366 -38.54856908
OS 45.38698822 -38.54949364
OS 45.38883734 -38.55134276
OS 45.39161102 -38.555041
OS 45.39530926 -38.5596638
OS 45.39993206 -38.56613572
OS 45.40547942 -38.57445676
OS 45.41102678 -38.58370236
OS 45.41657414 -38.59387252
OS 45.4221215 -38.60496724
OS 45.42766886 -38.61883564
OS 45.43321622 -38.63270404
OS 45.43783902 -38.64842156
OS 45.44153726 -38.66506364
OS 45.44431094 -38.68263028
OS 45.44616006 -38.70112148
OS 45.44708462 -38.7214618
OS 45.44708462 -38.72238636
OS 45.44708462 -38.72516004
OS 45.44708462 -38.72978284
OS 45.44708462 -38.73625476
OS 45.44616006 -38.74365124
OS 45.4452355 -38.75289684
OS 45.4452355 -38.76214244
OS 45.44338638 -38.7723126
OS 45.4406127 -38.7954266
OS 45.43506534 -38.8185406
OS 45.42859342 -38.8416546
OS 45.41934782 -38.86291948
OS 45.41934782 -38.86384404
OS 45.41842326 -38.8647686
OS 45.41657414 -38.86754228
OS 45.41472502 -38.87124052
OS 45.4082531 -38.88048612
OS 45.39993206 -38.89158084
OS 45.38883734 -38.90452468
OS 45.37496894 -38.91746852
OS 45.35925142 -38.93041236
OS 45.34076022 -38.94243164
OS 45.33983566 -38.94243164
OS 45.3389111 -38.9433562
OS 45.33613742 -38.94520532
OS 45.33151462 -38.94705444
OS 45.32689182 -38.94890356
OS 45.32134446 -38.95075268
OS 45.30747606 -38.95630004
OS 45.29175854 -38.96092284
OS 45.27234278 -38.96554564
OS 45.25200246 -38.96924388
OS 45.22981302 -38.97016844
OS 45.22056742 -38.97016844
OS 45.21317094 -38.96924388
OS 45.2048499 -38.96831932
OS 45.1956043 -38.9664702
OS 45.18450958 -38.96462108
OS 45.17341486 -38.96277196
OS 45.14845174 -38.95537548
OS 45.13458334 -38.94982812
OS 45.1216395 -38.94428076
OS 45.10869566 -38.93688428
OS 45.09575182 -38.92856324
OS 45.08373254 -38.91931764
OS 45.07171326 -38.90822292
OS 45.0707887 -38.90729836
OS 45.06893958 -38.90544924
OS 45.0661659 -38.901751
OS 45.06246766 -38.89620364
OS 45.05784486 -38.88973172
OS 45.05322206 -38.88233524
OS 45.0476747 -38.87308964
OS 45.04212734 -38.86199492
OS 45.03657998 -38.84997564
OS 45.03103262 -38.83610724
OS 45.02640982 -38.82131428
OS 45.02178702 -38.80559676
OS 45.01808878 -38.78803012
OS 45.0153151 -38.76953892
OS 45.01346598 -38.7491986
OS 45.01254142 -38.72793372
OS 45.01254142 -38.7260846
OS 45.01254142 -38.72238636
OS 45.01346598 -38.71591444
OS 45.01346598 -38.70666884
OS 45.01439054 -38.69649868
OS 45.01623966 -38.68355484
OS 45.01808878 -38.670611
OS 45.02178702 -38.65581804
OS 45.02548526 -38.64102508
OS 45.03010806 -38.62530756
OS 45.03565542 -38.60866548
OS 45.0430519 -38.59294796
OS 45.05044838 -38.578155
OS 45.06061854 -38.56336204
OS 45.0707887 -38.54949364
OS 45.08373254 -38.53747436
OS 45.0846571 -38.5365498
OS 45.08650622 -38.53562524
OS 45.09020446 -38.53285156
OS 45.09482726 -38.52915332
OS 45.10037462 -38.52545508
OS 45.1077711 -38.52083228
OS 45.11516758 -38.51620948
OS 45.12441318 -38.51158668
OS 45.13458334 -38.50696388
OS 45.14567806 -38.50234108
OS 45.17064118 -38.49402004
OS 45.19930254 -38.48754812
OS 45.2140955 -38.48662356
OS 45.22981302 -38.485699
OS 45.23905862 -38.485699
OS 45.24553054 -38.48662356
OE
OB 44.92193454 -38.95999828 I
OS 44.84334694 -38.95999828
OS 44.84334694 -38.49586916
OS 44.92193454 -38.49586916
OS 44.92193454 -38.95999828
OE
OB 46.10722046 -38.42745172 I
OS 46.08595558 -38.54671996
OS 46.0369539 -38.54671996
OS 46.01753814 -38.42745172
OS 46.01753814 -38.32020276
OS 46.10722046 -38.32020276
OS 46.10722046 -38.42745172
OE
OB 45.77160518 -38.48662356 I
OS 45.78177534 -38.48754812
OS 45.79379462 -38.48939724
OS 45.80673846 -38.49217092
OS 45.82060686 -38.49586916
OS 45.8335507 -38.50141652
OS 45.83539982 -38.50234108
OS 45.83909806 -38.5041902
OS 45.84556998 -38.50696388
OS 45.85296646 -38.51158668
OS 45.86221206 -38.51713404
OS 45.8705331 -38.52453052
OS 45.87885414 -38.531927
OS 45.88625062 -38.5411726
OS 45.88717518 -38.54209716
OS 45.8890243 -38.5457954
OS 45.89179798 -38.5504182
OS 45.89642078 -38.55689012
OS 45.90011902 -38.56613572
OS 45.90381726 -38.57538132
OS 45.90844006 -38.58647604
OS 45.91121374 -38.59849532
OS 45.91121374 -38.59941988
OS 45.9121383 -38.60311812
OS 45.91306286 -38.60866548
OS 45.91398742 -38.61606196
OS 45.91398742 -38.62715668
OS 45.91491198 -38.64010052
OS 45.91583654 -38.65581804
OS 45.91583654 -38.6752338
OS 45.91583654 -38.95999828
OS 45.83724894 -38.95999828
OS 45.83724894 -38.67893204
OS 45.83724894 -38.67800748
OS 45.83724894 -38.67708292
OS 45.83724894 -38.670611
OS 45.83724894 -38.66228996
OS 45.83632438 -38.6521198
OS 45.83539982 -38.64010052
OS 45.8335507 -38.62808124
OS 45.83077702 -38.61698652
OS 45.82800334 -38.60681636
OS 45.82800334 -38.6058918
OS 45.82615422 -38.60311812
OS 45.82338054 -38.59849532
OS 45.82060686 -38.59294796
OS 45.81598406 -38.5874006
OS 45.8104367 -38.58092868
OS 45.80304022 -38.57445676
OS 45.79471918 -38.5689094
OS 45.79379462 -38.56798484
OS 45.79102094 -38.56613572
OS 45.78547358 -38.5642866
OS 45.77900166 -38.56151292
OS 45.77160518 -38.55873924
OS 45.76235958 -38.55596556
OS 45.75126486 -38.555041
OS 45.74017014 -38.55411644
OS 45.73554734 -38.55411644
OS 45.7318491 -38.555041
OS 45.7226035 -38.55596556
OS 45.71058422 -38.55781468
OS 45.69764038 -38.56243748
OS 45.68284742 -38.56798484
OS 45.66805446 -38.57538132
OS 45.65418606 -38.58647604
OS 45.65233694 -38.58832516
OS 45.6486387 -38.59294796
OS 45.64586502 -38.5966462
OS 45.64309134 -38.601269
OS 45.6393931 -38.60681636
OS 45.63661942 -38.61328828
OS 45.63292118 -38.62068476
OS 45.62922294 -38.62993036
OS 45.62644926 -38.64010052
OS 45.62367558 -38.65119524
OS 45.62182646 -38.66321452
OS 45.61997734 -38.67615836
OS 45.61812822 -38.69187588
OS 45.61812822 -38.7075934
OS 45.61812822 -38.95999828
OS 45.53954062 -38.95999828
OS 45.53954062 -38.49586916
OS 45.60980718 -38.49586916
OS 45.60980718 -38.56243748
OS 45.61073174 -38.56151292
OS 45.61258086 -38.55873924
OS 45.61535454 -38.555041
OS 45.61905278 -38.5504182
OS 45.62460014 -38.54487084
OS 45.63107206 -38.53839892
OS 45.63846854 -38.53100244
OS 45.64771414 -38.52360596
OS 45.65695974 -38.51713404
OS 45.66805446 -38.50973756
OS 45.68007374 -38.50326564
OS 45.69301758 -38.49771828
OS 45.70781054 -38.49309548
OS 45.7226035 -38.48939724
OS 45.73924558 -38.48662356
OS 45.75681222 -38.485699
OS 45.7642087 -38.485699
OS 45.77160518 -38.48662356
OE
OB 44.2756671 -38.95999828 I
OS 44.1970795 -38.95999828
OS 44.1970795 -38.49586916
OS 44.2756671 -38.49586916
OS 44.2756671 -38.95999828
OE
OB 43.4574315 -38.48662356 I
OS 43.46482798 -38.48754812
OS 43.47407358 -38.48939724
OS 43.48424374 -38.49124636
OS 43.49626302 -38.49402004
OS 43.50735774 -38.49679372
OS 43.52030158 -38.50141652
OS 43.53232086 -38.50603932
OS 43.5452647 -38.51251124
OS 43.55820854 -38.51990772
OS 43.57115238 -38.52822876
OS 43.58317166 -38.53839892
OS 43.59426638 -38.54949364
OS 43.59519094 -38.5504182
OS 43.59704006 -38.55226732
OS 43.59981374 -38.55596556
OS 43.60351198 -38.56151292
OS 43.60813478 -38.56798484
OS 43.61275758 -38.57538132
OS 43.61830494 -38.58462692
OS 43.6238523 -38.59572164
OS 43.62939966 -38.60774092
OS 43.63494702 -38.62068476
OS 43.63956982 -38.63547772
OS 43.64419262 -38.65119524
OS 43.64789086 -38.66876188
OS 43.65066454 -38.68725308
OS 43.65251366 -38.70666884
OS 43.65343822 -38.72793372
OS 43.65343822 -38.72885828
OS 43.65343822 -38.73255652
OS 43.65343822 -38.73902844
OS 43.65251366 -38.74827404
OS 43.30580366 -38.74827404
OS 43.30580366 -38.7491986
OS 43.30580366 -38.75197228
OS 43.30672822 -38.75567052
OS 43.30672822 -38.76121788
OS 43.30765278 -38.7676898
OS 43.3095019 -38.77508628
OS 43.31227558 -38.79172836
OS 43.31782294 -38.81021956
OS 43.32521942 -38.83055988
OS 43.33538958 -38.84905108
OS 43.34833342 -38.86569316
OS 43.34925798 -38.86569316
OS 43.35018254 -38.86754228
OS 43.3557299 -38.87216508
OS 43.36405094 -38.878637
OS 43.37514566 -38.88510892
OS 43.38993862 -38.8925054
OS 43.4065807 -38.89897732
OS 43.4250719 -38.90360012
OS 43.43524206 -38.90452468
OS 43.44633678 -38.90544924
OS 43.45373326 -38.90544924
OS 43.4620543 -38.90452468
OS 43.47222446 -38.90267556
OS 43.48331918 -38.89990188
OS 43.49626302 -38.89620364
OS 43.5082823 -38.89065628
OS 43.52030158 -38.8832598
OS 43.52122614 -38.88233524
OS 43.52584894 -38.878637
OS 43.5313963 -38.87308964
OS 43.53786822 -38.86569316
OS 43.5452647 -38.855523
OS 43.55358574 -38.84257916
OS 43.56190678 -38.8277862
OS 43.56930326 -38.81021956
OS 43.65066454 -38.82038972
OS 43.65066454 -38.82131428
OS 43.64973998 -38.8231634
OS 43.64881542 -38.82686164
OS 43.6469663 -38.832409
OS 43.64419262 -38.83795636
OS 43.64141894 -38.84535284
OS 43.63402246 -38.86107036
OS 43.62477686 -38.878637
OS 43.61183302 -38.8971282
OS 43.59704006 -38.91469484
OS 43.57854886 -38.93133692
OS 43.5776243 -38.93133692
OS 43.57577518 -38.93318604
OS 43.5730015 -38.93503516
OS 43.56930326 -38.93780884
OS 43.5637559 -38.94058252
OS 43.55820854 -38.9433562
OS 43.55081206 -38.94705444
OS 43.54249102 -38.95075268
OS 43.53324542 -38.95445092
OS 43.52399982 -38.95814916
OS 43.50088582 -38.96369652
OS 43.47499814 -38.96831932
OS 43.44633678 -38.97016844
OS 43.43616662 -38.97016844
OS 43.4296947 -38.96924388
OS 43.42137366 -38.96831932
OS 43.4112035 -38.9664702
OS 43.40010878 -38.96462108
OS 43.3880895 -38.96277196
OS 43.36220182 -38.95537548
OS 43.34833342 -38.94982812
OS 43.33538958 -38.94428076
OS 43.32152118 -38.93688428
OS 43.30857734 -38.92856324
OS 43.29655806 -38.91931764
OS 43.28453878 -38.90822292
OS 43.28361422 -38.90729836
OS 43.2817651 -38.90544924
OS 43.27899142 -38.901751
OS 43.27529318 -38.89620364
OS 43.27067038 -38.88973172
OS 43.26604758 -38.88233524
OS 43.26050022 -38.87308964
OS 43.25495286 -38.86291948
OS 43.2494055 -38.8509002
OS 43.24385814 -38.83795636
OS 43.23923534 -38.8231634
OS 43.23461254 -38.80744588
OS 43.2309143 -38.7908038
OS 43.22814062 -38.7723126
OS 43.2262915 -38.75289684
OS 43.22536694 -38.73255652
OS 43.22536694 -38.73163196
OS 43.22536694 -38.72700916
OS 43.22536694 -38.7214618
OS 43.2262915 -38.71314076
OS 43.22721606 -38.7029706
OS 43.22814062 -38.69187588
OS 43.22998974 -38.67893204
OS 43.23276342 -38.6659882
OS 43.2401599 -38.63640228
OS 43.2447827 -38.62160932
OS 43.25033006 -38.6058918
OS 43.25772654 -38.59109884
OS 43.26604758 -38.57723044
OS 43.27529318 -38.56336204
OS 43.28546334 -38.5504182
OS 43.2863879 -38.54949364
OS 43.28823702 -38.54764452
OS 43.29193526 -38.54487084
OS 43.29655806 -38.54024804
OS 43.30210542 -38.53562524
OS 43.3095019 -38.53007788
OS 43.31782294 -38.52360596
OS 43.3279931 -38.5180586
OS 43.33816326 -38.51158668
OS 43.35018254 -38.50603932
OS 43.36312638 -38.50049196
OS 43.37699478 -38.49586916
OS 43.39178774 -38.49124636
OS 43.40750526 -38.48847268
OS 43.42414734 -38.48662356
OS 43.44171398 -38.485699
OS 43.45095958 -38.485699
OS 43.4574315 -38.48662356
OE
OB 43.13938286 -38.48662356 I
OS 43.14955302 -38.48847268
OS 43.1615723 -38.49217092
OS 43.17451614 -38.49679372
OS 43.1893091 -38.50326564
OS 43.20502662 -38.51158668
OS 43.17636526 -38.58370236
OS 43.1754407 -38.5827778
OS 43.17174246 -38.58092868
OS 43.1661951 -38.578155
OS 43.15879862 -38.57538132
OS 43.15047758 -38.57260764
OS 43.14030742 -38.56983396
OS 43.13013726 -38.56798484
OS 43.1199671 -38.56706028
OS 43.1153443 -38.56706028
OS 43.1107215 -38.56798484
OS 43.10424958 -38.5689094
OS 43.09777766 -38.57075852
OS 43.08945662 -38.5735322
OS 43.08113558 -38.57723044
OS 43.0737391 -38.5827778
OS 43.07281454 -38.58370236
OS 43.07004086 -38.58555148
OS 43.06726718 -38.58924972
OS 43.06264438 -38.59387252
OS 43.05802158 -38.60034444
OS 43.05339878 -38.60774092
OS 43.04877598 -38.61606196
OS 43.04507774 -38.62623212
OS 43.04415318 -38.62808124
OS 43.04322862 -38.6336286
OS 43.0413795 -38.64194964
OS 43.03860582 -38.65304436
OS 43.03583214 -38.66691276
OS 43.03398302 -38.68263028
OS 43.03305846 -38.69927236
OS 43.0321339 -38.71776356
OS 43.0321339 -38.95999828
OS 42.9535463 -38.95999828
OS 42.9535463 -38.49586916
OS 43.02473742 -38.49586916
OS 43.02473742 -38.56613572
OS 43.02566198 -38.56521116
OS 43.02936022 -38.55873924
OS 43.03398302 -38.5504182
OS 43.0413795 -38.54024804
OS 43.04877598 -38.53007788
OS 43.05709702 -38.51898316
OS 43.06541806 -38.50973756
OS 43.0737391 -38.50234108
OS 43.07466366 -38.50141652
OS 43.07743734 -38.4995674
OS 43.0829847 -38.49679372
OS 43.08853206 -38.49402004
OS 43.09592854 -38.49124636
OS 43.10517414 -38.48847268
OS 43.11441974 -38.48662356
OS 43.1245899 -38.485699
OS 43.13106182 -38.485699
OS 43.13938286 -38.48662356
OE
OB 43.95022198 -38.95999828 I
OS 43.87533262 -38.95999828
OS 43.70059078 -38.49586916
OS 43.78380118 -38.49586916
OS 43.88365366 -38.77416172
OS 43.88365366 -38.77508628
OS 43.88457822 -38.77601084
OS 43.88550278 -38.77878452
OS 43.88642734 -38.7815582
OS 43.88920102 -38.7908038
OS 43.89289926 -38.80282308
OS 43.89752206 -38.81669148
OS 43.90306942 -38.832409
OS 43.90769222 -38.84997564
OS 43.91323958 -38.86754228
OS 43.91416414 -38.86569316
OS 43.9150887 -38.86107036
OS 43.91786238 -38.85367388
OS 43.92063606 -38.84257916
OS 43.92525886 -38.83055988
OS 43.92988166 -38.81484236
OS 43.93635358 -38.79820028
OS 43.9428255 -38.77970908
OS 44.04545166 -38.49586916
OS 44.12681294 -38.49586916
OS 43.95022198 -38.95999828
OE
OB 44.2756671 -38.40988508 I
OS 44.1970795 -38.40988508
OS 44.1970795 -38.32020276
OS 44.2756671 -38.32020276
OS 44.2756671 -38.40988508
OE
OB 44.5669035 -38.48662356 I
OS 44.5807719 -38.48754812
OS 44.59556486 -38.48939724
OS 44.61128238 -38.49309548
OS 44.62792446 -38.49679372
OS 44.64364198 -38.50234108
OS 44.64456654 -38.50234108
OS 44.6454911 -38.50326564
OS 44.6501139 -38.50511476
OS 44.65751038 -38.508813
OS 44.66675598 -38.5134358
OS 44.67692614 -38.51990772
OS 44.6870963 -38.5273042
OS 44.6963419 -38.53562524
OS 44.70466294 -38.54487084
OS 44.7055875 -38.5457954
OS 44.70743662 -38.54949364
OS 44.71113486 -38.55596556
OS 44.71575766 -38.56336204
OS 44.72038046 -38.57445676
OS 44.72500326 -38.58647604
OS 44.7287015 -38.60034444
OS 44.73239974 -38.61606196
OS 44.65566126 -38.62623212
OS 44.65566126 -38.624383
OS 44.6547367 -38.62068476
OS 44.65288758 -38.61421284
OS 44.6501139 -38.6058918
OS 44.6454911 -38.59757076
OS 44.63994374 -38.58832516
OS 44.63347182 -38.57907956
OS 44.62422622 -38.57075852
OS 44.62330166 -38.56983396
OS 44.61960342 -38.56798484
OS 44.61405606 -38.5642866
OS 44.60573502 -38.56058836
OS 44.59648942 -38.55689012
OS 44.58447014 -38.55319188
OS 44.56967718 -38.55134276
OS 44.55395966 -38.5504182
OS 44.54471406 -38.5504182
OS 44.53546846 -38.55134276
OS 44.52344918 -38.55226732
OS 44.5114299 -38.555041
OS 44.49848606 -38.55781468
OS 44.48646678 -38.56243748
OS 44.47629662 -38.5689094
OS 44.47537206 -38.56983396
OS 44.47259838 -38.57168308
OS 44.46890014 -38.57538132
OS 44.4652019 -38.58092868
OS 44.4605791 -38.58647604
OS 44.45688086 -38.59387252
OS 44.45410718 -38.60219356
OS 44.45318262 -38.6105146
OS 44.45318262 -38.61143916
OS 44.45318262 -38.61328828
OS 44.45410718 -38.61606196
OS 44.45410718 -38.6197602
OS 44.45688086 -38.6290058
OS 44.46242822 -38.6382514
OS 44.46335278 -38.63917596
OS 44.46427734 -38.64010052
OS 44.46612646 -38.6428742
OS 44.4698247 -38.64564788
OS 44.47352294 -38.64842156
OS 44.4790703 -38.6521198
OS 44.48554222 -38.65489348
OS 44.4929387 -38.65859172
OS 44.49386326 -38.65859172
OS 44.49571238 -38.65951628
OS 44.49941062 -38.66044084
OS 44.50588254 -38.66321452
OS 44.51512814 -38.6659882
OS 44.52714742 -38.66876188
OS 44.5345439 -38.67153556
OS 44.54286494 -38.67338468
OS 44.55211054 -38.67615836
OS 44.5622807 -38.67893204
OS 44.56320526 -38.67893204
OS 44.56597894 -38.6798566
OS 44.57060174 -38.68078116
OS 44.5761491 -38.68263028
OS 44.58262102 -38.6844794
OS 44.59094206 -38.68632852
OS 44.6085087 -38.69187588
OS 44.62792446 -38.69742324
OS 44.64734022 -38.70389516
OS 44.66490686 -38.71036708
OS 44.67230334 -38.71314076
OS 44.67877526 -38.71591444
OS 44.68062438 -38.716839
OS 44.68432262 -38.71868812
OS 44.68986998 -38.7214618
OS 44.69819102 -38.7260846
OS 44.70651206 -38.73163196
OS 44.7148331 -38.73902844
OS 44.72315414 -38.74734948
OS 44.73055062 -38.75659508
OS 44.73147518 -38.75751964
OS 44.7333243 -38.76121788
OS 44.73702254 -38.76676524
OS 44.74072078 -38.77508628
OS 44.74349446 -38.78525644
OS 44.7471927 -38.79635116
OS 44.74904182 -38.809295
OS 44.74996638 -38.82408796
OS 44.74996638 -38.82593708
OS 44.74996638 -38.83055988
OS 44.74904182 -38.83795636
OS 44.7471927 -38.84812652
OS 44.74441902 -38.85922124
OS 44.73979622 -38.87124052
OS 44.73424886 -38.88510892
OS 44.72685238 -38.89805276
OS 44.72592782 -38.89990188
OS 44.72222958 -38.90360012
OS 44.71760678 -38.91007204
OS 44.7102103 -38.91746852
OS 44.70004014 -38.92578956
OS 44.68894542 -38.93503516
OS 44.67600158 -38.9433562
OS 44.66028406 -38.95167724
OS 44.6593595 -38.95167724
OS 44.65843494 -38.9526018
OS 44.65288758 -38.95445092
OS 44.64364198 -38.9572246
OS 44.6316227 -38.96092284
OS 44.61682974 -38.96462108
OS 44.60018766 -38.96739476
OS 44.58262102 -38.96924388
OS 44.5622807 -38.97016844
OS 44.55395966 -38.97016844
OS 44.54748774 -38.96924388
OS 44.54009126 -38.96924388
OS 44.53084566 -38.96831932
OS 44.52160006 -38.96739476
OS 44.5114299 -38.96554564
OS 44.48924046 -38.96092284
OS 44.46612646 -38.95445092
OS 44.44393702 -38.94520532
OS 44.43376686 -38.93965796
OS 44.42452126 -38.93318604
OS 44.4235967 -38.93226148
OS 44.42267214 -38.93133692
OS 44.41712478 -38.92578956
OS 44.40880374 -38.91746852
OS 44.39955814 -38.90452468
OS 44.38938798 -38.88880716
OS 44.37921782 -38.87031596
OS 44.37089678 -38.84720196
OS 44.36442486 -38.82131428
OS 44.4420879 -38.809295
OS 44.4420879 -38.81021956
OS 44.4420879 -38.81114412
OS 44.44393702 -38.81669148
OS 44.44578614 -38.82593708
OS 44.44948438 -38.83610724
OS 44.45410718 -38.84720196
OS 44.45965454 -38.85922124
OS 44.46797558 -38.87124052
OS 44.47814574 -38.88141068
OS 44.47999486 -38.88233524
OS 44.4836931 -38.88510892
OS 44.49108958 -38.88880716
OS 44.50033518 -38.89342996
OS 44.51235446 -38.89805276
OS 44.52622286 -38.901751
OS 44.54286494 -38.90452468
OS 44.5622807 -38.90544924
OS 44.5715263 -38.90544924
OS 44.5807719 -38.90452468
OS 44.59279118 -38.90267556
OS 44.60573502 -38.89990188
OS 44.61960342 -38.89620364
OS 44.6316227 -38.89158084
OS 44.64271742 -38.88418436
OS 44.64364198 -38.8832598
OS 44.64734022 -38.88048612
OS 44.65103846 -38.87586332
OS 44.65658582 -38.8693914
OS 44.66120862 -38.86199492
OS 44.66583142 -38.85274932
OS 44.6686051 -38.84350372
OS 44.66952966 -38.832409
OS 44.66952966 -38.83148444
OS 44.66952966 -38.8277862
OS 44.6686051 -38.8231634
OS 44.66675598 -38.81669148
OS 44.6639823 -38.81021956
OS 44.6593595 -38.80374764
OS 44.65381214 -38.79635116
OS 44.6454911 -38.7908038
OS 44.64456654 -38.78987924
OS 44.64179286 -38.78895468
OS 44.63717006 -38.786181
OS 44.62977358 -38.78340732
OS 44.61867886 -38.77970908
OS 44.61220694 -38.7769354
OS 44.60481046 -38.77508628
OS 44.59648942 -38.7723126
OS 44.58724382 -38.76953892
OS 44.57707366 -38.76676524
OS 44.56505438 -38.76399156
OS 44.56412982 -38.76399156
OS 44.56135614 -38.763067
OS 44.55673334 -38.76214244
OS 44.55118598 -38.76029332
OS 44.5437895 -38.7584442
OS 44.53546846 -38.75567052
OS 44.51790182 -38.75104772
OS 44.4975615 -38.7445758
OS 44.47814574 -38.73902844
OS 44.45965454 -38.73255652
OS 44.4513335 -38.72885828
OS 44.44486158 -38.7260846
OS 44.44301246 -38.72516004
OS 44.43931422 -38.72331092
OS 44.43376686 -38.71961268
OS 44.42637038 -38.71498988
OS 44.41804934 -38.70851796
OS 44.4097283 -38.70112148
OS 44.40140726 -38.69280044
OS 44.39401078 -38.68263028
OS 44.39308622 -38.68170572
OS 44.3912371 -38.67800748
OS 44.38846342 -38.67153556
OS 44.38568974 -38.66413908
OS 44.38291606 -38.65489348
OS 44.38014238 -38.64379876
OS 44.37829326 -38.63270404
OS 44.3773687 -38.6197602
OS 44.3773687 -38.61791108
OS 44.3773687 -38.61421284
OS 44.37829326 -38.60866548
OS 44.37921782 -38.60034444
OS 44.38106694 -38.5920234
OS 44.38291606 -38.58185324
OS 44.3866143 -38.57260764
OS 44.3912371 -38.56243748
OS 44.39216166 -38.56151292
OS 44.39401078 -38.55781468
OS 44.39678446 -38.55319188
OS 44.40140726 -38.54671996
OS 44.40695462 -38.54024804
OS 44.41342654 -38.531927
OS 44.42082302 -38.52453052
OS 44.43006862 -38.5180586
OS 44.43099318 -38.51713404
OS 44.43376686 -38.51620948
OS 44.4374651 -38.5134358
OS 44.44301246 -38.51066212
OS 44.45040894 -38.50696388
OS 44.45872998 -38.50326564
OS 44.46890014 -38.4995674
OS 44.47999486 -38.49586916
OS 44.48184398 -38.4949446
OS 44.48554222 -38.49402004
OS 44.49201414 -38.49217092
OS 44.50033518 -38.4903218
OS 44.51050534 -38.48847268
OS 44.52160006 -38.48754812
OS 44.5345439 -38.485699
OS 44.55673334 -38.485699
OS 44.5669035 -38.48662356
OE
OB 33.15968222 -38.32112732 I
OS 33.17539974 -38.32205188
OS 33.19204182 -38.32297644
OS 33.20775934 -38.32482556
OS 33.22162774 -38.32667468
OS 33.22347686 -38.32667468
OS 33.22994878 -38.3285238
OS 33.23826982 -38.33037292
OS 33.24936454 -38.3331466
OS 33.26138382 -38.3377694
OS 33.27432766 -38.34331676
OS 33.28819606 -38.34978868
OS 33.30021534 -38.35718516
OS 33.30206446 -38.35810972
OS 33.3057627 -38.3608834
OS 33.31131006 -38.36643076
OS 33.31870654 -38.37290268
OS 33.32702758 -38.38122372
OS 33.33534862 -38.39231844
OS 33.34459422 -38.40433772
OS 33.3519907 -38.41820612
OS 33.35291526 -38.42005524
OS 33.35476438 -38.42467804
OS 33.35846262 -38.43299908
OS 33.36216086 -38.4440938
OS 33.36493454 -38.45703764
OS 33.36863278 -38.4718306
OS 33.3704819 -38.48847268
OS 33.37140646 -38.50603932
OS 33.37140646 -38.50696388
OS 33.37140646 -38.50973756
OS 33.37140646 -38.5134358
OS 33.3704819 -38.51990772
OS 33.36955734 -38.52637964
OS 33.36863278 -38.53470068
OS 33.36678366 -38.54394628
OS 33.36493454 -38.55411644
OS 33.35846262 -38.57538132
OS 33.35476438 -38.58647604
OS 33.34921702 -38.59849532
OS 33.3427451 -38.6105146
OS 33.33627318 -38.62160932
OS 33.32795214 -38.63270404
OS 33.31870654 -38.64379876
OS 33.31778198 -38.64472332
OS 33.31593286 -38.64657244
OS 33.31315918 -38.64934612
OS 33.30853638 -38.6521198
OS 33.30298902 -38.6567426
OS 33.29559254 -38.6613654
OS 33.28634694 -38.66691276
OS 33.27617678 -38.67153556
OS 33.2641575 -38.67708292
OS 33.2502891 -38.68263028
OS 33.23549614 -38.68725308
OS 33.2179295 -38.69095132
OS 33.1994383 -38.69464956
OS 33.17909798 -38.69742324
OS 33.15598398 -38.69927236
OS 33.13194542 -38.70019692
OS 32.9682983 -38.70019692
OS 32.9682983 -38.95999828
OS 32.88323878 -38.95999828
OS 32.88323878 -38.32020276
OS 33.14581382 -38.32020276
OS 33.15968222 -38.32112732
OE
OB 32.75195126 -38.98403684 I
OS 32.75195126 -38.9849614
OS 32.75195126 -38.98773508
OS 32.75195126 -38.99235788
OS 32.75195126 -38.99790524
OS 32.7510267 -39.00530172
OS 32.7510267 -39.0126982
OS 32.74917758 -39.0311894
OS 32.7464039 -39.05060516
OS 32.74270566 -39.07094548
OS 32.7371583 -39.08851212
OS 32.73346006 -39.09683316
OS 32.72976182 -39.10330508
OS 32.72976182 -39.10422964
OS 32.72883726 -39.1051542
OS 32.72421446 -39.109777
OS 32.71681798 -39.11717348
OS 32.70757238 -39.12549452
OS 32.69462854 -39.13381556
OS 32.67798646 -39.14028748
OS 32.6585707 -39.14583484
OS 32.64747598 -39.1467594
OS 32.6354567 -39.14768396
OS 32.62990934 -39.14768396
OS 32.62436198 -39.1467594
OS 32.61604094 -39.1467594
OS 32.60679534 -39.14583484
OS 32.59662518 -39.14398572
OS 32.57443574 -39.13843836
OS 32.5892287 -39.07187004
OS 32.59015326 -39.07187004
OS 32.59292694 -39.0727946
OS 32.59754974 -39.07371916
OS 32.60217254 -39.07464372
OS 32.61419182 -39.0774174
OS 32.61973918 -39.07834196
OS 32.62898478 -39.07834196
OS 32.63360758 -39.0774174
OS 32.63915494 -39.07649284
OS 32.6447023 -39.07464372
OS 32.65024966 -39.07094548
OS 32.65672158 -39.06724724
OS 32.66134438 -39.06169988
OS 32.66226894 -39.06077532
OS 32.6631935 -39.05800164
OS 32.66504262 -39.05337884
OS 32.6678163 -39.04598236
OS 32.66966542 -39.0358122
OS 32.67058998 -39.02841572
OS 32.67151454 -39.0219438
OS 32.6724391 -39.01362276
OS 32.6724391 -39.0034526
OS 32.67336366 -38.99328244
OS 32.67336366 -38.98218772
OS 32.67336366 -38.49586916
OS 32.75195126 -38.49586916
OS 32.75195126 -38.98403684
OE
OB 33.77174094 -38.3100326 I
OS 33.78006198 -38.31095716
OS 33.79023214 -38.31188172
OS 33.8004023 -38.31280628
OS 33.81242158 -38.31557996
OS 33.8373847 -38.32112732
OS 33.8651215 -38.32944836
OS 33.8789899 -38.33499572
OS 33.89193374 -38.34146764
OS 33.90487758 -38.34978868
OS 33.91782142 -38.35810972
OS 33.91874598 -38.35903428
OS 33.9205951 -38.35995884
OS 33.92429334 -38.36273252
OS 33.92891614 -38.36735532
OS 33.93353894 -38.37197812
OS 33.94001086 -38.37845004
OS 33.94648278 -38.38584652
OS 33.95387926 -38.393243
OS 33.96127574 -38.4024886
OS 33.96867222 -38.41358332
OS 33.97699326 -38.42467804
OS 33.98438974 -38.43669732
OS 33.99086166 -38.45056572
OS 33.99825814 -38.46443412
OS 34.0038055 -38.47922708
OS 34.00935286 -38.49586916
OS 33.92614246 -38.51528492
OS 33.92614246 -38.51436036
OS 33.9252179 -38.51251124
OS 33.92336878 -38.508813
OS 33.92151966 -38.5041902
OS 33.91967054 -38.49864284
OS 33.91689686 -38.49124636
OS 33.90950038 -38.4764534
OS 33.90025478 -38.45981132
OS 33.88916006 -38.44316924
OS 33.87529166 -38.42745172
OS 33.8604987 -38.41358332
OS 33.85864958 -38.4117342
OS 33.85310222 -38.40803596
OS 33.84385662 -38.40341316
OS 33.83183734 -38.39694124
OS 33.81611982 -38.39139388
OS 33.79855318 -38.38584652
OS 33.7772883 -38.38214828
OS 33.7541743 -38.38122372
OS 33.74677782 -38.38122372
OS 33.74215502 -38.38214828
OS 33.7356831 -38.38214828
OS 33.72828662 -38.38307284
OS 33.71071998 -38.38584652
OS 33.69130422 -38.38954476
OS 33.6709639 -38.39601668
OS 33.64969902 -38.40526228
OS 33.63028326 -38.41728156
OS 33.6293587 -38.41728156
OS 33.62843414 -38.41913068
OS 33.62196222 -38.42375348
OS 33.61364118 -38.43114996
OS 33.60347102 -38.44224468
OS 33.59145174 -38.45611308
OS 33.58035702 -38.4718306
OS 33.57018686 -38.49124636
OS 33.56094126 -38.51251124
OS 33.56094126 -38.5134358
OS 33.5600167 -38.51528492
OS 33.55909214 -38.5180586
OS 33.55816758 -38.5226814
OS 33.55631846 -38.52822876
OS 33.55446934 -38.53470068
OS 33.55169566 -38.5504182
OS 33.54799742 -38.5689094
OS 33.54429918 -38.58924972
OS 33.54245006 -38.61143916
OS 33.5415255 -38.63547772
OS 33.5415255 -38.63640228
OS 33.5415255 -38.63917596
OS 33.5415255 -38.64379876
OS 33.5415255 -38.64934612
OS 33.54245006 -38.65581804
OS 33.54245006 -38.66413908
OS 33.54337462 -38.67338468
OS 33.54429918 -38.68355484
OS 33.54707286 -38.70574428
OS 33.55169566 -38.72978284
OS 33.55724302 -38.7538214
OS 33.5646395 -38.77785996
OS 33.5646395 -38.77878452
OS 33.56556406 -38.78063364
OS 33.56741318 -38.78340732
OS 33.5692623 -38.78803012
OS 33.57480966 -38.79912484
OS 33.5831307 -38.81206868
OS 33.59330086 -38.82686164
OS 33.6062447 -38.84257916
OS 33.62103766 -38.85644756
OS 33.6386043 -38.8693914
OS 33.63952886 -38.8693914
OS 33.64137798 -38.87031596
OS 33.64415166 -38.87216508
OS 33.6478499 -38.8740142
OS 33.6524727 -38.87586332
OS 33.65802006 -38.878637
OS 33.6709639 -38.88418436
OS 33.68760598 -38.88973172
OS 33.70609718 -38.89435452
OS 33.7264375 -38.89805276
OS 33.74770238 -38.89897732
OS 33.7541743 -38.89897732
OS 33.75972166 -38.89805276
OS 33.76619358 -38.89805276
OS 33.7726655 -38.8971282
OS 33.78930758 -38.89342996
OS 33.80872334 -38.88880716
OS 33.8281391 -38.88141068
OS 33.84847942 -38.87124052
OS 33.85864958 -38.86569316
OS 33.86789518 -38.85829668
OS 33.86881974 -38.85737212
OS 33.8697443 -38.85644756
OS 33.87251798 -38.85367388
OS 33.87621622 -38.8509002
OS 33.87991446 -38.8462774
OS 33.88453726 -38.84073004
OS 33.89008462 -38.83518268
OS 33.89470742 -38.8277862
OS 33.90025478 -38.81946516
OS 33.9067267 -38.81021956
OS 33.91227406 -38.80097396
OS 33.91782142 -38.78987924
OS 33.92244422 -38.77785996
OS 33.92706702 -38.76491612
OS 33.93168982 -38.75104772
OS 33.93538806 -38.73625476
OS 34.02044758 -38.75751964
OS 34.02044758 -38.7584442
OS 34.01952302 -38.76214244
OS 34.0176739 -38.7676898
OS 34.01490022 -38.77508628
OS 34.01212654 -38.78340732
OS 34.0084283 -38.79357748
OS 34.0038055 -38.8046722
OS 33.99825814 -38.81669148
OS 33.9853143 -38.84257916
OS 33.96867222 -38.86846684
OS 33.95850206 -38.88141068
OS 33.9483319 -38.89435452
OS 33.93723718 -38.90544924
OS 33.92429334 -38.91654396
OS 33.92336878 -38.91746852
OS 33.92151966 -38.91931764
OS 33.91689686 -38.92116676
OS 33.91227406 -38.924865
OS 33.90487758 -38.9294878
OS 33.8974811 -38.9341106
OS 33.88731094 -38.9387334
OS 33.87714078 -38.9433562
OS 33.8651215 -38.94890356
OS 33.85217766 -38.95352636
OS 33.83830926 -38.95814916
OS 33.8235163 -38.96277196
OS 33.80779878 -38.9664702
OS 33.7911567 -38.96831932
OS 33.77359006 -38.97016844
OS 33.75509886 -38.971093
OS 33.7449287 -38.971093
OS 33.73753222 -38.97016844
OS 33.72921118 -38.97016844
OS 33.71904102 -38.96924388
OS 33.7079463 -38.96739476
OS 33.69500246 -38.96554564
OS 33.66819022 -38.96092284
OS 33.64045342 -38.95352636
OS 33.61271662 -38.9433562
OS 33.59977278 -38.93688428
OS 33.58682894 -38.9294878
OS 33.58590438 -38.92856324
OS 33.58405526 -38.92763868
OS 33.58035702 -38.924865
OS 33.57665878 -38.92116676
OS 33.57111142 -38.91746852
OS 33.5646395 -38.91192116
OS 33.55724302 -38.90544924
OS 33.54984654 -38.89805276
OS 33.54245006 -38.88973172
OS 33.53412902 -38.88141068
OS 33.51748694 -38.8601458
OS 33.50176942 -38.83518268
OS 33.48790102 -38.80744588
OS 33.48790102 -38.80652132
OS 33.4860519 -38.80374764
OS 33.48512734 -38.79912484
OS 33.48235366 -38.79357748
OS 33.48050454 -38.786181
OS 33.47773086 -38.7769354
OS 33.47403262 -38.76676524
OS 33.47125894 -38.75567052
OS 33.46848526 -38.74365124
OS 33.46478702 -38.72978284
OS 33.46016422 -38.70112148
OS 33.45646598 -38.66876188
OS 33.45461686 -38.63547772
OS 33.45461686 -38.63455316
OS 33.45461686 -38.63085492
OS 33.45461686 -38.62530756
OS 33.45554142 -38.61883564
OS 33.45554142 -38.60959004
OS 33.45646598 -38.60034444
OS 33.45739054 -38.58832516
OS 33.45923966 -38.57630588
OS 33.46386246 -38.54949364
OS 33.47033438 -38.51990772
OS 33.47957998 -38.4903218
OS 33.49252382 -38.46166044
OS 33.49344838 -38.46073588
OS 33.49437294 -38.4579622
OS 33.49622206 -38.45426396
OS 33.4999203 -38.44964116
OS 33.50361854 -38.44316924
OS 33.50824134 -38.43577276
OS 33.52026062 -38.41913068
OS 33.53597814 -38.40063948
OS 33.55446934 -38.38214828
OS 33.57573422 -38.36365708
OS 33.60069734 -38.34793956
OS 33.6016219 -38.347015
OS 33.60439558 -38.34609044
OS 33.60809382 -38.34424132
OS 33.61271662 -38.34146764
OS 33.6201131 -38.33869396
OS 33.62750958 -38.33592028
OS 33.63675518 -38.33222204
OS 33.64692534 -38.3285238
OS 33.65802006 -38.32482556
OS 33.67003934 -38.32112732
OS 33.69592702 -38.31557996
OS 33.72551294 -38.31095716
OS 33.75602342 -38.30910804
OS 33.76526902 -38.30910804
OS 33.77174094 -38.3100326
OE
OB 35.15858094 -39.1375138 I
OS 34.63805366 -39.1375138
OS 34.63805366 -39.08111564
OS 35.15858094 -39.08111564
OS 35.15858094 -39.1375138
OE
OB 34.37917686 -38.32112732 I
OS 34.38657334 -38.32112732
OS 34.40321542 -38.32297644
OS 34.42170662 -38.32482556
OS 34.44112238 -38.3285238
OS 34.46053814 -38.3331466
OS 34.47810478 -38.33961852
OS 34.47902934 -38.33961852
OS 34.4799539 -38.34054308
OS 34.48550126 -38.34331676
OS 34.4938223 -38.34793956
OS 34.5030679 -38.35441148
OS 34.51416262 -38.36273252
OS 34.5261819 -38.37290268
OS 34.53727662 -38.38584652
OS 34.54744678 -38.39971492
OS 34.54837134 -38.40156404
OS 34.55114502 -38.4071114
OS 34.55576782 -38.41450788
OS 34.56039062 -38.4256026
OS 34.56501342 -38.43854644
OS 34.56963622 -38.45241484
OS 34.5724099 -38.46813236
OS 34.57333446 -38.48384988
OS 34.57333446 -38.485699
OS 34.57333446 -38.4903218
OS 34.5724099 -38.49864284
OS 34.57056078 -38.508813
OS 34.5677871 -38.52083228
OS 34.5631643 -38.53377612
OS 34.55761694 -38.54671996
OS 34.55022046 -38.56058836
OS 34.5492959 -38.56243748
OS 34.54652222 -38.56613572
OS 34.54097486 -38.5735322
OS 34.53357838 -38.58092868
OS 34.52433278 -38.59017428
OS 34.51323806 -38.60034444
OS 34.49936966 -38.60959004
OS 34.48365214 -38.61883564
OS 34.4845767 -38.61883564
OS 34.48642582 -38.6197602
OS 34.4891995 -38.62068476
OS 34.49289774 -38.62253388
OS 34.50399246 -38.62623212
OS 34.5169363 -38.63270404
OS 34.5308047 -38.64102508
OS 34.54652222 -38.65119524
OS 34.56039062 -38.66321452
OS 34.57333446 -38.67800748
OS 34.57425902 -38.6798566
OS 34.57795726 -38.68540396
OS 34.58350462 -38.693725
OS 34.58905198 -38.70481972
OS 34.59459934 -38.71961268
OS 34.6001467 -38.7353302
OS 34.60384494 -38.7538214
OS 34.6047695 -38.77416172
OS 34.6047695 -38.77508628
OS 34.6047695 -38.77601084
OS 34.6047695 -38.7815582
OS 34.60384494 -38.7908038
OS 34.60199582 -38.80189852
OS 34.6001467 -38.81484236
OS 34.59644846 -38.82871076
OS 34.59182566 -38.84350372
OS 34.58535374 -38.85829668
OS 34.58442918 -38.8601458
OS 34.5816555 -38.8647686
OS 34.57795726 -38.87124052
OS 34.5724099 -38.88048612
OS 34.56501342 -38.88973172
OS 34.55761694 -38.89990188
OS 34.54837134 -38.91007204
OS 34.53820118 -38.91839308
OS 34.53727662 -38.91931764
OS 34.53357838 -38.92209132
OS 34.52710646 -38.92578956
OS 34.51878542 -38.9294878
OS 34.50861526 -38.93503516
OS 34.49659598 -38.94058252
OS 34.48365214 -38.94520532
OS 34.46793462 -38.94982812
OS 34.4660855 -38.94982812
OS 34.46053814 -38.95167724
OS 34.45129254 -38.9526018
OS 34.43927326 -38.95445092
OS 34.4244803 -38.95630004
OS 34.40691366 -38.95814916
OS 34.3874979 -38.95907372
OS 34.36530846 -38.95999828
OS 34.12122462 -38.95999828
OS 34.12122462 -38.32020276
OS 34.37270494 -38.32020276
OS 34.37917686 -38.32112732
OE
OB 31.74233174 -38.95999828 I
OS 31.65264942 -38.95999828
OS 31.65264942 -38.87031596
OS 31.74233174 -38.87031596
OS 31.74233174 -38.95999828
OE
OB 31.52968294 -38.42745172 I
OS 31.50841806 -38.54671996
OS 31.45941638 -38.54671996
OS 31.44000062 -38.42745172
OS 31.44000062 -38.32020276
OS 31.52968294 -38.32020276
OS 31.52968294 -38.42745172
OE
OB 32.0992119 -38.48662356 I
OS 32.10568382 -38.48754812
OS 32.11955222 -38.48939724
OS 32.1361943 -38.49309548
OS 32.15376094 -38.49864284
OS 32.17132758 -38.50696388
OS 32.18889422 -38.51713404
OS 32.18981878 -38.51713404
OS 32.19074334 -38.51898316
OS 32.1962907 -38.5226814
OS 32.20461174 -38.53007788
OS 32.2147819 -38.53932348
OS 32.22587662 -38.55134276
OS 32.23697134 -38.56613572
OS 32.24806606 -38.58370236
OS 32.25731166 -38.60311812
OS 32.25731166 -38.60404268
OS 32.25823622 -38.6058918
OS 32.25916078 -38.60866548
OS 32.2610099 -38.61236372
OS 32.26285902 -38.61791108
OS 32.26470814 -38.624383
OS 32.26933094 -38.63917596
OS 32.27395374 -38.65766716
OS 32.27765198 -38.67800748
OS 32.28042566 -38.70112148
OS 32.28135022 -38.72516004
OS 32.28135022 -38.7260846
OS 32.28135022 -38.72793372
OS 32.28135022 -38.73163196
OS 32.28135022 -38.73717932
OS 32.28042566 -38.74365124
OS 32.28042566 -38.75104772
OS 32.27857654 -38.7676898
OS 32.2748783 -38.78803012
OS 32.2702555 -38.809295
OS 32.26378358 -38.83148444
OS 32.25546254 -38.85367388
OS 32.25546254 -38.85459844
OS 32.25453798 -38.85644756
OS 32.25268886 -38.85922124
OS 32.25083974 -38.86291948
OS 32.24436782 -38.87308964
OS 32.23604678 -38.88603348
OS 32.22587662 -38.89990188
OS 32.21293278 -38.91377028
OS 32.19813982 -38.92763868
OS 32.18057318 -38.94058252
OS 32.17964862 -38.94058252
OS 32.17872406 -38.94150708
OS 32.17595038 -38.9433562
OS 32.17225214 -38.94520532
OS 32.16300654 -38.94982812
OS 32.1500627 -38.95537548
OS 32.13434518 -38.96092284
OS 32.1177031 -38.96554564
OS 32.09828734 -38.96924388
OS 32.07887158 -38.97016844
OS 32.07239966 -38.97016844
OS 32.06500318 -38.96924388
OS 32.05575758 -38.96831932
OS 32.04466286 -38.9664702
OS 32.03264358 -38.96369652
OS 32.0206243 -38.95999828
OS 32.00860502 -38.95445092
OS 32.00768046 -38.95352636
OS 32.00305766 -38.95167724
OS 31.9975103 -38.947979
OS 31.99011382 -38.94243164
OS 31.98271734 -38.93688428
OS 31.97347174 -38.9294878
OS 31.9651507 -38.92116676
OS 31.95775422 -38.91192116
OS 31.95775422 -39.1375138
OS 31.87916662 -39.1375138
OS 31.87916662 -38.49586916
OS 31.95035774 -38.49586916
OS 31.95035774 -38.55689012
OS 31.9512823 -38.555041
OS 31.95498054 -38.55134276
OS 31.95960334 -38.54487084
OS 31.96699982 -38.53747436
OS 31.97532086 -38.52822876
OS 31.98456646 -38.51990772
OS 31.99566118 -38.51158668
OS 32.0067559 -38.5041902
OS 32.00860502 -38.50326564
OS 32.01230326 -38.50141652
OS 32.01969974 -38.49864284
OS 32.02894534 -38.4949446
OS 32.04004006 -38.49124636
OS 32.0529839 -38.48847268
OS 32.06777686 -38.48662356
OS 32.08441894 -38.485699
OS 32.0945891 -38.485699
OS 32.0992119 -38.48662356
OE
OB 32.5614919 -38.48662356 I
OS 32.57166206 -38.48847268
OS 32.58368134 -38.49217092
OS 32.59662518 -38.49679372
OS 32.61141814 -38.50326564
OS 32.62713566 -38.51158668
OS 32.5984743 -38.58370236
OS 32.59754974 -38.5827778
OS 32.5938515 -38.58092868
OS 32.58830414 -38.578155
OS 32.58090766 -38.57538132
OS 32.57258662 -38.57260764
OS 32.56241646 -38.56983396
OS 32.5522463 -38.56798484
OS 32.54207614 -38.56706028
OS 32.53745334 -38.56706028
OS 32.53283054 -38.56798484
OS 32.52635862 -38.5689094
OS 32.5198867 -38.57075852
OS 32.51156566 -38.5735322
OS 32.50324462 -38.57723044
OS 32.49584814 -38.5827778
OS 32.49492358 -38.58370236
OS 32.4921499 -38.58555148
OS 32.48937622 -38.58924972
OS 32.48475342 -38.59387252
OS 32.48013062 -38.60034444
OS 32.47550782 -38.60774092
OS 32.47088502 -38.61606196
OS 32.46718678 -38.62623212
OS 32.46626222 -38.62808124
OS 32.46533766 -38.6336286
OS 32.46348854 -38.64194964
OS 32.46071486 -38.65304436
OS 32.45794118 -38.66691276
OS 32.45609206 -38.68263028
OS 32.4551675 -38.69927236
OS 32.45424294 -38.71776356
OS 32.45424294 -38.95999828
OS 32.37565534 -38.95999828
OS 32.37565534 -38.49586916
OS 32.44684646 -38.49586916
OS 32.44684646 -38.56613572
OS 32.44777102 -38.56521116
OS 32.45146926 -38.55873924
OS 32.45609206 -38.5504182
OS 32.46348854 -38.54024804
OS 32.47088502 -38.53007788
OS 32.47920606 -38.51898316
OS 32.4875271 -38.50973756
OS 32.49584814 -38.50234108
OS 32.4967727 -38.50141652
OS 32.49954638 -38.4995674
OS 32.50509374 -38.49679372
OS 32.5106411 -38.49402004
OS 32.51803758 -38.49124636
OS 32.52728318 -38.48847268
OS 32.53652878 -38.48662356
OS 32.54669894 -38.485699
OS 32.55317086 -38.485699
OS 32.5614919 -38.48662356
OE
OB 32.75195126 -38.4117342 I
OS 32.67336366 -38.4117342
OS 32.67336366 -38.32020276
OS 32.75195126 -38.32020276
OS 32.75195126 -38.4117342
OE
OB 36.56668582 -38.95999828 I
OS 36.47885262 -38.95999828
OS 36.1441619 -38.4579622
OS 36.1441619 -38.95999828
OS 36.06280062 -38.95999828
OS 36.06280062 -38.32020276
OS 36.14970926 -38.32020276
OS 36.48532454 -38.8231634
OS 36.48532454 -38.32020276
OS 36.56668582 -38.32020276
OS 36.56668582 -38.95999828
OE
OB 35.74382742 -38.32112732 I
OS 35.75954494 -38.32205188
OS 35.77618702 -38.32297644
OS 35.79190454 -38.32482556
OS 35.80577294 -38.32667468
OS 35.80762206 -38.32667468
OS 35.81409398 -38.3285238
OS 35.82241502 -38.33037292
OS 35.83350974 -38.3331466
OS 35.84552902 -38.3377694
OS 35.85847286 -38.34331676
OS 35.87234126 -38.34978868
OS 35.88436054 -38.35718516
OS 35.88620966 -38.35810972
OS 35.8899079 -38.3608834
OS 35.89545526 -38.36643076
OS 35.90285174 -38.37290268
OS 35.91117278 -38.38122372
OS 35.91949382 -38.39231844
OS 35.92873942 -38.40433772
OS 35.9361359 -38.41820612
OS 35.93706046 -38.42005524
OS 35.93890958 -38.42467804
OS 35.94260782 -38.43299908
OS 35.94630606 -38.4440938
OS 35.94907974 -38.45703764
OS 35.95277798 -38.4718306
OS 35.9546271 -38.48847268
OS 35.95555166 -38.50603932
OS 35.95555166 -38.50696388
OS 35.95555166 -38.50973756
OS 35.95555166 -38.5134358
OS 35.9546271 -38.51990772
OS 35.95370254 -38.52637964
OS 35.95277798 -38.53470068
OS 35.95092886 -38.54394628
OS 35.94907974 -38.55411644
OS 35.94260782 -38.57538132
OS 35.93890958 -38.58647604
OS 35.93336222 -38.59849532
OS 35.9268903 -38.6105146
OS 35.92041838 -38.62160932
OS 35.91209734 -38.63270404
OS 35.90285174 -38.64379876
OS 35.90192718 -38.64472332
OS 35.90007806 -38.64657244
OS 35.89730438 -38.64934612
OS 35.89268158 -38.6521198
OS 35.88713422 -38.6567426
OS 35.87973774 -38.6613654
OS 35.87049214 -38.66691276
OS 35.86032198 -38.67153556
OS 35.8483027 -38.67708292
OS 35.8344343 -38.68263028
OS 35.81964134 -38.68725308
OS 35.8020747 -38.69095132
OS 35.7835835 -38.69464956
OS 35.76324318 -38.69742324
OS 35.74012918 -38.69927236
OS 35.71609062 -38.70019692
OS 35.5524435 -38.70019692
OS 35.5524435 -38.95999828
OS 35.46738398 -38.95999828
OS 35.46738398 -38.32020276
OS 35.72995902 -38.32020276
OS 35.74382742 -38.32112732
OE
OB 36.76916446 -38.42745172 I
OS 36.74789958 -38.54671996
OS 36.6988979 -38.54671996
OS 36.67948214 -38.42745172
OS 36.67948214 -38.32020276
OS 36.76916446 -38.32020276
OS 36.76916446 -38.42745172
OE
OB 38.2382903 -38.39601668 I
OS 37.86014526 -38.39601668
OS 37.86014526 -38.59109884
OS 38.21425174 -38.59109884
OS 38.21425174 -38.66691276
OS 37.86014526 -38.66691276
OS 37.86014526 -38.88418436
OS 38.25308326 -38.88418436
OS 38.25308326 -38.95999828
OS 37.77508574 -38.95999828
OS 37.77508574 -38.32020276
OS 38.2382903 -38.32020276
OS 38.2382903 -38.39601668
OE
OB 37.4339231 -38.32112732 I
OS 37.44224414 -38.32112732
OS 37.4616599 -38.32205188
OS 37.48200022 -38.32482556
OS 37.50418966 -38.32759924
OS 37.52452998 -38.33222204
OS 37.53470014 -38.33499572
OS 37.54302118 -38.3377694
OS 37.54394574 -38.3377694
OS 37.5448703 -38.33869396
OS 37.55041766 -38.34146764
OS 37.5587387 -38.34516588
OS 37.56890886 -38.3516378
OS 37.58000358 -38.35995884
OS 37.59202286 -38.37105356
OS 37.60311758 -38.3839974
OS 37.6142123 -38.39879036
OS 37.6142123 -38.39971492
OS 37.61513686 -38.40063948
OS 37.6188351 -38.40618684
OS 37.62253334 -38.41543244
OS 37.6280807 -38.42745172
OS 37.6327035 -38.44132012
OS 37.6373263 -38.4579622
OS 37.64009998 -38.47552884
OS 37.64102454 -38.4949446
OS 37.64102454 -38.49586916
OS 37.64102454 -38.49771828
OS 37.64102454 -38.50141652
OS 37.64009998 -38.50603932
OS 37.64009998 -38.51251124
OS 37.63917542 -38.51898316
OS 37.63547718 -38.53470068
OS 37.62992982 -38.55319188
OS 37.62253334 -38.57260764
OS 37.61143862 -38.5920234
OS 37.60404214 -38.601269
OS 37.59664566 -38.6105146
OS 37.5957211 -38.61143916
OS 37.59479654 -38.61236372
OS 37.59202286 -38.6151374
OS 37.58832462 -38.61791108
OS 37.58370182 -38.62160932
OS 37.57815446 -38.62530756
OS 37.57075798 -38.62993036
OS 37.5633615 -38.63547772
OS 37.5541159 -38.64010052
OS 37.54394574 -38.64472332
OS 37.53285102 -38.65027068
OS 37.52083174 -38.65489348
OS 37.50696334 -38.65859172
OS 37.49309494 -38.66321452
OS 37.47737742 -38.6659882
OS 37.46073534 -38.66876188
OS 37.46258446 -38.66968644
OS 37.4662827 -38.67153556
OS 37.47183006 -38.6752338
OS 37.47922654 -38.67893204
OS 37.49586862 -38.6891022
OS 37.50418966 -38.69557412
OS 37.51158614 -38.70112148
OS 37.51343526 -38.7029706
OS 37.51805806 -38.7075934
OS 37.52545454 -38.71498988
OS 37.53470014 -38.72423548
OS 37.5448703 -38.73717932
OS 37.55688958 -38.75104772
OS 37.56890886 -38.7676898
OS 37.5818527 -38.786181
OS 37.69187534 -38.95999828
OS 37.5864755 -38.95999828
OS 37.50234054 -38.82686164
OS 37.50234054 -38.82593708
OS 37.50049142 -38.82408796
OS 37.4986423 -38.82131428
OS 37.49586862 -38.81761604
OS 37.4893967 -38.80744588
OS 37.48107566 -38.79450204
OS 37.4709055 -38.78063364
OS 37.46073534 -38.76584068
OS 37.45056518 -38.75197228
OS 37.44131958 -38.73902844
OS 37.44039502 -38.73810388
OS 37.43762134 -38.73440564
OS 37.43299854 -38.72885828
OS 37.42652662 -38.72238636
OS 37.41265822 -38.70851796
OS 37.40526174 -38.70204604
OS 37.39786526 -38.69649868
OS 37.3969407 -38.69557412
OS 37.39509158 -38.69464956
OS 37.39139334 -38.69280044
OS 37.38584598 -38.69002676
OS 37.38029862 -38.68725308
OS 37.3738267 -38.6844794
OS 37.35903374 -38.6798566
OS 37.35810918 -38.6798566
OS 37.35626006 -38.67893204
OS 37.35256182 -38.67893204
OS 37.34793902 -38.67800748
OS 37.3414671 -38.67708292
OS 37.33407062 -38.67708292
OS 37.32390046 -38.67615836
OS 37.21480238 -38.67615836
OS 37.21480238 -38.95999828
OS 37.12974286 -38.95999828
OS 37.12974286 -38.32020276
OS 37.42652662 -38.32020276
OS 37.4339231 -38.32112732
OE
OB 35.31760526 -38.95999828 I
OS 35.23254574 -38.95999828
OS 35.23254574 -38.32020276
OS 35.31760526 -38.32020276
OS 35.31760526 -38.95999828
OE
OB 42.12051774 -38.66413908 H
OS 41.95224782 -38.66413908
OS 41.95224782 -38.88418436
OS 42.13438614 -38.88418436
OS 42.1538019 -38.8832598
OS 42.16212294 -38.88233524
OS 42.16951942 -38.88141068
OS 42.17044398 -38.88141068
OS 42.17414222 -38.88048612
OS 42.17968958 -38.87956156
OS 42.1861615 -38.87771244
OS 42.20187902 -38.87216508
OS 42.21759654 -38.8647686
OS 42.2185211 -38.86384404
OS 42.22129478 -38.86199492
OS 42.22499302 -38.85922124
OS 42.22961582 -38.855523
OS 42.23423862 -38.84997564
OS 42.24071054 -38.84442828
OS 42.24533334 -38.8370318
OS 42.2508807 -38.82871076
OS 42.25180526 -38.8277862
OS 42.25272982 -38.82501252
OS 42.25457894 -38.81946516
OS 42.25735262 -38.81299324
OS 42.2601263 -38.80559676
OS 42.26197542 -38.79635116
OS 42.26289998 -38.78525644
OS 42.26382454 -38.77416172
OS 42.26382454 -38.7723126
OS 42.26382454 -38.76861436
OS 42.26289998 -38.76121788
OS 42.26105086 -38.75289684
OS 42.25920174 -38.74365124
OS 42.2555035 -38.73348108
OS 42.2508807 -38.72331092
OS 42.24440878 -38.71314076
OS 42.24348422 -38.7122162
OS 42.24071054 -38.70851796
OS 42.2370123 -38.70389516
OS 42.23146494 -38.6983478
OS 42.22406846 -38.69187588
OS 42.21482286 -38.68540396
OS 42.2046527 -38.6798566
OS 42.19263342 -38.6752338
OS 42.1907843 -38.67430924
OS 42.18708606 -38.67338468
OS 42.17876502 -38.67153556
OS 42.16859486 -38.66968644
OS 42.15565102 -38.66783732
OS 42.1399335 -38.6659882
OS 42.12051774 -38.66413908
OE
OB 45.22981302 -38.5504182 H
OS 45.22426566 -38.5504182
OS 45.21964286 -38.55134276
OS 45.2094727 -38.55226732
OS 45.1956043 -38.55596556
OS 45.17988678 -38.56151292
OS 45.1632447 -38.5689094
OS 45.14752718 -38.58000412
OS 45.13920614 -38.5874006
OS 45.13180966 -38.59479708
OS 45.13180966 -38.59572164
OS 45.12996054 -38.5966462
OS 45.12811142 -38.59941988
OS 45.12533774 -38.60311812
OS 45.12256406 -38.60774092
OS 45.11979038 -38.61328828
OS 45.11609214 -38.62068476
OS 45.1123939 -38.62808124
OS 45.10869566 -38.63732684
OS 45.10499742 -38.64657244
OS 45.10222374 -38.65766716
OS 45.09945006 -38.66968644
OS 45.09667638 -38.68263028
OS 45.09482726 -38.69649868
OS 45.0939027 -38.7122162
OS 45.09297814 -38.72793372
OS 45.09297814 -38.72885828
OS 45.09297814 -38.73163196
OS 45.09297814 -38.73625476
OS 45.0939027 -38.74272668
OS 45.0939027 -38.75012316
OS 45.09482726 -38.7584442
OS 45.09760094 -38.77785996
OS 45.10222374 -38.8000494
OS 45.10962022 -38.82223884
OS 45.11886582 -38.84350372
OS 45.12533774 -38.85274932
OS 45.13180966 -38.86199492
OS 45.13273422 -38.86199492
OS 45.13365878 -38.86384404
OS 45.13920614 -38.86846684
OS 45.14752718 -38.87586332
OS 45.1586219 -38.8832598
OS 45.1724903 -38.89158084
OS 45.18913238 -38.89897732
OS 45.20854814 -38.90360012
OS 45.2187183 -38.90452468
OS 45.22981302 -38.90544924
OS 45.23536038 -38.90544924
OS 45.23998318 -38.90452468
OS 45.25015334 -38.90267556
OS 45.26402174 -38.89990188
OS 45.2788147 -38.89435452
OS 45.29545678 -38.88695804
OS 45.3111743 -38.87586332
OS 45.31949534 -38.86846684
OS 45.32689182 -38.86107036
OS 45.32781638 -38.8601458
OS 45.32874094 -38.85922124
OS 45.33059006 -38.85644756
OS 45.33336374 -38.85274932
OS 45.33613742 -38.84812652
OS 45.33983566 -38.84257916
OS 45.3435339 -38.83518268
OS 45.34723214 -38.8277862
OS 45.35093038 -38.8185406
OS 45.35370406 -38.80837044
OS 45.3574023 -38.79727572
OS 45.36017598 -38.78525644
OS 45.36294966 -38.77138804
OS 45.36479878 -38.75751964
OS 45.3666479 -38.74180212
OS 45.3666479 -38.72516004
OS 45.3666479 -38.72423548
OS 45.3666479 -38.7214618
OS 45.3666479 -38.716839
OS 45.36572334 -38.71129164
OS 45.36572334 -38.70389516
OS 45.36479878 -38.69557412
OS 45.3620251 -38.67615836
OS 45.3574023 -38.65581804
OS 45.35000582 -38.6336286
OS 45.33983566 -38.61328828
OS 45.3342883 -38.60311812
OS 45.32689182 -38.59479708
OS 45.32689182 -38.59387252
OS 45.3250427 -38.59294796
OS 45.31949534 -38.5874006
OS 45.3111743 -38.58092868
OS 45.30007958 -38.57260764
OS 45.28621118 -38.5642866
OS 45.2695691 -38.55689012
OS 45.2510779 -38.55226732
OS 45.24090774 -38.55134276
OS 45.22981302 -38.5504182
OE
OB 32.07702246 -38.54764452 H
OS 32.07239966 -38.54764452
OS 32.06870142 -38.54856908
OS 32.05945582 -38.5504182
OS 32.04743654 -38.55319188
OS 32.03356814 -38.55873924
OS 32.01877518 -38.56706028
OS 32.01045414 -38.57260764
OS 32.00305766 -38.57907956
OS 31.99566118 -38.58647604
OS 31.9882647 -38.59479708
OS 31.9882647 -38.59572164
OS 31.98641558 -38.5966462
OS 31.98456646 -38.59941988
OS 31.98271734 -38.60311812
OS 31.97994366 -38.60866548
OS 31.97624542 -38.61421284
OS 31.97254718 -38.62160932
OS 31.9697735 -38.6290058
OS 31.96607526 -38.6382514
OS 31.96237702 -38.64842156
OS 31.95960334 -38.65951628
OS 31.9559051 -38.67153556
OS 31.95405598 -38.68540396
OS 31.95220686 -38.69927236
OS 31.95035774 -38.71406532
OS 31.95035774 -38.7307074
OS 31.95035774 -38.73163196
OS 31.95035774 -38.73440564
OS 31.95035774 -38.73902844
OS 31.9512823 -38.74550036
OS 31.9512823 -38.75289684
OS 31.95220686 -38.76121788
OS 31.95498054 -38.78063364
OS 31.95960334 -38.80282308
OS 31.9651507 -38.82408796
OS 31.9743963 -38.84535284
OS 31.97994366 -38.85459844
OS 31.98641558 -38.86291948
OS 31.9882647 -38.8647686
OS 31.9928875 -38.8693914
OS 32.00028398 -38.87678788
OS 32.01045414 -38.88418436
OS 32.02339798 -38.89158084
OS 32.03819094 -38.89897732
OS 32.05483302 -38.90360012
OS 32.06407862 -38.90452468
OS 32.07332422 -38.90544924
OS 32.07887158 -38.90544924
OS 32.08256982 -38.90452468
OS 32.09181542 -38.90267556
OS 32.10475926 -38.89990188
OS 32.11862766 -38.89435452
OS 32.13342062 -38.88695804
OS 32.14821358 -38.87586332
OS 32.15561006 -38.8693914
OS 32.16300654 -38.86199492
OS 32.16300654 -38.86107036
OS 32.16485566 -38.8601458
OS 32.16670478 -38.85737212
OS 32.1685539 -38.85367388
OS 32.17225214 -38.84905108
OS 32.17502582 -38.84257916
OS 32.17872406 -38.83610724
OS 32.1824223 -38.8277862
OS 32.18519598 -38.81946516
OS 32.18889422 -38.80837044
OS 32.19259246 -38.79727572
OS 32.19536614 -38.78525644
OS 32.19721526 -38.77138804
OS 32.19906438 -38.75659508
OS 32.2009135 -38.74087756
OS 32.2009135 -38.72423548
OS 32.2009135 -38.72331092
OS 32.2009135 -38.72053724
OS 32.2009135 -38.71591444
OS 32.19998894 -38.70944252
OS 32.19998894 -38.70204604
OS 32.19906438 -38.693725
OS 32.1962907 -38.67430924
OS 32.1916679 -38.65304436
OS 32.18519598 -38.63177948
OS 32.17595038 -38.6105146
OS 32.17040302 -38.60034444
OS 32.1639311 -38.5920234
OS 32.1639311 -38.59109884
OS 32.16208198 -38.59017428
OS 32.15745918 -38.58462692
OS 32.1500627 -38.578155
OS 32.13989254 -38.56983396
OS 32.1269487 -38.56151292
OS 32.11215574 -38.55411644
OS 32.09551366 -38.54949364
OS 32.08626806 -38.54856908
OS 32.07702246 -38.54764452
OE
OB 42.10387566 -38.39601668 H
OS 41.95224782 -38.39601668
OS 41.95224782 -38.58832516
OS 42.10942302 -38.58832516
OS 42.1214423 -38.5874006
OS 42.13438614 -38.58647604
OS 42.14732998 -38.58555148
OS 42.16027382 -38.58370236
OS 42.17044398 -38.58185324
OS 42.1722931 -38.58092868
OS 42.17599134 -38.58000412
OS 42.1815387 -38.57723044
OS 42.18893518 -38.5735322
OS 42.19633166 -38.56983396
OS 42.2046527 -38.5642866
OS 42.21297374 -38.55689012
OS 42.21944566 -38.54949364
OS 42.22037022 -38.54856908
OS 42.22221934 -38.5457954
OS 42.22499302 -38.54024804
OS 42.2277667 -38.53377612
OS 42.23054038 -38.52637964
OS 42.23331406 -38.51713404
OS 42.23516318 -38.50603932
OS 42.23608774 -38.49402004
OS 42.23608774 -38.49217092
OS 42.23608774 -38.48847268
OS 42.23516318 -38.48292532
OS 42.23423862 -38.47552884
OS 42.2323895 -38.46628324
OS 42.22961582 -38.45703764
OS 42.22591758 -38.44779204
OS 42.22037022 -38.43854644
OS 42.21944566 -38.43762188
OS 42.21759654 -38.4348482
OS 42.2138983 -38.4302254
OS 42.2092755 -38.4256026
OS 42.20280358 -38.42005524
OS 42.1954071 -38.41450788
OS 42.1861615 -38.40896052
OS 42.17599134 -38.40526228
OS 42.17506678 -38.40526228
OS 42.17044398 -38.40341316
OS 42.16397206 -38.4024886
OS 42.1538019 -38.40063948
OS 42.1399335 -38.39879036
OS 42.12421598 -38.3978658
OS 42.10387566 -38.39601668
OE
OB 37.41635646 -38.39139388 H
OS 37.21480238 -38.39139388
OS 37.21480238 -38.60311812
OS 37.40526174 -38.60311812
OS 37.41635646 -38.60219356
OS 37.4293003 -38.601269
OS 37.44409326 -38.60034444
OS 37.45888622 -38.59849532
OS 37.47367918 -38.59572164
OS 37.48662302 -38.5920234
OS 37.48847214 -38.59109884
OS 37.49217038 -38.58924972
OS 37.49771774 -38.58647604
OS 37.50511422 -38.5827778
OS 37.51343526 -38.57723044
OS 37.5217563 -38.57075852
OS 37.53007734 -38.56243748
OS 37.53654926 -38.55319188
OS 37.53747382 -38.55226732
OS 37.53932294 -38.54856908
OS 37.54209662 -38.54302172
OS 37.54579486 -38.53562524
OS 37.54856854 -38.5273042
OS 37.55134222 -38.5180586
OS 37.55319134 -38.50696388
OS 37.5541159 -38.49586916
OS 37.5541159 -38.4949446
OS 37.5541159 -38.49402004
OS 37.55319134 -38.48847268
OS 37.55226678 -38.48015164
OS 37.55041766 -38.46905692
OS 37.54579486 -38.4579622
OS 37.5402475 -38.44501836
OS 37.53192646 -38.43299908
OS 37.52083174 -38.4209798
OS 37.51898262 -38.42005524
OS 37.51435982 -38.416357
OS 37.50696334 -38.4117342
OS 37.49494406 -38.40618684
OS 37.48107566 -38.40063948
OS 37.46258446 -38.39601668
OS 37.44131958 -38.39231844
OS 37.41635646 -38.39139388
OE
OB 39.82298614 -38.54764452 H
OS 39.81836334 -38.54764452
OS 39.8146651 -38.54856908
OS 39.8054195 -38.5504182
OS 39.79340022 -38.55319188
OS 39.77953182 -38.55873924
OS 39.76473886 -38.56706028
OS 39.75641782 -38.57260764
OS 39.74902134 -38.57907956
OS 39.74162486 -38.58647604
OS 39.73422838 -38.59479708
OS 39.73422838 -38.59572164
OS 39.73237926 -38.5966462
OS 39.73053014 -38.59941988
OS 39.72868102 -38.60311812
OS 39.72590734 -38.60866548
OS 39.7222091 -38.61421284
OS 39.71851086 -38.62160932
OS 39.71573718 -38.6290058
OS 39.71203894 -38.6382514
OS 39.7083407 -38.64842156
OS 39.70556702 -38.65951628
OS 39.70186878 -38.67153556
OS 39.70001966 -38.68540396
OS 39.69817054 -38.69927236
OS 39.69632142 -38.71406532
OS 39.69632142 -38.7307074
OS 39.69632142 -38.73163196
OS 39.69632142 -38.73440564
OS 39.69632142 -38.73902844
OS 39.69724598 -38.74550036
OS 39.69724598 -38.75289684
OS 39.69817054 -38.76121788
OS 39.70094422 -38.78063364
OS 39.70556702 -38.80282308
OS 39.71111438 -38.82408796
OS 39.72035998 -38.84535284
OS 39.72590734 -38.85459844
OS 39.73237926 -38.86291948
OS 39.73422838 -38.8647686
OS 39.73885118 -38.8693914
OS 39.74624766 -38.87678788
OS 39.75641782 -38.88418436
OS 39.76936166 -38.89158084
OS 39.78415462 -38.89897732
OS 39.8007967 -38.90360012
OS 39.8100423 -38.90452468
OS 39.8192879 -38.90544924
OS 39.82483526 -38.90544924
OS 39.8285335 -38.90452468
OS 39.8377791 -38.90267556
OS 39.85072294 -38.89990188
OS 39.86459134 -38.89435452
OS 39.8793843 -38.88695804
OS 39.89417726 -38.87586332
OS 39.90157374 -38.8693914
OS 39.90897022 -38.86199492
OS 39.90897022 -38.86107036
OS 39.91081934 -38.8601458
OS 39.91266846 -38.85737212
OS 39.91451758 -38.85367388
OS 39.91821582 -38.84905108
OS 39.9209895 -38.84257916
OS 39.92468774 -38.83610724
OS 39.92838598 -38.8277862
OS 39.93115966 -38.81946516
OS 39.9348579 -38.80837044
OS 39.93855614 -38.79727572
OS 39.94132982 -38.78525644
OS 39.94317894 -38.77138804
OS 39.94502806 -38.75659508
OS 39.94687718 -38.74087756
OS 39.94687718 -38.72423548
OS 39.94687718 -38.72331092
OS 39.94687718 -38.72053724
OS 39.94687718 -38.71591444
OS 39.94595262 -38.70944252
OS 39.94595262 -38.70204604
OS 39.94502806 -38.693725
OS 39.94225438 -38.67430924
OS 39.93763158 -38.65304436
OS 39.93115966 -38.63177948
OS 39.92191406 -38.6105146
OS 39.9163667 -38.60034444
OS 39.90989478 -38.5920234
OS 39.90989478 -38.59109884
OS 39.90804566 -38.59017428
OS 39.90342286 -38.58462692
OS 39.89602638 -38.578155
OS 39.88585622 -38.56983396
OS 39.87291238 -38.56151292
OS 39.85811942 -38.55411644
OS 39.84147734 -38.54949364
OS 39.83223174 -38.54856908
OS 39.82298614 -38.54764452
OE
OB 35.73550638 -38.39601668 H
OS 35.5524435 -38.39601668
OS 35.5524435 -38.624383
OS 35.72441166 -38.624383
OS 35.73088358 -38.62345844
OS 35.7373555 -38.62345844
OS 35.74475198 -38.62253388
OS 35.76231862 -38.62068476
OS 35.78173438 -38.61698652
OS 35.80115014 -38.61143916
OS 35.81871678 -38.60404268
OS 35.82703782 -38.59941988
OS 35.83350974 -38.59387252
OS 35.83535886 -38.5920234
OS 35.8390571 -38.58832516
OS 35.84460446 -38.58092868
OS 35.85107638 -38.57168308
OS 35.8575483 -38.5596638
OS 35.86309566 -38.54487084
OS 35.8667939 -38.52822876
OS 35.86864302 -38.508813
OS 35.86864302 -38.50788844
OS 35.86864302 -38.50696388
OS 35.86864302 -38.50234108
OS 35.86771846 -38.49402004
OS 35.86586934 -38.48477444
OS 35.86402022 -38.47460428
OS 35.86032198 -38.462585
OS 35.85477462 -38.45149028
OS 35.8483027 -38.44039556
OS 35.84737814 -38.439471
OS 35.84460446 -38.43577276
OS 35.83998166 -38.43114996
OS 35.8344343 -38.42467804
OS 35.82611326 -38.41820612
OS 35.81686766 -38.41265876
OS 35.8066975 -38.4071114
OS 35.79467822 -38.4024886
OS 35.79375366 -38.4024886
OS 35.79005542 -38.40156404
OS 35.78450806 -38.40063948
OS 35.77711158 -38.39879036
OS 35.76601686 -38.3978658
OS 35.75214846 -38.39694124
OS 35.73550638 -38.39601668
OE
OB 43.44263854 -38.5504182 H
OS 43.43709118 -38.5504182
OS 43.43339294 -38.55134276
OS 43.42322278 -38.55226732
OS 43.4112035 -38.555041
OS 43.39641054 -38.5596638
OS 43.38069302 -38.56613572
OS 43.36590006 -38.57538132
OS 43.3511071 -38.5874006
OS 43.34925798 -38.58924972
OS 43.34555974 -38.59387252
OS 43.33908782 -38.60219356
OS 43.3326159 -38.61328828
OS 43.32521942 -38.62623212
OS 43.3187475 -38.6428742
OS 43.31320014 -38.66228996
OS 43.31042646 -38.68355484
OS 43.57022782 -38.68355484
OS 43.57022782 -38.68263028
OS 43.57022782 -38.68078116
OS 43.56930326 -38.67800748
OS 43.56930326 -38.67430924
OS 43.56745414 -38.66321452
OS 43.56468046 -38.65119524
OS 43.56005766 -38.63640228
OS 43.55543486 -38.62253388
OS 43.54803838 -38.60866548
OS 43.53971734 -38.5966462
OS 43.53971734 -38.59572164
OS 43.53786822 -38.59479708
OS 43.53324542 -38.58924972
OS 43.52492438 -38.58185324
OS 43.51382966 -38.5735322
OS 43.49996126 -38.56521116
OS 43.48331918 -38.55781468
OS 43.46390342 -38.55226732
OS 43.45373326 -38.55134276
OS 43.44263854 -38.5504182
OE
OB 34.35791198 -38.39601668 H
OS 34.20628414 -38.39601668
OS 34.20628414 -38.58832516
OS 34.36345934 -38.58832516
OS 34.37547862 -38.5874006
OS 34.38842246 -38.58647604
OS 34.4013663 -38.58555148
OS 34.41431014 -38.58370236
OS 34.4244803 -38.58185324
OS 34.42632942 -38.58092868
OS 34.43002766 -38.58000412
OS 34.43557502 -38.57723044
OS 34.4429715 -38.5735322
OS 34.45036798 -38.56983396
OS 34.45868902 -38.5642866
OS 34.46701006 -38.55689012
OS 34.47348198 -38.54949364
OS 34.47440654 -38.54856908
OS 34.47625566 -38.5457954
OS 34.47902934 -38.54024804
OS 34.48180302 -38.53377612
OS 34.4845767 -38.52637964
OS 34.48735038 -38.51713404
OS 34.4891995 -38.50603932
OS 34.49012406 -38.49402004
OS 34.49012406 -38.49217092
OS 34.49012406 -38.48847268
OS 34.4891995 -38.48292532
OS 34.48827494 -38.47552884
OS 34.48642582 -38.46628324
OS 34.48365214 -38.45703764
OS 34.4799539 -38.44779204
OS 34.47440654 -38.43854644
OS 34.47348198 -38.43762188
OS 34.47163286 -38.4348482
OS 34.46793462 -38.4302254
OS 34.46331182 -38.4256026
OS 34.4568399 -38.42005524
OS 34.44944342 -38.41450788
OS 34.44019782 -38.40896052
OS 34.43002766 -38.40526228
OS 34.4291031 -38.40526228
OS 34.4244803 -38.40341316
OS 34.41800838 -38.4024886
OS 34.40783822 -38.40063948
OS 34.39396982 -38.39879036
OS 34.3782523 -38.3978658
OS 34.35791198 -38.39601668
OE
OB 40.89732486 -38.39601668 H
OS 40.71426198 -38.39601668
OS 40.71426198 -38.624383
OS 40.88623014 -38.624383
OS 40.89270206 -38.62345844
OS 40.89917398 -38.62345844
OS 40.90657046 -38.62253388
OS 40.9241371 -38.62068476
OS 40.94355286 -38.61698652
OS 40.96296862 -38.61143916
OS 40.98053526 -38.60404268
OS 40.9888563 -38.59941988
OS 40.99532822 -38.59387252
OS 40.99717734 -38.5920234
OS 41.00087558 -38.58832516
OS 41.00642294 -38.58092868
OS 41.01289486 -38.57168308
OS 41.01936678 -38.5596638
OS 41.02491414 -38.54487084
OS 41.02861238 -38.52822876
OS 41.0304615 -38.508813
OS 41.0304615 -38.50788844
OS 41.0304615 -38.50696388
OS 41.0304615 -38.50234108
OS 41.02953694 -38.49402004
OS 41.02768782 -38.48477444
OS 41.0258387 -38.47460428
OS 41.02214046 -38.462585
OS 41.0165931 -38.45149028
OS 41.01012118 -38.44039556
OS 41.00919662 -38.439471
OS 41.00642294 -38.43577276
OS 41.00180014 -38.43114996
OS 40.99625278 -38.42467804
OS 40.98793174 -38.41820612
OS 40.97868614 -38.41265876
OS 40.96851598 -38.4071114
OS 40.9564967 -38.4024886
OS 40.95557214 -38.4024886
OS 40.9518739 -38.40156404
OS 40.94632654 -38.40063948
OS 40.93893006 -38.39879036
OS 40.92783534 -38.3978658
OS 40.91396694 -38.39694124
OS 40.89732486 -38.39601668
OE
OB 33.15136118 -38.39601668 H
OS 32.9682983 -38.39601668
OS 32.9682983 -38.624383
OS 33.14026646 -38.624383
OS 33.14673838 -38.62345844
OS 33.1532103 -38.62345844
OS 33.16060678 -38.62253388
OS 33.17817342 -38.62068476
OS 33.19758918 -38.61698652
OS 33.21700494 -38.61143916
OS 33.23457158 -38.60404268
OS 33.24289262 -38.59941988
OS 33.24936454 -38.59387252
OS 33.25121366 -38.5920234
OS 33.2549119 -38.58832516
OS 33.26045926 -38.58092868
OS 33.26693118 -38.57168308
OS 33.2734031 -38.5596638
OS 33.27895046 -38.54487084
OS 33.2826487 -38.52822876
OS 33.28449782 -38.508813
OS 33.28449782 -38.50788844
OS 33.28449782 -38.50696388
OS 33.28449782 -38.50234108
OS 33.28357326 -38.49402004
OS 33.28172414 -38.48477444
OS 33.27987502 -38.47460428
OS 33.27617678 -38.462585
OS 33.27062942 -38.45149028
OS 33.2641575 -38.44039556
OS 33.26323294 -38.439471
OS 33.26045926 -38.43577276
OS 33.25583646 -38.43114996
OS 33.2502891 -38.42467804
OS 33.24196806 -38.41820612
OS 33.23272246 -38.41265876
OS 33.2225523 -38.4071114
OS 33.21053302 -38.4024886
OS 33.20960846 -38.4024886
OS 33.20591022 -38.40156404
OS 33.20036286 -38.40063948
OS 33.19296638 -38.39879036
OS 33.18187166 -38.3978658
OS 33.16800326 -38.39694124
OS 33.15136118 -38.39601668
OE
OB 34.37455406 -38.66413908 H
OS 34.20628414 -38.66413908
OS 34.20628414 -38.88418436
OS 34.38842246 -38.88418436
OS 34.40783822 -38.8832598
OS 34.41615926 -38.88233524
OS 34.42355574 -38.88141068
OS 34.4244803 -38.88141068
OS 34.42817854 -38.88048612
OS 34.4337259 -38.87956156
OS 34.44019782 -38.87771244
OS 34.45591534 -38.87216508
OS 34.47163286 -38.8647686
OS 34.47255742 -38.86384404
OS 34.4753311 -38.86199492
OS 34.47902934 -38.85922124
OS 34.48365214 -38.855523
OS 34.48827494 -38.84997564
OS 34.49474686 -38.84442828
OS 34.49936966 -38.8370318
OS 34.50491702 -38.82871076
OS 34.50584158 -38.8277862
OS 34.50676614 -38.82501252
OS 34.50861526 -38.81946516
OS 34.51138894 -38.81299324
OS 34.51416262 -38.80559676
OS 34.51601174 -38.79635116
OS 34.5169363 -38.78525644
OS 34.51786086 -38.77416172
OS 34.51786086 -38.7723126
OS 34.51786086 -38.76861436
OS 34.5169363 -38.76121788
OS 34.51508718 -38.75289684
OS 34.51323806 -38.74365124
OS 34.50953982 -38.73348108
OS 34.50491702 -38.72331092
OS 34.4984451 -38.71314076
OS 34.49752054 -38.7122162
OS 34.49474686 -38.70851796
OS 34.49104862 -38.70389516
OS 34.48550126 -38.6983478
OS 34.47810478 -38.69187588
OS 34.46885918 -38.68540396
OS 34.45868902 -38.6798566
OS 34.44666974 -38.6752338
OS 34.44482062 -38.67430924
OS 34.44112238 -38.67338468
OS 34.43280134 -38.67153556
OS 34.42263118 -38.66968644
OS 34.40968734 -38.66783732
OS 34.39396982 -38.6659882
OS 34.37455406 -38.66413908
OE
SE
S P 0
OB 32.31422036 39.98905388 I
OS 32.31422036 40.4254462
OS 32.39927988 40.4254462
OS 32.39927988 39.98443108
OS 32.39927988 39.96501532
OS 32.401129 39.94837324
OS 32.40205356 39.93450484
OS 32.40390268 39.92341012
OS 32.4057518 39.91508908
OS 32.40667636 39.90861716
OS 32.40852548 39.90491892
OS 32.40852548 39.90399436
OS 32.41222372 39.89474876
OS 32.41684652 39.88735228
OS 32.42239388 39.88088036
OS 32.42701668 39.87440844
OS 32.43256404 39.8707102
OS 32.43626228 39.86701196
OS 32.43903596 39.86516284
OS 32.43996052 39.86423828
OS 32.44920612 39.85961548
OS 32.45845172 39.85591724
OS 32.46769732 39.85406812
OS 32.47601836 39.852219
OS 32.4843394 39.85129444
OS 32.48988676 39.85036988
OS 32.49543412 39.85036988
OS 32.51022708 39.85129444
OS 32.52409548 39.85499268
OS 32.5351902 39.85869092
OS 32.54536036 39.86423828
OS 32.55275684 39.86886108
OS 32.5583042 39.87348388
OS 32.56200244 39.87625756
OS 32.562927 39.87718212
OS 32.5675498 39.88272948
OS 32.57124804 39.8892014
OS 32.5767954 39.90399436
OS 32.58234276 39.92063644
OS 32.58511644 39.93727852
OS 32.58789012 39.95299604
OS 32.58789012 39.95946796
OS 32.58881468 39.96501532
OS 32.58973924 39.97056268
OS 32.58973924 39.97426092
OS 32.58973924 39.97611004
OS 32.58973924 39.9770346
OS 32.66647772 39.96593988
OS 32.66647772 39.94837324
OS 32.66555316 39.93265572
OS 32.66277948 39.9169382
OS 32.66093036 39.9030698
OS 32.65723212 39.89012596
OS 32.65353388 39.87903124
OS 32.64983564 39.86793652
OS 32.6461374 39.85869092
OS 32.6415146 39.85036988
OS 32.63781636 39.8429734
OS 32.63411812 39.83650148
OS 32.63041988 39.83187868
OS 32.6276462 39.82818044
OS 32.62579708 39.8244822
OS 32.62487252 39.82355764
OS 32.62394796 39.82263308
OS 32.61470236 39.81431204
OS 32.60545676 39.80691556
OS 32.5952866 39.80044364
OS 32.58419188 39.79489628
OS 32.562927 39.78657524
OS 32.54258668 39.78102788
OS 32.52317092 39.77732964
OS 32.51577444 39.77640508
OS 32.50837796 39.77548052
OS 32.5028306 39.77455596
OS 32.49450956 39.77455596
OS 32.47416924 39.77548052
OS 32.45567804 39.7782542
OS 32.43903596 39.78195244
OS 32.424243 39.78657524
OS 32.41222372 39.79027348
OS 32.40390268 39.79397172
OS 32.39835532 39.7967454
OS 32.3965062 39.79766996
OS 32.38171324 39.80691556
OS 32.3687694 39.81801028
OS 32.35859924 39.829105
OS 32.34935364 39.83927516
OS 32.34288172 39.84944532
OS 32.33825892 39.8568418
OS 32.33548524 39.86238916
OS 32.33456068 39.86331372
OS 32.33456068 39.86423828
OS 32.32808876 39.88272948
OS 32.3225414 39.90214524
OS 32.31884316 39.92341012
OS 32.31699404 39.94375044
OS 32.31514492 39.96131708
OS 32.31514492 39.96871356
OS 32.31422036 39.97611004
OS 32.31422036 39.9816574
OS 32.31422036 39.98535564
OS 32.31422036 39.98812932
OS 32.31422036 39.98905388
OE
OB 31.8140334 40.3422358 I
OS 31.8140334 40.41712516
OS 32.13208204 40.41712516
OS 32.19402756 40.0879818
OS 32.12006276 40.07781164
OS 32.11359084 40.0879818
OS 32.1052698 40.09630284
OS 32.09787332 40.10462388
OS 32.09047684 40.1110958
OS 32.08308036 40.1157186
OS 32.077533 40.1203414
OS 32.07383476 40.12219052
OS 32.0729102 40.12311508
OS 32.06089092 40.12866244
OS 32.04887164 40.13328524
OS 32.03777692 40.13605892
OS 32.0266822 40.1388326
OS 32.0174366 40.13975716
OS 32.01004012 40.14068172
OS 31.99247348 40.14068172
OS 31.98137876 40.1388326
OS 31.961963 40.1342098
OS 31.94532092 40.12773788
OS 31.93052796 40.12126596
OS 31.91943324 40.11386948
OS 31.9111122 40.10739756
OS 31.9064894 40.10277476
OS 31.90464028 40.1018502
OS 31.90464028 40.10092564
OS 31.89169644 40.08520812
OS 31.88245084 40.06856604
OS 31.87597892 40.0509994
OS 31.87135612 40.03343276
OS 31.86858244 40.0186398
OS 31.86765788 40.01216788
OS 31.86765788 40.00662052
OS 31.86673332 40.00199772
OS 31.86673332 39.99829948
OS 31.86673332 39.99645036
OS 31.86673332 39.9955258
OS 31.86673332 39.98258196
OS 31.86858244 39.97056268
OS 31.87320524 39.94744868
OS 31.87967716 39.92803292
OS 31.88614908 39.9123154
OS 31.89354556 39.89937156
OS 31.90001748 39.8892014
OS 31.90279116 39.88642772
OS 31.90464028 39.88365404
OS 31.90556484 39.88272948
OS 31.9064894 39.88180492
OS 31.91388588 39.87440844
OS 31.92128236 39.86793652
OS 31.93792444 39.8568418
OS 31.95364196 39.84944532
OS 31.96935948 39.84482252
OS 31.98230332 39.84112428
OS 31.99339804 39.84019972
OS 31.99709628 39.83927516
OS 32.00264364 39.83927516
OS 32.02021028 39.84019972
OS 32.0359278 39.84389796
OS 32.0497962 39.84852076
OS 32.06089092 39.85406812
OS 32.07106108 39.85961548
OS 32.07845756 39.86423828
OS 32.0821558 39.86793652
OS 32.08400492 39.86886108
OS 32.09509964 39.88180492
OS 32.10434524 39.89567332
OS 32.11174172 39.91139084
OS 32.11728908 39.92525924
OS 32.12098732 39.93912764
OS 32.123761 39.9492978
OS 32.12468556 39.9539206
OS 32.12561012 39.95669428
OS 32.12561012 39.9585434
OS 32.12561012 39.95946796
OS 32.20789596 39.95299604
OS 32.20604684 39.93820308
OS 32.20327316 39.92433468
OS 32.19495212 39.898447
OS 32.18478196 39.87625756
OS 32.1792346 39.8660874
OS 32.17368724 39.85776636
OS 32.16906444 39.84944532
OS 32.16351708 39.84204884
OS 32.15889428 39.83650148
OS 32.15427148 39.83187868
OS 32.15057324 39.82818044
OS 32.14872412 39.8244822
OS 32.146875 39.82355764
OS 32.14595044 39.82263308
OS 32.13485572 39.81431204
OS 32.123761 39.80691556
OS 32.11174172 39.80044364
OS 32.09972244 39.79489628
OS 32.07660844 39.78657524
OS 32.05349444 39.78102788
OS 32.04332428 39.7782542
OS 32.03315412 39.77732964
OS 32.02483308 39.77640508
OS 32.0174366 39.77548052
OS 32.01096468 39.77455596
OS 32.00264364 39.77455596
OS 31.98322788 39.77548052
OS 31.96473668 39.7782542
OS 31.94717004 39.78195244
OS 31.93145252 39.78657524
OS 31.91665956 39.79304716
OS 31.90279116 39.79951908
OS 31.88984732 39.805991
OS 31.8787526 39.81338748
OS 31.86858244 39.82078396
OS 31.85933684 39.82725588
OS 31.85194036 39.83465236
OS 31.84546844 39.84019972
OS 31.84084564 39.84482252
OS 31.8371474 39.84852076
OS 31.83529828 39.85129444
OS 31.83437372 39.852219
OS 31.82512812 39.86423828
OS 31.81773164 39.87718212
OS 31.81033516 39.8892014
OS 31.8047878 39.90214524
OS 31.7955422 39.92710836
OS 31.78999484 39.95114692
OS 31.78814572 39.96131708
OS 31.7862966 39.97148724
OS 31.78537204 39.97980828
OS 31.78444748 39.98720476
OS 31.78352292 39.99367668
OS 31.78352292 39.99829948
OS 31.78352292 40.00107316
OS 31.78352292 40.00199772
OS 31.78444748 40.0186398
OS 31.7862966 40.03435732
OS 31.78907028 40.05007484
OS 31.79276852 40.06394324
OS 31.79739132 40.07688708
OS 31.80201412 40.08983092
OS 31.80756148 40.10092564
OS 31.81218428 40.1110958
OS 31.81773164 40.1203414
OS 31.823279 40.12866244
OS 31.8279018 40.13513436
OS 31.8325246 40.14160628
OS 31.83622284 40.14622908
OS 31.83899652 40.14900276
OS 31.84084564 40.15085188
OS 31.8417702 40.15177644
OS 31.85286492 40.1619466
OS 31.86395964 40.1711922
OS 31.87597892 40.17858868
OS 31.8879982 40.1850606
OS 31.90001748 40.19153252
OS 31.91203676 40.19615532
OS 31.9342262 40.20262724
OS 31.94439636 40.20540092
OS 31.95364196 40.20725004
OS 31.961963 40.2081746
OS 31.96935948 40.20909916
OS 31.97490684 40.21002372
OS 31.99524716 40.21002372
OS 32.00634188 40.2081746
OS 32.02853132 40.2035518
OS 32.04887164 40.19707988
OS 32.06736284 40.1896834
OS 32.0821558 40.18228692
OS 32.08862772 40.17858868
OS 32.09417508 40.175815
OS 32.09879788 40.17304132
OS 32.10157156 40.1711922
OS 32.10342068 40.17026764
OS 32.10434524 40.16934308
OS 32.07013652 40.3422358
OS 31.8140334 40.3422358
OE
SE
S P 0
OB 33.95172534 9.95313478 I
OS 33.95912182 9.95405934
OS 34.25590558 9.95405934
OS 34.25590558 9.31426382
OS 34.17084606 9.31426382
OS 34.17084606 9.59810374
OS 34.06174798 9.59810374
OS 34.05157782 9.59717918
OS 34.04418134 9.59717918
OS 34.03770942 9.59625462
OS 34.03308662 9.59533006
OS 34.02938838 9.59533006
OS 34.02753926 9.5944055
OS 34.0266147 9.5944055
OS 34.01182174 9.5897827
OS 34.00534982 9.58700902
OS 33.99980246 9.58423534
OS 33.9942551 9.58146166
OS 33.99055686 9.57961254
OS 33.98870774 9.57868798
OS 33.98778318 9.57776342
OS 33.9803867 9.57221606
OS 33.97299022 9.56574414
OS 33.95912182 9.55187574
OS 33.9526499 9.54540382
OS 33.9480271 9.53985646
OS 33.94525342 9.53615822
OS 33.94432886 9.53523366
OS 33.93508326 9.52228982
OS 33.9249131 9.50842142
OS 33.91474294 9.49362846
OS 33.90457278 9.47976006
OS 33.89625174 9.46681622
OS 33.88977982 9.45664606
OS 33.88700614 9.45294782
OS 33.88515702 9.45017414
OS 33.8833079 9.44832502
OS 33.8833079 9.44740046
OS 33.79917294 9.31426382
OS 33.6937731 9.31426382
OS 33.80379574 9.4880811
OS 33.81673958 9.5065723
OS 33.82875886 9.52321438
OS 33.84077814 9.53708278
OS 33.8509483 9.55002662
OS 33.8601939 9.55927222
OS 33.86759038 9.5666687
OS 33.87221318 9.5712915
OS 33.8740623 9.57314062
OS 33.88145878 9.57868798
OS 33.88977982 9.5851599
OS 33.9064219 9.59533006
OS 33.91381838 9.5990283
OS 33.91936574 9.60272654
OS 33.92306398 9.60457566
OS 33.9249131 9.60550022
OS 33.90827102 9.6082739
OS 33.8925535 9.61104758
OS 33.8786851 9.61567038
OS 33.8648167 9.61936862
OS 33.85279742 9.62399142
OS 33.8417027 9.62953878
OS 33.83153254 9.63416158
OS 33.82228694 9.63878438
OS 33.81489046 9.64433174
OS 33.80749398 9.64895454
OS 33.80194662 9.65265278
OS 33.79732382 9.65635102
OS 33.79362558 9.6591247
OS 33.7908519 9.66189838
OS 33.78992734 9.66282294
OS 33.78900278 9.6637475
OS 33.7816063 9.6729931
OS 33.77420982 9.6822387
OS 33.7631151 9.70165446
OS 33.75571862 9.72107022
OS 33.75017126 9.73956142
OS 33.74647302 9.75527894
OS 33.74554846 9.76175086
OS 33.74554846 9.76822278
OS 33.7446239 9.77284558
OS 33.7446239 9.77654382
OS 33.7446239 9.77839294
OS 33.7446239 9.7793175
OS 33.74554846 9.79873326
OS 33.74832214 9.8162999
OS 33.75294494 9.83294198
OS 33.75756774 9.84681038
OS 33.7631151 9.85882966
OS 33.76681334 9.86807526
OS 33.77051158 9.87362262
OS 33.77143614 9.87454718
OS 33.77143614 9.87547174
OS 33.78253086 9.8902647
OS 33.79362558 9.90320854
OS 33.80564486 9.91430326
OS 33.81673958 9.9226243
OS 33.82690974 9.92909622
OS 33.83523078 9.93279446
OS 33.84077814 9.93556814
OS 33.8417027 9.9364927
OS 33.84262726 9.9364927
OS 33.8509483 9.93926638
OS 33.86111846 9.94204006
OS 33.88145878 9.94666286
OS 33.90364822 9.94943654
OS 33.92398854 9.95221022
OS 33.9434043 9.95313478
OS 33.95172534 9.95313478
OE
OB 33.42380158 9.95590846 I
OS 33.43397174 9.95683302
OS 33.45708574 9.95683302
OS 33.47002958 9.9549839
OS 33.4949927 9.9503611
OS 33.51625758 9.94296462
OS 33.53474878 9.93556814
OS 33.54306982 9.93094534
OS 33.54954174 9.9272471
OS 33.55601366 9.92354886
OS 33.56063646 9.91985062
OS 33.5643347 9.91707694
OS 33.56710838 9.91522782
OS 33.5689575 9.91430326
OS 33.56988206 9.9133787
OS 33.5874487 9.89581206
OS 33.6013171 9.8763963
OS 33.61241182 9.85605598
OS 33.62165742 9.83571566
OS 33.62720478 9.81814902
OS 33.62997846 9.81075254
OS 33.63182758 9.80428062
OS 33.63275214 9.79873326
OS 33.6336767 9.79503502
OS 33.63460126 9.79226134
OS 33.63460126 9.79133678
OS 33.55601366 9.77746838
OS 33.55231542 9.7978087
OS 33.54676806 9.81537534
OS 33.54029614 9.8301683
OS 33.53382422 9.84218758
OS 33.5273523 9.85143318
OS 33.52180494 9.8579051
OS 33.5181067 9.8625279
OS 33.51718214 9.86345246
OS 33.50516286 9.87269806
OS 33.49221902 9.88009454
OS 33.48019974 9.88471734
OS 33.46818046 9.88841558
OS 33.45708574 9.8902647
OS 33.4487647 9.89211382
OS 33.44136822 9.89211382
OS 33.42472614 9.89118926
OS 33.40993318 9.88749102
OS 33.39698934 9.88286822
OS 33.38589462 9.87824542
OS 33.37757358 9.87269806
OS 33.37110166 9.86807526
OS 33.36647886 9.86437702
OS 33.3655543 9.86345246
OS 33.35538414 9.85235774
OS 33.34798766 9.84033846
OS 33.34336486 9.82831918
OS 33.33966662 9.81722446
OS 33.3378175 9.8070543
OS 33.33596838 9.79965782
OS 33.33596838 9.79411046
OS 33.33596838 9.7931859
OS 33.33596838 9.79226134
OS 33.33596838 9.78209118
OS 33.3378175 9.77284558
OS 33.3424403 9.75712806
OS 33.34891222 9.74325966
OS 33.3563087 9.73124038
OS 33.36370518 9.72291934
OS 33.3701771 9.71644742
OS 33.3747999 9.71274918
OS 33.37572446 9.71182462
OS 33.37664902 9.71182462
OS 33.39236654 9.70350358
OS 33.4071595 9.69703166
OS 33.42287702 9.69240886
OS 33.43674542 9.68963518
OS 33.4487647 9.68778606
OS 33.45893486 9.68593694
OS 33.47095414 9.68593694
OS 33.47465238 9.6868615
OS 33.47927518 9.6868615
OS 33.48852078 9.6175195
OS 33.4765015 9.62029318
OS 33.46540678 9.6221423
OS 33.45616118 9.62399142
OS 33.44784014 9.62491598
OS 33.44136822 9.62584054
OS 33.43304718 9.62584054
OS 33.41363142 9.62399142
OS 33.39606478 9.62029318
OS 33.38034726 9.61474582
OS 33.36740342 9.6082739
OS 33.35723326 9.60180198
OS 33.34983678 9.59625462
OS 33.34521398 9.59255638
OS 33.34336486 9.59070726
OS 33.33134558 9.57683886
OS 33.32209998 9.5620459
OS 33.31562806 9.54725294
OS 33.31192982 9.53245998
OS 33.30915614 9.5204407
OS 33.30823158 9.51027054
OS 33.30730702 9.5065723
OS 33.30730702 9.50379862
OS 33.30730702 9.5019495
OS 33.30730702 9.50102494
OS 33.30915614 9.48068462
OS 33.31377894 9.46219342
OS 33.3193263 9.4464759
OS 33.32672278 9.4326075
OS 33.33411926 9.42151278
OS 33.33966662 9.41319174
OS 33.34428942 9.40764438
OS 33.34613854 9.40579526
OS 33.3609315 9.39285142
OS 33.37664902 9.38360582
OS 33.39236654 9.3771339
OS 33.4071595 9.3725111
OS 33.42010334 9.36973742
OS 33.4302735 9.36881286
OS 33.43397174 9.3678883
OS 33.4395191 9.3678883
OS 33.45616118 9.36881286
OS 33.4718787 9.3725111
OS 33.4857471 9.3771339
OS 33.49684182 9.38268126
OS 33.50608742 9.38730406
OS 33.5134839 9.39192686
OS 33.51718214 9.3956251
OS 33.51903126 9.39654966
OS 33.53012598 9.4094935
OS 33.53937158 9.42428646
OS 33.54769262 9.44000398
OS 33.55416454 9.45664606
OS 33.55878734 9.47051446
OS 33.56063646 9.47698638
OS 33.56156102 9.48253374
OS 33.56248558 9.48715654
OS 33.56341014 9.49085478
OS 33.5643347 9.4927039
OS 33.5643347 9.49362846
OS 33.6429223 9.4834583
OS 33.64107318 9.46866534
OS 33.6382995 9.45479694
OS 33.62997846 9.42890926
OS 33.6198083 9.40671982
OS 33.61426094 9.39747422
OS 33.60871358 9.38822862
OS 33.60316622 9.37990758
OS 33.59761886 9.37343566
OS 33.59299606 9.36696374
OS 33.58837326 9.36234094
OS 33.58559958 9.3586427
OS 33.5828259 9.35586902
OS 33.58097678 9.3540199
OS 33.58005222 9.35309534
OS 33.5689575 9.3447743
OS 33.55786278 9.33645326
OS 33.54676806 9.32998134
OS 33.53474878 9.32443398
OS 33.51163478 9.31518838
OS 33.48944534 9.30964102
OS 33.47927518 9.3077919
OS 33.47002958 9.30594278
OS 33.46170854 9.30501822
OS 33.45431206 9.30409366
OS 33.4487647 9.3031691
OS 33.44044366 9.3031691
OS 33.42287702 9.30409366
OS 33.4071595 9.30594278
OS 33.39144198 9.30871646
OS 33.37664902 9.3124147
OS 33.36278062 9.3170375
OS 33.35076134 9.3216603
OS 33.33874206 9.32720766
OS 33.3285719 9.33275502
OS 33.31840174 9.33737782
OS 33.3100807 9.34292518
OS 33.30268422 9.34754798
OS 33.29713686 9.35217078
OS 33.29251406 9.35586902
OS 33.28881582 9.3586427
OS 33.2869667 9.36049182
OS 33.28604214 9.36141638
OS 33.27494742 9.3725111
OS 33.26570182 9.38453038
OS 33.25738078 9.39654966
OS 33.2499843 9.40856894
OS 33.24443694 9.41966366
OS 33.23888958 9.43168294
OS 33.2314931 9.45387238
OS 33.22964398 9.46404254
OS 33.22779486 9.47328814
OS 33.22594574 9.48160918
OS 33.22502118 9.48900566
OS 33.22409662 9.49455302
OS 33.22409662 9.49917582
OS 33.22409662 9.5019495
OS 33.22409662 9.50287406
OS 33.22502118 9.5250635
OS 33.22871942 9.54540382
OS 33.23426678 9.56297046
OS 33.23981414 9.57776342
OS 33.2453615 9.5897827
OS 33.25090886 9.5990283
OS 33.2546071 9.60457566
OS 33.25553166 9.60642478
OS 33.2684755 9.62029318
OS 33.2823439 9.63231246
OS 33.29713686 9.64155806
OS 33.31192982 9.64895454
OS 33.32487366 9.6545019
OS 33.33504382 9.65820014
OS 33.33874206 9.6591247
OS 33.34151574 9.66004926
OS 33.34336486 9.66097382
OS 33.34428942 9.66097382
OS 33.3285719 9.66929486
OS 33.31562806 9.6776159
OS 33.30453334 9.6868615
OS 33.29528774 9.69518254
OS 33.28789126 9.70257902
OS 33.2823439 9.70905094
OS 33.27957022 9.71274918
OS 33.27864566 9.7145983
OS 33.27124918 9.72754214
OS 33.26570182 9.74048598
OS 33.26107902 9.75342982
OS 33.25830534 9.7654491
OS 33.25645622 9.77561926
OS 33.25553166 9.78301574
OS 33.25553166 9.7885631
OS 33.25553166 9.79041222
OS 33.25645622 9.80612974
OS 33.2592299 9.82184726
OS 33.26292814 9.83571566
OS 33.26755094 9.84773494
OS 33.27217374 9.8579051
OS 33.27587198 9.86622614
OS 33.27864566 9.87084894
OS 33.27957022 9.87269806
OS 33.28881582 9.88656646
OS 33.29991054 9.89858574
OS 33.31100526 9.9087559
OS 33.32209998 9.9180015
OS 33.33134558 9.92447342
OS 33.33966662 9.93002078
OS 33.34521398 9.93279446
OS 33.34613854 9.93371902
OS 33.3470631 9.93371902
OS 33.36370518 9.9411155
OS 33.38034726 9.94666286
OS 33.39698934 9.95128566
OS 33.4117823 9.95405934
OS 33.42380158 9.95590846
OE
OB 33.96929198 9.88286822 H
OS 33.94432886 9.88194366
OS 33.92306398 9.87824542
OS 33.90457278 9.87362262
OS 33.89070438 9.86807526
OS 33.8786851 9.8625279
OS 33.87128862 9.8579051
OS 33.86666582 9.85420686
OS 33.8648167 9.8532823
OS 33.85372198 9.84126302
OS 33.84540094 9.82924374
OS 33.83985358 9.8162999
OS 33.83523078 9.80520518
OS 33.83338166 9.79411046
OS 33.8324571 9.78578942
OS 33.83153254 9.78024206
OS 33.83153254 9.7793175
OS 33.83153254 9.77839294
OS 33.8324571 9.76729822
OS 33.83430622 9.7562035
OS 33.8370799 9.7469579
OS 33.83985358 9.73863686
OS 33.84355182 9.73124038
OS 33.8463255 9.72569302
OS 33.84817462 9.72199478
OS 33.84909918 9.72107022
OS 33.8555711 9.71182462
OS 33.86389214 9.70350358
OS 33.87221318 9.69703166
OS 33.88053422 9.6914843
OS 33.8879307 9.68778606
OS 33.89347806 9.68501238
OS 33.8971763 9.68316326
OS 33.89902542 9.6822387
OS 33.91196926 9.67854046
OS 33.92676222 9.67576678
OS 33.94155518 9.67391766
OS 33.95634814 9.6729931
OS 33.96929198 9.67206854
OS 33.9803867 9.67114398
OS 34.17084606 9.67114398
OS 34.17084606 9.88286822
OS 33.96929198 9.88286822
OE
SE
S P 0
OB 35.58552192 3.1640526 I
OS 35.58552192 3.60044492
OS 35.67058144 3.60044492
OS 35.67058144 3.1594298
OS 35.67058144 3.14001404
OS 35.67243056 3.12337196
OS 35.67335512 3.10950356
OS 35.67520424 3.09840884
OS 35.67705336 3.0900878
OS 35.67797792 3.08361588
OS 35.67982704 3.07991764
OS 35.67982704 3.07899308
OS 35.68352528 3.06974748
OS 35.68814808 3.062351
OS 35.69369544 3.05587908
OS 35.69831824 3.04940716
OS 35.7038656 3.04570892
OS 35.70756384 3.04201068
OS 35.71033752 3.04016156
OS 35.71126208 3.039237
OS 35.72050768 3.0346142
OS 35.72975328 3.03091596
OS 35.73899888 3.02906684
OS 35.74731992 3.02721772
OS 35.75564096 3.02629316
OS 35.76118832 3.0253686
OS 35.76673568 3.0253686
OS 35.78152864 3.02629316
OS 35.79539704 3.0299914
OS 35.80649176 3.03368964
OS 35.81666192 3.039237
OS 35.8240584 3.0438598
OS 35.82960576 3.0484826
OS 35.833304 3.05125628
OS 35.83422856 3.05218084
OS 35.83885136 3.0577282
OS 35.8425496 3.06420012
OS 35.84809696 3.07899308
OS 35.85364432 3.09563516
OS 35.856418 3.11227724
OS 35.85919168 3.12799476
OS 35.85919168 3.13446668
OS 35.86011624 3.14001404
OS 35.8610408 3.1455614
OS 35.8610408 3.14925964
OS 35.8610408 3.15110876
OS 35.8610408 3.15203332
OS 35.93777928 3.1409386
OS 35.93777928 3.12337196
OS 35.93685472 3.10765444
OS 35.93408104 3.09193692
OS 35.93223192 3.07806852
OS 35.92853368 3.06512468
OS 35.92483544 3.05402996
OS 35.9211372 3.04293524
OS 35.91743896 3.03368964
OS 35.91281616 3.0253686
OS 35.90911792 3.01797212
OS 35.90541968 3.0115002
OS 35.90172144 3.0068774
OS 35.89894776 3.00317916
OS 35.89709864 2.99948092
OS 35.89617408 2.99855636
OS 35.89524952 2.9976318
OS 35.88600392 2.98931076
OS 35.87675832 2.98191428
OS 35.86658816 2.97544236
OS 35.85549344 2.969895
OS 35.83422856 2.96157396
OS 35.81388824 2.9560266
OS 35.79447248 2.95232836
OS 35.787076 2.9514038
OS 35.77967952 2.95047924
OS 35.77413216 2.94955468
OS 35.76581112 2.94955468
OS 35.7454708 2.95047924
OS 35.7269796 2.95325292
OS 35.71033752 2.95695116
OS 35.69554456 2.96157396
OS 35.68352528 2.9652722
OS 35.67520424 2.96897044
OS 35.66965688 2.97174412
OS 35.66780776 2.97266868
OS 35.6530148 2.98191428
OS 35.64007096 2.993009
OS 35.6299008 3.00410372
OS 35.6206552 3.01427388
OS 35.61418328 3.02444404
OS 35.60956048 3.03184052
OS 35.6067868 3.03738788
OS 35.60586224 3.03831244
OS 35.60586224 3.039237
OS 35.59939032 3.0577282
OS 35.59384296 3.07714396
OS 35.59014472 3.09840884
OS 35.5882956 3.11874916
OS 35.58644648 3.1363158
OS 35.58644648 3.14371228
OS 35.58552192 3.15110876
OS 35.58552192 3.15665612
OS 35.58552192 3.16035436
OS 35.58552192 3.16312804
OS 35.58552192 3.1640526
OE
OB 35.1491296 3.18624204 I
OS 35.1491296 3.60044492
OS 35.21292424 3.60044492
OS 35.50600976 3.18624204
OS 35.50600976 3.11412636
OS 35.2277172 3.11412636
OS 35.2277172 2.9606494
OS 35.1491296 2.9606494
OS 35.1491296 3.11412636
OS 35.06222096 3.11412636
OS 35.06222096 3.18624204
OS 35.1491296 3.18624204
OE
OB 35.2277172 3.47285564 H
OS 35.2277172 3.18624204
OS 35.42927128 3.18624204
OS 35.2277172 3.47285564
OE
SE
S P 0
OB 40.23977982 10.27006836 I
OS 40.24625174 10.27099292
OS 40.25549734 10.27099292
OS 40.28600782 10.2691438
OS 40.31559374 10.264521
OS 40.34148142 10.25897364
OS 40.3535007 10.2552754
OS 40.36459542 10.25157716
OS 40.37476558 10.24787892
OS 40.38401118 10.24418068
OS 40.39140766 10.241407
OS 40.39880414 10.23863332
OS 40.40342694 10.23585964
OS 40.40712518 10.23401052
OS 40.40989886 10.23308596
OS 40.41082342 10.2321614
OS 40.43578654 10.21644388
OS 40.45705142 10.19795268
OS 40.47554262 10.17946148
OS 40.49126014 10.16097028
OS 40.50327942 10.1443282
OS 40.50790222 10.13693172
OS 40.51160046 10.1304598
OS 40.5152987 10.125837
OS 40.51714782 10.12213876
OS 40.51807238 10.11936508
OS 40.51899694 10.11844052
OS 40.53194078 10.08977916
OS 40.54118638 10.06019324
OS 40.5476583 10.03060732
OS 40.5522811 10.00379508
OS 40.55413022 9.9917758
OS 40.55505478 9.97975652
OS 40.55597934 9.97051092
OS 40.55597934 9.96126532
OS 40.5569039 9.9547934
OS 40.5569039 9.94924604
OS 40.5569039 9.9455478
OS 40.5569039 9.94462324
OS 40.55505478 9.91133908
OS 40.55135654 9.87897948
OS 40.54673374 9.85031812
OS 40.5430355 9.83644972
OS 40.54026182 9.82443044
OS 40.53748814 9.81333572
OS 40.5337899 9.80316556
OS 40.53101622 9.79391996
OS 40.5291671 9.78652348
OS 40.52639342 9.78097612
OS 40.52546886 9.77635332
OS 40.52361974 9.77357964
OS 40.52361974 9.77265508
OS 40.50975134 9.74491828
OS 40.49403382 9.71995516
OS 40.47739174 9.69869028
OS 40.4690707 9.69036924
OS 40.46167422 9.6820482
OS 40.45427774 9.67465172
OS 40.44688126 9.6681798
OS 40.44040934 9.66263244
OS 40.43486198 9.6589342
OS 40.43116374 9.65523596
OS 40.4274655 9.65246228
OS 40.42561638 9.65153772
OS 40.42469182 9.65061316
OS 40.41174798 9.64321668
OS 40.39880414 9.63674476
OS 40.37106734 9.6265746
OS 40.34333054 9.61917812
OS 40.3165183 9.61455532
OS 40.30357446 9.6127062
OS 40.29247974 9.61085708
OS 40.28230958 9.60993252
OS 40.27398854 9.60993252
OS 40.26659206 9.60900796
OS 40.2564219 9.60900796
OS 40.2379307 9.60993252
OS 40.22036406 9.61178164
OS 40.20372198 9.61363076
OS 40.18800446 9.617329
OS 40.1732115 9.6219518
OS 40.1593431 9.6265746
OS 40.14639926 9.6311974
OS 40.13437998 9.63674476
OS 40.12420982 9.64136756
OS 40.11403966 9.64599036
OS 40.10664318 9.65061316
OS 40.0992467 9.65523596
OS 40.0946239 9.6589342
OS 40.0900011 9.66078332
OS 40.08815198 9.66263244
OS 40.08722742 9.663557
OS 40.07428358 9.67465172
OS 40.06318886 9.68574644
OS 40.0530187 9.69869028
OS 40.04284854 9.71163412
OS 40.02620646 9.7375218
OS 40.01326262 9.76340948
OS 40.00771526 9.77542876
OS 40.00309246 9.78652348
OS 39.99939422 9.79669364
OS 39.99662054 9.80501468
OS 39.99384686 9.81241116
OS 39.99199774 9.81795852
OS 39.99107318 9.82165676
OS 39.99107318 9.82258132
OS 40.0761327 9.8438462
OS 40.07983094 9.82905324
OS 40.08445374 9.81518484
OS 40.08907654 9.802241
OS 40.09369934 9.79022172
OS 40.0992467 9.779127
OS 40.10479406 9.7698814
OS 40.11126598 9.7606358
OS 40.11681334 9.75231476
OS 40.12143614 9.74491828
OS 40.1269835 9.73937092
OS 40.1316063 9.73382356
OS 40.13530454 9.72920076
OS 40.13900278 9.72642708
OS 40.14177646 9.7236534
OS 40.14270102 9.72272884
OS 40.14362558 9.72180428
OS 40.15287118 9.7144078
OS 40.16304134 9.70886044
OS 40.18338166 9.69869028
OS 40.20279742 9.6912938
OS 40.22221318 9.686671
OS 40.23885526 9.68297276
OS 40.24532718 9.6820482
OS 40.2517991 9.6820482
OS 40.25734646 9.68112364
OS 40.26381838 9.68112364
OS 40.28508326 9.6820482
OS 40.30542358 9.68574644
OS 40.32391478 9.69036924
OS 40.34055686 9.6959166
OS 40.3535007 9.70146396
OS 40.35904806 9.70423764
OS 40.36367086 9.70608676
OS 40.3673691 9.70793588
OS 40.37014278 9.709785
OS 40.3719919 9.71070956
OS 40.37291646 9.71070956
OS 40.3904831 9.7236534
OS 40.40527606 9.7375218
OS 40.4182199 9.75323932
OS 40.42839006 9.76803228
OS 40.4367111 9.78097612
OS 40.44225846 9.79207084
OS 40.44410758 9.79669364
OS 40.4459567 9.79946732
OS 40.44688126 9.80131644
OS 40.44688126 9.802241
OS 40.45427774 9.82627956
OS 40.4598251 9.85031812
OS 40.4644479 9.87435668
OS 40.46722158 9.89654612
OS 40.46814614 9.90671628
OS 40.4690707 9.91596188
OS 40.4690707 9.92428292
OS 40.46999526 9.93075484
OS 40.46999526 9.9363022
OS 40.46999526 9.940925
OS 40.46999526 9.94369868
OS 40.46999526 9.94462324
OS 40.4690707 9.9686618
OS 40.46722158 9.99085124
OS 40.46352334 10.01119156
OS 40.4598251 10.02968276
OS 40.45705142 10.04540028
OS 40.4552023 10.0518722
OS 40.45335318 10.05741956
OS 40.45242862 10.06204236
OS 40.45150406 10.06481604
OS 40.4505795 10.06666516
OS 40.4505795 10.06758972
OS 40.4413339 10.0888546
OS 40.43116374 10.10827036
OS 40.42006902 10.12398788
OS 40.40804974 10.13785628
OS 40.39787958 10.148951
OS 40.38955854 10.15634748
OS 40.38308662 10.16097028
OS 40.38216206 10.1628194
OS 40.3812375 10.1628194
OS 40.36182174 10.17483868
OS 40.34055686 10.18408428
OS 40.32021654 10.1905562
OS 40.30080078 10.19425444
OS 40.28323414 10.19702812
OS 40.27583766 10.19795268
OS 40.26936574 10.19795268
OS 40.26474294 10.19887724
OS 40.25734646 10.19887724
OS 40.23423246 10.19795268
OS 40.21296758 10.19425444
OS 40.19540094 10.18870708
OS 40.17968342 10.18315972
OS 40.16766414 10.1766878
OS 40.15841854 10.172065
OS 40.15287118 10.16836676
OS 40.15102206 10.16651764
OS 40.1362291 10.15264924
OS 40.1223607 10.13693172
OS 40.11126598 10.12028964
OS 40.10202038 10.10364756
OS 40.0946239 10.0888546
OS 40.09185022 10.08145812
OS 40.0900011 10.07591076
OS 40.08815198 10.07128796
OS 40.08630286 10.06758972
OS 40.0853783 10.0657406
OS 40.0853783 10.06481604
OS 40.0021679 10.0842318
OS 40.00771526 10.10087388
OS 40.01326262 10.11566684
OS 40.0206591 10.12953524
OS 40.02713102 10.14340364
OS 40.0345275 10.15542292
OS 40.04284854 10.16651764
OS 40.05024502 10.17761236
OS 40.0576415 10.18685796
OS 40.06503798 10.19425444
OS 40.0715099 10.20165092
OS 40.07798182 10.20812284
OS 40.08260462 10.21274564
OS 40.08722742 10.21736844
OS 40.09092566 10.22014212
OS 40.09277478 10.22106668
OS 40.09369934 10.22199124
OS 40.10664318 10.23031228
OS 40.11958702 10.23863332
OS 40.13253086 10.24510524
OS 40.14639926 10.2506526
OS 40.17413606 10.25897364
OS 40.19909918 10.264521
OS 40.21111846 10.26729468
OS 40.22128862 10.26821924
OS 40.23145878 10.2691438
OS 40.23977982 10.27006836
OE
OB 39.6230983 9.62010268 I
OS 39.6230983 10.26267188
OS 39.6739491 10.26267188
OS 39.6831947 10.24695436
OS 39.69336486 10.2321614
OS 39.70538414 10.21736844
OS 39.71647886 10.2044246
OS 39.72757358 10.19332988
OS 39.73589462 10.18408428
OS 39.73959286 10.1813106
OS 39.74236654 10.17853692
OS 39.7432911 10.17761236
OS 39.74421566 10.1766878
OS 39.76363142 10.16097028
OS 39.78304718 10.14617732
OS 39.80153838 10.13323348
OS 39.82002958 10.12306332
OS 39.8357471 10.11381772
OS 39.84221902 10.11011948
OS 39.84776638 10.1073458
OS 39.85238918 10.10457212
OS 39.85608742 10.10364756
OS 39.85793654 10.10179844
OS 39.8588611 10.10179844
OS 39.8588611 10.02598452
OS 39.8449927 10.03153188
OS 39.8311243 10.0380038
OS 39.8172559 10.04447572
OS 39.80431206 10.05094764
OS 39.79321734 10.056495
OS 39.78397174 10.0611178
OS 39.77842438 10.06481604
OS 39.77749982 10.0657406
OS 39.77657526 10.0657406
OS 39.75993318 10.07591076
OS 39.74514022 10.08608092
OS 39.73219638 10.09532652
OS 39.72202622 10.10364756
OS 39.71278062 10.11011948
OS 39.70723326 10.11566684
OS 39.70261046 10.11936508
OS 39.7016859 10.12028964
OS 39.7016859 9.62010268
OS 39.6230983 9.62010268
OE
SE
S P 0
OB 40.83347688 2.15758522 I
OS 40.84734528 2.15850978
OS 41.10992032 2.15850978
OS 41.10992032 1.51871426
OS 41.0248608 1.51871426
OS 41.0248608 1.77851562
OS 40.86121368 1.77851562
OS 40.83717512 1.77944018
OS 40.81406112 1.7812893
OS 40.7937208 1.78406298
OS 40.7752296 1.78776122
OS 40.75766296 1.79145946
OS 40.74287 1.79608226
OS 40.7290016 1.80162962
OS 40.71698232 1.80717698
OS 40.70681216 1.81179978
OS 40.69756656 1.81734714
OS 40.69017008 1.82196994
OS 40.68462272 1.82659274
OS 40.67999992 1.82936642
OS 40.67722624 1.8321401
OS 40.67537712 1.83398922
OS 40.67445256 1.83491378
OS 40.66520696 1.8460085
OS 40.65688592 1.85710322
OS 40.650414 1.86819794
OS 40.64394208 1.88021722
OS 40.63839472 1.8922365
OS 40.63469648 1.90333122
OS 40.62822456 1.9245961
OS 40.62637544 1.93476626
OS 40.62452632 1.94401186
OS 40.62360176 1.9523329
OS 40.6226772 1.95880482
OS 40.62175264 1.96527674
OS 40.62175264 1.96897498
OS 40.62175264 1.97174866
OS 40.62175264 1.97267322
OS 40.6226772 1.99023986
OS 40.62452632 2.00688194
OS 40.62822456 2.0216749
OS 40.63099824 2.03461874
OS 40.63469648 2.04571346
OS 40.63839472 2.0540345
OS 40.64024384 2.0586573
OS 40.6411684 2.06050642
OS 40.64856488 2.07437482
OS 40.65781048 2.0863941
OS 40.66613152 2.09748882
OS 40.67445256 2.10580986
OS 40.68184904 2.11228178
OS 40.6873964 2.11782914
OS 40.69109464 2.12060282
OS 40.69294376 2.12152738
OS 40.70496304 2.12892386
OS 40.71883144 2.13539578
OS 40.73177528 2.14094314
OS 40.74379456 2.14556594
OS 40.75488928 2.14833962
OS 40.76321032 2.15018874
OS 40.76968224 2.15203786
OS 40.77153136 2.15203786
OS 40.78539976 2.15388698
OS 40.80111728 2.1557361
OS 40.81775936 2.15666066
OS 40.83347688 2.15758522
OE
OB 40.25007952 1.51871426 I
OS 40.25007952 2.16128346
OS 40.30093032 2.16128346
OS 40.31017592 2.14556594
OS 40.32034608 2.13077298
OS 40.33236536 2.11598002
OS 40.34346008 2.10303618
OS 40.3545548 2.09194146
OS 40.36287584 2.08269586
OS 40.36657408 2.07992218
OS 40.36934776 2.0771485
OS 40.37027232 2.07622394
OS 40.37119688 2.07529938
OS 40.39061264 2.05958186
OS 40.4100284 2.0447889
OS 40.4285196 2.03184506
OS 40.4470108 2.0216749
OS 40.46272832 2.0124293
OS 40.46920024 2.00873106
OS 40.4747476 2.00595738
OS 40.4793704 2.0031837
OS 40.48306864 2.00225914
OS 40.48491776 2.00041002
OS 40.48584232 2.00041002
OS 40.48584232 1.9245961
OS 40.47197392 1.93014346
OS 40.45810552 1.93661538
OS 40.44423712 1.9430873
OS 40.43129328 1.94955922
OS 40.42019856 1.95510658
OS 40.41095296 1.95972938
OS 40.4054056 1.96342762
OS 40.40448104 1.96435218
OS 40.40355648 1.96435218
OS 40.3869144 1.97452234
OS 40.37212144 1.9846925
OS 40.3591776 1.9939381
OS 40.34900744 2.00225914
OS 40.33976184 2.00873106
OS 40.33421448 2.01427842
OS 40.32959168 2.01797666
OS 40.32866712 2.01890122
OS 40.32866712 1.51871426
OS 40.25007952 1.51871426
OE
OB 40.84179792 2.08269586 H
OS 40.82515584 2.0817713
OS 40.81128744 2.08084674
OS 40.80019272 2.07992218
OS 40.79279624 2.07807306
OS 40.78724888 2.0771485
OS 40.78355064 2.07622394
OS 40.78262608 2.07622394
OS 40.7706068 2.07160114
OS 40.76043664 2.06605378
OS 40.75119104 2.06050642
OS 40.74287 2.0540345
OS 40.73732264 2.04756258
OS 40.73269984 2.04293978
OS 40.72992616 2.03924154
OS 40.7290016 2.03831698
OS 40.72252968 2.02722226
OS 40.71698232 2.01612754
OS 40.71328408 2.00410826
OS 40.71143496 1.9939381
OS 40.70958584 1.9846925
OS 40.70866128 1.97637146
OS 40.70866128 1.97174866
OS 40.70866128 1.9708241
OS 40.70866128 1.96989954
OS 40.7105104 1.95048378
OS 40.71420864 1.9338417
OS 40.719756 1.91904874
OS 40.72622792 1.90702946
OS 40.73269984 1.89778386
OS 40.7382472 1.89038738
OS 40.74194544 1.88668914
OS 40.74379456 1.88484002
OS 40.75026648 1.87929266
OS 40.75858752 1.87466986
OS 40.77615416 1.86727338
OS 40.79556992 1.86172602
OS 40.81498568 1.85802778
OS 40.83255232 1.85617866
OS 40.8399488 1.8552541
OS 40.84642072 1.8552541
OS 40.85289264 1.85432954
OS 41.0248608 1.85432954
OS 41.0248608 2.08269586
OS 40.84179792 2.08269586
OE
SE
S P 0
OB 40.89218644 22.64533444 I
OS 40.90605484 22.646259
OS 41.16862988 22.646259
OS 41.16862988 22.00646348
OS 41.08357036 22.00646348
OS 41.08357036 22.26626484
OS 40.91992324 22.26626484
OS 40.89588468 22.2671894
OS 40.87277068 22.26903852
OS 40.85243036 22.2718122
OS 40.83393916 22.27551044
OS 40.81637252 22.27920868
OS 40.80157956 22.28383148
OS 40.78771116 22.28937884
OS 40.77569188 22.2949262
OS 40.76552172 22.299549
OS 40.75627612 22.30509636
OS 40.74887964 22.30971916
OS 40.74333228 22.31434196
OS 40.73870948 22.31711564
OS 40.7359358 22.31988932
OS 40.73408668 22.32173844
OS 40.73316212 22.322663
OS 40.72391652 22.33375772
OS 40.71559548 22.34485244
OS 40.70912356 22.35594716
OS 40.70265164 22.36796644
OS 40.69710428 22.37998572
OS 40.69340604 22.39108044
OS 40.68693412 22.41234532
OS 40.685085 22.42251548
OS 40.68323588 22.43176108
OS 40.68231132 22.44008212
OS 40.68138676 22.44655404
OS 40.6804622 22.45302596
OS 40.6804622 22.4567242
OS 40.6804622 22.45949788
OS 40.6804622 22.46042244
OS 40.68138676 22.47798908
OS 40.68323588 22.49463116
OS 40.68693412 22.50942412
OS 40.6897078 22.52236796
OS 40.69340604 22.53346268
OS 40.69710428 22.54178372
OS 40.6989534 22.54640652
OS 40.69987796 22.54825564
OS 40.70727444 22.56212404
OS 40.71652004 22.57414332
OS 40.72484108 22.58523804
OS 40.73316212 22.59355908
OS 40.7405586 22.600031
OS 40.74610596 22.60557836
OS 40.7498042 22.60835204
OS 40.75165332 22.6092766
OS 40.7636726 22.61667308
OS 40.777541 22.623145
OS 40.79048484 22.62869236
OS 40.80250412 22.63331516
OS 40.81359884 22.63608884
OS 40.82191988 22.63793796
OS 40.8283918 22.63978708
OS 40.83024092 22.63978708
OS 40.84410932 22.6416362
OS 40.85982684 22.64348532
OS 40.87646892 22.64440988
OS 40.89218644 22.64533444
OE
OB 40.37720652 22.64810812 I
OS 40.38367844 22.64903268
OS 40.39292404 22.64903268
OS 40.40956612 22.64810812
OS 40.42528364 22.64718356
OS 40.4400766 22.64440988
OS 40.453945 22.6416362
OS 40.46688884 22.63793796
OS 40.47890812 22.63423972
OS 40.49000284 22.62961692
OS 40.500173 22.62499412
OS 40.5094186 22.62037132
OS 40.51681508 22.61574852
OS 40.523287 22.61205028
OS 40.52883436 22.60835204
OS 40.53345716 22.60557836
OS 40.53623084 22.60280468
OS 40.53807996 22.60188012
OS 40.53900452 22.60095556
OS 40.54825012 22.59170996
OS 40.55657116 22.5815398
OS 40.5648922 22.57044508
OS 40.57136412 22.55935036
OS 40.58245884 22.53716092
OS 40.58985532 22.51497148
OS 40.592629 22.50480132
OS 40.59540268 22.49463116
OS 40.5972518 22.48631012
OS 40.59910092 22.47891364
OS 40.60002548 22.47244172
OS 40.60002548 22.46781892
OS 40.60095004 22.46504524
OS 40.60095004 22.46412068
OS 40.52051332 22.45579964
OS 40.5186642 22.47706452
OS 40.51496596 22.49555572
OS 40.5094186 22.5121978
OS 40.50294668 22.52514164
OS 40.49739932 22.53623636
OS 40.49185196 22.54363284
OS 40.48815372 22.54825564
OS 40.4863046 22.55010476
OS 40.4724362 22.56119948
OS 40.45764324 22.56952052
OS 40.44192572 22.57599244
OS 40.42805732 22.57969068
OS 40.41511348 22.58246436
OS 40.40401876 22.58338892
OS 40.40032052 22.58431348
OS 40.39477316 22.58431348
OS 40.3753574 22.58338892
OS 40.35779076 22.57969068
OS 40.3429978 22.57414332
OS 40.33005396 22.56859596
OS 40.3198838 22.56212404
OS 40.31341188 22.55750124
OS 40.30878908 22.553803
OS 40.30693996 22.55195388
OS 40.29584524 22.53901004
OS 40.2875242 22.5260662
OS 40.28105228 22.51312236
OS 40.27735404 22.50017852
OS 40.27458036 22.49000836
OS 40.2736558 22.48076276
OS 40.27273124 22.4752154
OS 40.27273124 22.47429084
OS 40.27273124 22.47336628
OS 40.27458036 22.4567242
OS 40.2782786 22.43915756
OS 40.28475052 22.42344004
OS 40.29122244 22.40864708
OS 40.29861892 22.3966278
OS 40.30509084 22.38645764
OS 40.30693996 22.3827594
OS 40.30878908 22.37998572
OS 40.3106382 22.37906116
OS 40.3106382 22.3781366
OS 40.31803468 22.36796644
OS 40.32728028 22.35779628
OS 40.33745044 22.34670156
OS 40.34854516 22.33560684
OS 40.37165916 22.3134174
OS 40.39477316 22.29122796
OS 40.40679244 22.2810578
OS 40.4169626 22.2718122
OS 40.42713276 22.26349116
OS 40.4354538 22.25609468
OS 40.44192572 22.25054732
OS 40.44747308 22.24592452
OS 40.45117132 22.24315084
OS 40.45209588 22.24222628
OS 40.47520988 22.22281052
OS 40.49647476 22.20431932
OS 40.5140414 22.18767724
OS 40.5279098 22.17380884
OS 40.53992908 22.16178956
OS 40.54825012 22.15346852
OS 40.55287292 22.14792116
OS 40.55472204 22.1469966
OS 40.55472204 22.14607204
OS 40.56766588 22.13035452
OS 40.57783604 22.11556156
OS 40.58708164 22.1007686
OS 40.59447812 22.08782476
OS 40.60002548 22.07673004
OS 40.60372372 22.068409
OS 40.60557284 22.06286164
OS 40.6064974 22.06193708
OS 40.6064974 22.06101252
OS 40.61019564 22.05084236
OS 40.61204476 22.04159676
OS 40.61389388 22.03235116
OS 40.61481844 22.02403012
OS 40.615743 22.01663364
OS 40.615743 22.01108628
OS 40.615743 22.00738804
OS 40.615743 22.00646348
OS 40.19136996 22.00646348
OS 40.19136996 22.0822774
OS 40.50664492 22.0822774
OS 40.4955502 22.09799492
OS 40.49000284 22.10446684
OS 40.48538004 22.11093876
OS 40.48075724 22.11648612
OS 40.477059 22.12018436
OS 40.47428532 22.12295804
OS 40.47336076 22.1238826
OS 40.46873796 22.1285054
OS 40.4631906 22.1331282
OS 40.45024676 22.14514748
OS 40.4354538 22.15901588
OS 40.41973628 22.17288428
OS 40.40494332 22.18490356
OS 40.3984714 22.19045092
OS 40.39292404 22.19599828
OS 40.38830124 22.19969652
OS 40.384603 22.2024702
OS 40.38275388 22.20431932
OS 40.38182932 22.20524388
OS 40.36703636 22.21818772
OS 40.3522434 22.230207
OS 40.33929956 22.24222628
OS 40.32728028 22.25239644
OS 40.31618556 22.2625666
OS 40.30693996 22.2718122
OS 40.29769436 22.28013324
OS 40.29029788 22.28752972
OS 40.2829014 22.2949262
OS 40.27735404 22.30047356
OS 40.27273124 22.30509636
OS 40.26810844 22.30971916
OS 40.26348564 22.31526652
OS 40.26163652 22.31711564
OS 40.24869268 22.33283316
OS 40.23759796 22.34670156
OS 40.22835236 22.36056996
OS 40.22095588 22.37166468
OS 40.21540852 22.38183484
OS 40.21171028 22.38923132
OS 40.20986116 22.39385412
OS 40.2089366 22.39570324
OS 40.20338924 22.40957164
OS 40.199691 22.42344004
OS 40.19599276 22.43638388
OS 40.19414364 22.4474786
OS 40.19321908 22.45764876
OS 40.19229452 22.46504524
OS 40.19229452 22.46966804
OS 40.19229452 22.47151716
OS 40.19321908 22.48538556
OS 40.1950682 22.4983294
OS 40.19691732 22.51127324
OS 40.20061556 22.52236796
OS 40.20986116 22.5445574
OS 40.21910676 22.56212404
OS 40.22465412 22.57044508
OS 40.22927692 22.576917
OS 40.23389972 22.58338892
OS 40.23852252 22.58801172
OS 40.24222076 22.59170996
OS 40.24406988 22.5954082
OS 40.245919 22.59633276
OS 40.24684356 22.59725732
OS 40.25701372 22.60650292
OS 40.26810844 22.61482396
OS 40.28012772 22.62129588
OS 40.292147 22.62684324
OS 40.31618556 22.63608884
OS 40.34022412 22.64256076
OS 40.35039428 22.64440988
OS 40.36056444 22.646259
OS 40.36981004 22.64718356
OS 40.37720652 22.64810812
OE
OB 40.90050748 22.57044508 H
OS 40.8838654 22.56952052
OS 40.869997 22.56859596
OS 40.85890228 22.5676714
OS 40.8515058 22.56582228
OS 40.84595844 22.56489772
OS 40.8422602 22.56397316
OS 40.84133564 22.56397316
OS 40.82931636 22.55935036
OS 40.8191462 22.553803
OS 40.8099006 22.54825564
OS 40.80157956 22.54178372
OS 40.7960322 22.5353118
OS 40.7914094 22.530689
OS 40.78863572 22.52699076
OS 40.78771116 22.5260662
OS 40.78123924 22.51497148
OS 40.77569188 22.50387676
OS 40.77199364 22.49185748
OS 40.77014452 22.48168732
OS 40.7682954 22.47244172
OS 40.76737084 22.46412068
OS 40.76737084 22.45949788
OS 40.76737084 22.45857332
OS 40.76737084 22.45764876
OS 40.76921996 22.438233
OS 40.7729182 22.42159092
OS 40.77846556 22.40679796
OS 40.78493748 22.39477868
OS 40.7914094 22.38553308
OS 40.79695676 22.3781366
OS 40.800655 22.37443836
OS 40.80250412 22.37258924
OS 40.80897604 22.36704188
OS 40.81729708 22.36241908
OS 40.83486372 22.3550226
OS 40.85427948 22.34947524
OS 40.87369524 22.345777
OS 40.89126188 22.34392788
OS 40.89865836 22.34300332
OS 40.90513028 22.34300332
OS 40.9116022 22.34207876
OS 41.08357036 22.34207876
OS 41.08357036 22.57044508
OS 40.90050748 22.57044508
OE
SE
S P 0
OB 40.8954224 43.08813328 I
OS 40.9092908 43.08905784
OS 41.17186584 43.08905784
OS 41.17186584 42.44926232
OS 41.08680632 42.44926232
OS 41.08680632 42.70906368
OS 40.9231592 42.70906368
OS 40.89912064 42.70998824
OS 40.87600664 42.71183736
OS 40.85566632 42.71461104
OS 40.83717512 42.71830928
OS 40.81960848 42.72200752
OS 40.80481552 42.72663032
OS 40.79094712 42.73217768
OS 40.77892784 42.73772504
OS 40.76875768 42.74234784
OS 40.75951208 42.7478952
OS 40.7521156 42.752518
OS 40.74656824 42.7571408
OS 40.74194544 42.75991448
OS 40.73917176 42.76268816
OS 40.73732264 42.76453728
OS 40.73639808 42.76546184
OS 40.72715248 42.77655656
OS 40.71883144 42.78765128
OS 40.71235952 42.798746
OS 40.7058876 42.81076528
OS 40.70034024 42.82278456
OS 40.696642 42.83387928
OS 40.69017008 42.85514416
OS 40.68832096 42.86531432
OS 40.68647184 42.87455992
OS 40.68554728 42.88288096
OS 40.68462272 42.88935288
OS 40.68369816 42.8958248
OS 40.68369816 42.89952304
OS 40.68369816 42.90229672
OS 40.68369816 42.90322128
OS 40.68462272 42.92078792
OS 40.68647184 42.93743
OS 40.69017008 42.95222296
OS 40.69294376 42.9651668
OS 40.696642 42.97626152
OS 40.70034024 42.98458256
OS 40.70218936 42.98920536
OS 40.70311392 42.99105448
OS 40.7105104 43.00492288
OS 40.719756 43.01694216
OS 40.72807704 43.02803688
OS 40.73639808 43.03635792
OS 40.74379456 43.04282984
OS 40.74934192 43.0483772
OS 40.75304016 43.05115088
OS 40.75488928 43.05207544
OS 40.76690856 43.05947192
OS 40.78077696 43.06594384
OS 40.7937208 43.0714912
OS 40.80574008 43.076114
OS 40.8168348 43.07888768
OS 40.82515584 43.0807368
OS 40.83162776 43.08258592
OS 40.83347688 43.08258592
OS 40.84734528 43.08443504
OS 40.8630628 43.08628416
OS 40.87970488 43.08720872
OS 40.8954224 43.08813328
OE
OB 40.38783896 43.09090696 I
OS 40.39800912 43.09183152
OS 40.42112312 43.09183152
OS 40.43406696 43.0899824
OS 40.45903008 43.0853596
OS 40.48029496 43.07796312
OS 40.49878616 43.07056664
OS 40.5071072 43.06594384
OS 40.51357912 43.0622456
OS 40.52005104 43.05854736
OS 40.52467384 43.05484912
OS 40.52837208 43.05207544
OS 40.53114576 43.05022632
OS 40.53299488 43.04930176
OS 40.53391944 43.0483772
OS 40.55148608 43.03081056
OS 40.56535448 43.0113948
OS 40.5764492 42.99105448
OS 40.5856948 42.97071416
OS 40.59124216 42.95314752
OS 40.59401584 42.94575104
OS 40.59586496 42.93927912
OS 40.59678952 42.93373176
OS 40.59771408 42.93003352
OS 40.59863864 42.92725984
OS 40.59863864 42.92633528
OS 40.52005104 42.91246688
OS 40.5163528 42.9328072
OS 40.51080544 42.95037384
OS 40.50433352 42.9651668
OS 40.4978616 42.97718608
OS 40.49138968 42.98643168
OS 40.48584232 42.9929036
OS 40.48214408 42.9975264
OS 40.48121952 42.99845096
OS 40.46920024 43.00769656
OS 40.4562564 43.01509304
OS 40.44423712 43.01971584
OS 40.43221784 43.02341408
OS 40.42112312 43.0252632
OS 40.41280208 43.02711232
OS 40.4054056 43.02711232
OS 40.38876352 43.02618776
OS 40.37397056 43.02248952
OS 40.36102672 43.01786672
OS 40.349932 43.01324392
OS 40.34161096 43.00769656
OS 40.33513904 43.00307376
OS 40.33051624 42.99937552
OS 40.32959168 42.99845096
OS 40.31942152 42.98735624
OS 40.31202504 42.97533696
OS 40.30740224 42.96331768
OS 40.303704 42.95222296
OS 40.30185488 42.9420528
OS 40.30000576 42.93465632
OS 40.30000576 42.92910896
OS 40.30000576 42.9281844
OS 40.30000576 42.92725984
OS 40.30000576 42.91708968
OS 40.30185488 42.90784408
OS 40.30647768 42.89212656
OS 40.3129496 42.87825816
OS 40.32034608 42.86623888
OS 40.32774256 42.85791784
OS 40.33421448 42.85144592
OS 40.33883728 42.84774768
OS 40.33976184 42.84682312
OS 40.3406864 42.84682312
OS 40.35640392 42.83850208
OS 40.37119688 42.83203016
OS 40.3869144 42.82740736
OS 40.4007828 42.82463368
OS 40.41280208 42.82278456
OS 40.42297224 42.82093544
OS 40.43499152 42.82093544
OS 40.43868976 42.82186
OS 40.44331256 42.82186
OS 40.45255816 42.752518
OS 40.44053888 42.75529168
OS 40.42944416 42.7571408
OS 40.42019856 42.75898992
OS 40.41187752 42.75991448
OS 40.4054056 42.76083904
OS 40.39708456 42.76083904
OS 40.3776688 42.75898992
OS 40.36010216 42.75529168
OS 40.34438464 42.74974432
OS 40.3314408 42.7432724
OS 40.32127064 42.73680048
OS 40.31387416 42.73125312
OS 40.30925136 42.72755488
OS 40.30740224 42.72570576
OS 40.29538296 42.71183736
OS 40.28613736 42.6970444
OS 40.27966544 42.68225144
OS 40.2759672 42.66745848
OS 40.27319352 42.6554392
OS 40.27226896 42.64526904
OS 40.2713444 42.6415708
OS 40.2713444 42.63879712
OS 40.2713444 42.636948
OS 40.2713444 42.63602344
OS 40.27319352 42.61568312
OS 40.27781632 42.59719192
OS 40.28336368 42.5814744
OS 40.29076016 42.567606
OS 40.29815664 42.55651128
OS 40.303704 42.54819024
OS 40.3083268 42.54264288
OS 40.31017592 42.54079376
OS 40.32496888 42.52784992
OS 40.3406864 42.51860432
OS 40.35640392 42.5121324
OS 40.37119688 42.5075096
OS 40.38414072 42.50473592
OS 40.39431088 42.50381136
OS 40.39800912 42.5028868
OS 40.40355648 42.5028868
OS 40.42019856 42.50381136
OS 40.43591608 42.5075096
OS 40.44978448 42.5121324
OS 40.4608792 42.51767976
OS 40.4701248 42.52230256
OS 40.47752128 42.52692536
OS 40.48121952 42.5306236
OS 40.48306864 42.53154816
OS 40.49416336 42.544492
OS 40.50340896 42.55928496
OS 40.51173 42.57500248
OS 40.51820192 42.59164456
OS 40.52282472 42.60551296
OS 40.52467384 42.61198488
OS 40.5255984 42.61753224
OS 40.52652296 42.62215504
OS 40.52744752 42.62585328
OS 40.52837208 42.6277024
OS 40.52837208 42.62862696
OS 40.60695968 42.6184568
OS 40.60511056 42.60366384
OS 40.60233688 42.58979544
OS 40.59401584 42.56390776
OS 40.58384568 42.54171832
OS 40.57829832 42.53247272
OS 40.57275096 42.52322712
OS 40.5672036 42.51490608
OS 40.56165624 42.50843416
OS 40.55703344 42.50196224
OS 40.55241064 42.49733944
OS 40.54963696 42.4936412
OS 40.54686328 42.49086752
OS 40.54501416 42.4890184
OS 40.5440896 42.48809384
OS 40.53299488 42.4797728
OS 40.52190016 42.47145176
OS 40.51080544 42.46497984
OS 40.49878616 42.45943248
OS 40.47567216 42.45018688
OS 40.45348272 42.44463952
OS 40.44331256 42.4427904
OS 40.43406696 42.44094128
OS 40.42574592 42.44001672
OS 40.41834944 42.43909216
OS 40.41280208 42.4381676
OS 40.40448104 42.4381676
OS 40.3869144 42.43909216
OS 40.37119688 42.44094128
OS 40.35547936 42.44371496
OS 40.3406864 42.4474132
OS 40.326818 42.452036
OS 40.31479872 42.4566588
OS 40.30277944 42.46220616
OS 40.29260928 42.46775352
OS 40.28243912 42.47237632
OS 40.27411808 42.47792368
OS 40.2667216 42.48254648
OS 40.26117424 42.48716928
OS 40.25655144 42.49086752
OS 40.2528532 42.4936412
OS 40.25100408 42.49549032
OS 40.25007952 42.49641488
OS 40.2389848 42.5075096
OS 40.2297392 42.51952888
OS 40.22141816 42.53154816
OS 40.21402168 42.54356744
OS 40.20847432 42.55466216
OS 40.20292696 42.56668144
OS 40.19553048 42.58887088
OS 40.19368136 42.59904104
OS 40.19183224 42.60828664
OS 40.18998312 42.61660768
OS 40.18905856 42.62400416
OS 40.188134 42.62955152
OS 40.188134 42.63417432
OS 40.188134 42.636948
OS 40.188134 42.63787256
OS 40.18905856 42.660062
OS 40.1927568 42.68040232
OS 40.19830416 42.69796896
OS 40.20385152 42.71276192
OS 40.20939888 42.7247812
OS 40.21494624 42.7340268
OS 40.21864448 42.73957416
OS 40.21956904 42.74142328
OS 40.23251288 42.75529168
OS 40.24638128 42.76731096
OS 40.26117424 42.77655656
OS 40.2759672 42.78395304
OS 40.28891104 42.7895004
OS 40.2990812 42.79319864
OS 40.30277944 42.7941232
OS 40.30555312 42.79504776
OS 40.30740224 42.79597232
OS 40.3083268 42.79597232
OS 40.29260928 42.80429336
OS 40.27966544 42.8126144
OS 40.26857072 42.82186
OS 40.25932512 42.83018104
OS 40.25192864 42.83757752
OS 40.24638128 42.84404944
OS 40.2436076 42.84774768
OS 40.24268304 42.8495968
OS 40.23528656 42.86254064
OS 40.2297392 42.87548448
OS 40.2251164 42.88842832
OS 40.22234272 42.9004476
OS 40.2204936 42.91061776
OS 40.21956904 42.91801424
OS 40.21956904 42.9235616
OS 40.21956904 42.92541072
OS 40.2204936 42.94112824
OS 40.22326728 42.95684576
OS 40.22696552 42.97071416
OS 40.23158832 42.98273344
OS 40.23621112 42.9929036
OS 40.23990936 43.00122464
OS 40.24268304 43.00584744
OS 40.2436076 43.00769656
OS 40.2528532 43.02156496
OS 40.26394792 43.03358424
OS 40.27504264 43.0437544
OS 40.28613736 43.053
OS 40.29538296 43.05947192
OS 40.303704 43.06501928
OS 40.30925136 43.06779296
OS 40.31017592 43.06871752
OS 40.31110048 43.06871752
OS 40.32774256 43.076114
OS 40.34438464 43.08166136
OS 40.36102672 43.08628416
OS 40.37581968 43.08905784
OS 40.38783896 43.09090696
OE
OB 40.90374344 43.01324392 H
OS 40.88710136 43.01231936
OS 40.87323296 43.0113948
OS 40.86213824 43.01047024
OS 40.85474176 43.00862112
OS 40.8491944 43.00769656
OS 40.84549616 43.006772
OS 40.8445716 43.006772
OS 40.83255232 43.0021492
OS 40.82238216 42.99660184
OS 40.81313656 42.99105448
OS 40.80481552 42.98458256
OS 40.79926816 42.97811064
OS 40.79464536 42.97348784
OS 40.79187168 42.9697896
OS 40.79094712 42.96886504
OS 40.7844752 42.95777032
OS 40.77892784 42.9466756
OS 40.7752296 42.93465632
OS 40.77338048 42.92448616
OS 40.77153136 42.91524056
OS 40.7706068 42.90691952
OS 40.7706068 42.90229672
OS 40.7706068 42.90137216
OS 40.7706068 42.9004476
OS 40.77245592 42.88103184
OS 40.77615416 42.86438976
OS 40.78170152 42.8495968
OS 40.78817344 42.83757752
OS 40.79464536 42.82833192
OS 40.80019272 42.82093544
OS 40.80389096 42.8172372
OS 40.80574008 42.81538808
OS 40.812212 42.80984072
OS 40.82053304 42.80521792
OS 40.83809968 42.79782144
OS 40.85751544 42.79227408
OS 40.8769312 42.78857584
OS 40.89449784 42.78672672
OS 40.90189432 42.78580216
OS 40.90836624 42.78580216
OS 40.91483816 42.7848776
OS 41.08680632 42.7848776
OS 41.08680632 43.01324392
OS 40.90374344 43.01324392
OE
SE
S P 0
OB 41.56870528 16.28258618 I
OS 41.57610176 16.28351074
OS 41.87288552 16.28351074
OS 41.87288552 15.64371522
OS 41.787826 15.64371522
OS 41.787826 15.92755514
OS 41.67872792 15.92755514
OS 41.66855776 15.92663058
OS 41.66116128 15.92663058
OS 41.65468936 15.92570602
OS 41.65006656 15.92478146
OS 41.64636832 15.92478146
OS 41.6445192 15.9238569
OS 41.64359464 15.9238569
OS 41.62880168 15.9192341
OS 41.62232976 15.91646042
OS 41.6167824 15.91368674
OS 41.61123504 15.91091306
OS 41.6075368 15.90906394
OS 41.60568768 15.90813938
OS 41.60476312 15.90721482
OS 41.59736664 15.90166746
OS 41.58997016 15.89519554
OS 41.57610176 15.88132714
OS 41.56962984 15.87485522
OS 41.56500704 15.86930786
OS 41.56223336 15.86560962
OS 41.5613088 15.86468506
OS 41.5520632 15.85174122
OS 41.54189304 15.83787282
OS 41.53172288 15.82307986
OS 41.52155272 15.80921146
OS 41.51323168 15.79626762
OS 41.50675976 15.78609746
OS 41.50398608 15.78239922
OS 41.50213696 15.77962554
OS 41.50028784 15.77777642
OS 41.50028784 15.77685186
OS 41.41615288 15.64371522
OS 41.31075304 15.64371522
OS 41.42077568 15.8175325
OS 41.43371952 15.8360237
OS 41.4457388 15.85266578
OS 41.45775808 15.86653418
OS 41.46792824 15.87947802
OS 41.47717384 15.88872362
OS 41.48457032 15.8961201
OS 41.48919312 15.9007429
OS 41.49104224 15.90259202
OS 41.49843872 15.90813938
OS 41.50675976 15.9146113
OS 41.52340184 15.92478146
OS 41.53079832 15.9284797
OS 41.53634568 15.93217794
OS 41.54004392 15.93402706
OS 41.54189304 15.93495162
OS 41.52525096 15.9377253
OS 41.50953344 15.94049898
OS 41.49566504 15.94512178
OS 41.48179664 15.94882002
OS 41.46977736 15.95344282
OS 41.45868264 15.95899018
OS 41.44851248 15.96361298
OS 41.43926688 15.96823578
OS 41.4318704 15.97378314
OS 41.42447392 15.97840594
OS 41.41892656 15.98210418
OS 41.41430376 15.98580242
OS 41.41060552 15.9885761
OS 41.40783184 15.99134978
OS 41.40690728 15.99227434
OS 41.40598272 15.9931989
OS 41.39858624 16.0024445
OS 41.39118976 16.0116901
OS 41.38009504 16.03110586
OS 41.37269856 16.05052162
OS 41.3671512 16.06901282
OS 41.36345296 16.08473034
OS 41.3625284 16.09120226
OS 41.3625284 16.09767418
OS 41.36160384 16.10229698
OS 41.36160384 16.10599522
OS 41.36160384 16.10784434
OS 41.36160384 16.1087689
OS 41.3625284 16.12818466
OS 41.36530208 16.1457513
OS 41.36992488 16.16239338
OS 41.37454768 16.17626178
OS 41.38009504 16.18828106
OS 41.38379328 16.19752666
OS 41.38749152 16.20307402
OS 41.38841608 16.20399858
OS 41.38841608 16.20492314
OS 41.3995108 16.2197161
OS 41.41060552 16.23265994
OS 41.4226248 16.24375466
OS 41.43371952 16.2520757
OS 41.44388968 16.25854762
OS 41.45221072 16.26224586
OS 41.45775808 16.26501954
OS 41.45868264 16.2659441
OS 41.4596072 16.2659441
OS 41.46792824 16.26871778
OS 41.4780984 16.27149146
OS 41.49843872 16.27611426
OS 41.52062816 16.27888794
OS 41.54096848 16.28166162
OS 41.56038424 16.28258618
OS 41.56870528 16.28258618
OE
OB 40.9649676 15.64371522 I
OS 40.9649676 16.28628442
OS 41.0158184 16.28628442
OS 41.025064 16.2705669
OS 41.03523416 16.25577394
OS 41.04725344 16.24098098
OS 41.05834816 16.22803714
OS 41.06944288 16.21694242
OS 41.07776392 16.20769682
OS 41.08146216 16.20492314
OS 41.08423584 16.20214946
OS 41.0851604 16.2012249
OS 41.08608496 16.20030034
OS 41.10550072 16.18458282
OS 41.12491648 16.16978986
OS 41.14340768 16.15684602
OS 41.16189888 16.14667586
OS 41.1776164 16.13743026
OS 41.18408832 16.13373202
OS 41.18963568 16.13095834
OS 41.19425848 16.12818466
OS 41.19795672 16.1272601
OS 41.19980584 16.12541098
OS 41.2007304 16.12541098
OS 41.2007304 16.04959706
OS 41.186862 16.05514442
OS 41.1729936 16.06161634
OS 41.1591252 16.06808826
OS 41.14618136 16.07456018
OS 41.13508664 16.08010754
OS 41.12584104 16.08473034
OS 41.12029368 16.08842858
OS 41.11936912 16.08935314
OS 41.11844456 16.08935314
OS 41.10180248 16.0995233
OS 41.08700952 16.10969346
OS 41.07406568 16.11893906
OS 41.06389552 16.1272601
OS 41.05464992 16.13373202
OS 41.04910256 16.13927938
OS 41.04447976 16.14297762
OS 41.0435552 16.14390218
OS 41.0435552 15.64371522
OS 40.9649676 15.64371522
OE
OB 41.58627192 16.21231962 H
OS 41.5613088 16.21139506
OS 41.54004392 16.20769682
OS 41.52155272 16.20307402
OS 41.50768432 16.19752666
OS 41.49566504 16.1919793
OS 41.48826856 16.1873565
OS 41.48364576 16.18365826
OS 41.48179664 16.1827337
OS 41.47070192 16.17071442
OS 41.46238088 16.15869514
OS 41.45683352 16.1457513
OS 41.45221072 16.13465658
OS 41.4503616 16.12356186
OS 41.44943704 16.11524082
OS 41.44851248 16.10969346
OS 41.44851248 16.1087689
OS 41.44851248 16.10784434
OS 41.44943704 16.09674962
OS 41.45128616 16.0856549
OS 41.45405984 16.0764093
OS 41.45683352 16.06808826
OS 41.46053176 16.06069178
OS 41.46330544 16.05514442
OS 41.46515456 16.05144618
OS 41.46607912 16.05052162
OS 41.47255104 16.04127602
OS 41.48087208 16.03295498
OS 41.48919312 16.02648306
OS 41.49751416 16.0209357
OS 41.50491064 16.01723746
OS 41.510458 16.01446378
OS 41.51415624 16.01261466
OS 41.51600536 16.0116901
OS 41.5289492 16.00799186
OS 41.54374216 16.00521818
OS 41.55853512 16.00336906
OS 41.57332808 16.0024445
OS 41.58627192 16.00151994
OS 41.59736664 16.00059538
OS 41.787826 16.00059538
OS 41.787826 16.21231962
OS 41.58627192 16.21231962
OE
SE
S P 0
OB 41.74848902 8.43006696 I
OS 41.75496094 8.43099152
OS 41.76420654 8.43099152
OS 41.79471702 8.4291424
OS 41.82430294 8.4245196
OS 41.85019062 8.41897224
OS 41.8622099 8.415274
OS 41.87330462 8.41157576
OS 41.88347478 8.40787752
OS 41.89272038 8.40417928
OS 41.90011686 8.4014056
OS 41.90751334 8.39863192
OS 41.91213614 8.39585824
OS 41.91583438 8.39400912
OS 41.91860806 8.39308456
OS 41.91953262 8.39216
OS 41.94449574 8.37644248
OS 41.96576062 8.35795128
OS 41.98425182 8.33946008
OS 41.99996934 8.32096888
OS 42.01198862 8.3043268
OS 42.01661142 8.29693032
OS 42.02030966 8.2904584
OS 42.0240079 8.2858356
OS 42.02585702 8.28213736
OS 42.02678158 8.27936368
OS 42.02770614 8.27843912
OS 42.04064998 8.24977776
OS 42.04989558 8.22019184
OS 42.0563675 8.19060592
OS 42.0609903 8.16379368
OS 42.06283942 8.1517744
OS 42.06376398 8.13975512
OS 42.06468854 8.13050952
OS 42.06468854 8.12126392
OS 42.0656131 8.114792
OS 42.0656131 8.10924464
OS 42.0656131 8.1055464
OS 42.0656131 8.10462184
OS 42.06376398 8.07133768
OS 42.06006574 8.03897808
OS 42.05544294 8.01031672
OS 42.0517447 7.99644832
OS 42.04897102 7.98442904
OS 42.04619734 7.97333432
OS 42.0424991 7.96316416
OS 42.03972542 7.95391856
OS 42.0378763 7.94652208
OS 42.03510262 7.94097472
OS 42.03417806 7.93635192
OS 42.03232894 7.93357824
OS 42.03232894 7.93265368
OS 42.01846054 7.90491688
OS 42.00274302 7.87995376
OS 41.98610094 7.85868888
OS 41.9777799 7.85036784
OS 41.97038342 7.8420468
OS 41.96298694 7.83465032
OS 41.95559046 7.8281784
OS 41.94911854 7.82263104
OS 41.94357118 7.8189328
OS 41.93987294 7.81523456
OS 41.9361747 7.81246088
OS 41.93432558 7.81153632
OS 41.93340102 7.81061176
OS 41.92045718 7.80321528
OS 41.90751334 7.79674336
OS 41.87977654 7.7865732
OS 41.85203974 7.77917672
OS 41.8252275 7.77455392
OS 41.81228366 7.7727048
OS 41.80118894 7.77085568
OS 41.79101878 7.76993112
OS 41.78269774 7.76993112
OS 41.77530126 7.76900656
OS 41.7651311 7.76900656
OS 41.7466399 7.76993112
OS 41.72907326 7.77178024
OS 41.71243118 7.77362936
OS 41.69671366 7.7773276
OS 41.6819207 7.7819504
OS 41.6680523 7.7865732
OS 41.65510846 7.791196
OS 41.64308918 7.79674336
OS 41.63291902 7.80136616
OS 41.62274886 7.80598896
OS 41.61535238 7.81061176
OS 41.6079559 7.81523456
OS 41.6033331 7.8189328
OS 41.5987103 7.82078192
OS 41.59686118 7.82263104
OS 41.59593662 7.8235556
OS 41.58299278 7.83465032
OS 41.57189806 7.84574504
OS 41.5617279 7.85868888
OS 41.55155774 7.87163272
OS 41.53491566 7.8975204
OS 41.52197182 7.92340808
OS 41.51642446 7.93542736
OS 41.51180166 7.94652208
OS 41.50810342 7.95669224
OS 41.50532974 7.96501328
OS 41.50255606 7.97240976
OS 41.50070694 7.97795712
OS 41.49978238 7.98165536
OS 41.49978238 7.98257992
OS 41.5848419 8.0038448
OS 41.58854014 7.98905184
OS 41.59316294 7.97518344
OS 41.59778574 7.9622396
OS 41.60240854 7.95022032
OS 41.6079559 7.9391256
OS 41.61350326 7.92988
OS 41.61997518 7.9206344
OS 41.62552254 7.91231336
OS 41.63014534 7.90491688
OS 41.6356927 7.89936952
OS 41.6403155 7.89382216
OS 41.64401374 7.88919936
OS 41.64771198 7.88642568
OS 41.65048566 7.883652
OS 41.65141022 7.88272744
OS 41.65233478 7.88180288
OS 41.66158038 7.8744064
OS 41.67175054 7.86885904
OS 41.69209086 7.85868888
OS 41.71150662 7.8512924
OS 41.73092238 7.8466696
OS 41.74756446 7.84297136
OS 41.75403638 7.8420468
OS 41.7605083 7.8420468
OS 41.76605566 7.84112224
OS 41.77252758 7.84112224
OS 41.79379246 7.8420468
OS 41.81413278 7.84574504
OS 41.83262398 7.85036784
OS 41.84926606 7.8559152
OS 41.8622099 7.86146256
OS 41.86775726 7.86423624
OS 41.87238006 7.86608536
OS 41.8760783 7.86793448
OS 41.87885198 7.8697836
OS 41.8807011 7.87070816
OS 41.88162566 7.87070816
OS 41.8991923 7.883652
OS 41.91398526 7.8975204
OS 41.9269291 7.91323792
OS 41.93709926 7.92803088
OS 41.9454203 7.94097472
OS 41.95096766 7.95206944
OS 41.95281678 7.95669224
OS 41.9546659 7.95946592
OS 41.95559046 7.96131504
OS 41.95559046 7.9622396
OS 41.96298694 7.98627816
OS 41.9685343 8.01031672
OS 41.9731571 8.03435528
OS 41.97593078 8.05654472
OS 41.97685534 8.06671488
OS 41.9777799 8.07596048
OS 41.9777799 8.08428152
OS 41.97870446 8.09075344
OS 41.97870446 8.0963008
OS 41.97870446 8.1009236
OS 41.97870446 8.10369728
OS 41.97870446 8.10462184
OS 41.9777799 8.1286604
OS 41.97593078 8.15084984
OS 41.97223254 8.17119016
OS 41.9685343 8.18968136
OS 41.96576062 8.20539888
OS 41.9639115 8.2118708
OS 41.96206238 8.21741816
OS 41.96113782 8.22204096
OS 41.96021326 8.22481464
OS 41.9592887 8.22666376
OS 41.9592887 8.22758832
OS 41.9500431 8.2488532
OS 41.93987294 8.26826896
OS 41.92877822 8.28398648
OS 41.91675894 8.29785488
OS 41.90658878 8.3089496
OS 41.89826774 8.31634608
OS 41.89179582 8.32096888
OS 41.89087126 8.322818
OS 41.8899467 8.322818
OS 41.87053094 8.33483728
OS 41.84926606 8.34408288
OS 41.82892574 8.3505548
OS 41.80950998 8.35425304
OS 41.79194334 8.35702672
OS 41.78454686 8.35795128
OS 41.77807494 8.35795128
OS 41.77345214 8.35887584
OS 41.76605566 8.35887584
OS 41.74294166 8.35795128
OS 41.72167678 8.35425304
OS 41.70411014 8.34870568
OS 41.68839262 8.34315832
OS 41.67637334 8.3366864
OS 41.66712774 8.3320636
OS 41.66158038 8.32836536
OS 41.65973126 8.32651624
OS 41.6449383 8.31264784
OS 41.6310699 8.29693032
OS 41.61997518 8.28028824
OS 41.61072958 8.26364616
OS 41.6033331 8.2488532
OS 41.60055942 8.24145672
OS 41.5987103 8.23590936
OS 41.59686118 8.23128656
OS 41.59501206 8.22758832
OS 41.5940875 8.2257392
OS 41.5940875 8.22481464
OS 41.5108771 8.2442304
OS 41.51642446 8.26087248
OS 41.52197182 8.27566544
OS 41.5293683 8.28953384
OS 41.53584022 8.30340224
OS 41.5432367 8.31542152
OS 41.55155774 8.32651624
OS 41.55895422 8.33761096
OS 41.5663507 8.34685656
OS 41.57374718 8.35425304
OS 41.5802191 8.36164952
OS 41.58669102 8.36812144
OS 41.59131382 8.37274424
OS 41.59593662 8.37736704
OS 41.59963486 8.38014072
OS 41.60148398 8.38106528
OS 41.60240854 8.38198984
OS 41.61535238 8.39031088
OS 41.62829622 8.39863192
OS 41.64124006 8.40510384
OS 41.65510846 8.4106512
OS 41.68284526 8.41897224
OS 41.70780838 8.4245196
OS 41.71982766 8.42729328
OS 41.72999782 8.42821784
OS 41.74016798 8.4291424
OS 41.74848902 8.43006696
OE
OB 41.20022494 8.42174592 I
OS 41.20669686 8.42267048
OS 41.21594246 8.42267048
OS 41.23258454 8.42174592
OS 41.24830206 8.42082136
OS 41.26309502 8.41804768
OS 41.27696342 8.415274
OS 41.28990726 8.41157576
OS 41.30192654 8.40787752
OS 41.31302126 8.40325472
OS 41.32319142 8.39863192
OS 41.33243702 8.39400912
OS 41.3398335 8.38938632
OS 41.34630542 8.38568808
OS 41.35185278 8.38198984
OS 41.35647558 8.37921616
OS 41.35924926 8.37644248
OS 41.36109838 8.37551792
OS 41.36202294 8.37459336
OS 41.37126854 8.36534776
OS 41.37958958 8.3551776
OS 41.38791062 8.34408288
OS 41.39438254 8.33298816
OS 41.40547726 8.31079872
OS 41.41287374 8.28860928
OS 41.41564742 8.27843912
OS 41.4184211 8.26826896
OS 41.42027022 8.25994792
OS 41.42211934 8.25255144
OS 41.4230439 8.24607952
OS 41.4230439 8.24145672
OS 41.42396846 8.23868304
OS 41.42396846 8.23775848
OS 41.34353174 8.22943744
OS 41.34168262 8.25070232
OS 41.33798438 8.26919352
OS 41.33243702 8.2858356
OS 41.3259651 8.29877944
OS 41.32041774 8.30987416
OS 41.31487038 8.31727064
OS 41.31117214 8.32189344
OS 41.30932302 8.32374256
OS 41.29545462 8.33483728
OS 41.28066166 8.34315832
OS 41.26494414 8.34963024
OS 41.25107574 8.35332848
OS 41.2381319 8.35610216
OS 41.22703718 8.35702672
OS 41.22333894 8.35795128
OS 41.21779158 8.35795128
OS 41.19837582 8.35702672
OS 41.18080918 8.35332848
OS 41.16601622 8.34778112
OS 41.15307238 8.34223376
OS 41.14290222 8.33576184
OS 41.1364303 8.33113904
OS 41.1318075 8.3274408
OS 41.12995838 8.32559168
OS 41.11886366 8.31264784
OS 41.11054262 8.299704
OS 41.1040707 8.28676016
OS 41.10037246 8.27381632
OS 41.09759878 8.26364616
OS 41.09667422 8.25440056
OS 41.09574966 8.2488532
OS 41.09574966 8.24792864
OS 41.09574966 8.24700408
OS 41.09759878 8.230362
OS 41.10129702 8.21279536
OS 41.10776894 8.19707784
OS 41.11424086 8.18228488
OS 41.12163734 8.1702656
OS 41.12810926 8.16009544
OS 41.12995838 8.1563972
OS 41.1318075 8.15362352
OS 41.13365662 8.15269896
OS 41.13365662 8.1517744
OS 41.1410531 8.14160424
OS 41.1502987 8.13143408
OS 41.16046886 8.12033936
OS 41.17156358 8.10924464
OS 41.19467758 8.0870552
OS 41.21779158 8.06486576
OS 41.22981086 8.0546956
OS 41.23998102 8.04545
OS 41.25015118 8.03712896
OS 41.25847222 8.02973248
OS 41.26494414 8.02418512
OS 41.2704915 8.01956232
OS 41.27418974 8.01678864
OS 41.2751143 8.01586408
OS 41.2982283 7.99644832
OS 41.31949318 7.97795712
OS 41.33705982 7.96131504
OS 41.35092822 7.94744664
OS 41.3629475 7.93542736
OS 41.37126854 7.92710632
OS 41.37589134 7.92155896
OS 41.37774046 7.9206344
OS 41.37774046 7.91970984
OS 41.3906843 7.90399232
OS 41.40085446 7.88919936
OS 41.41010006 7.8744064
OS 41.41749654 7.86146256
OS 41.4230439 7.85036784
OS 41.42674214 7.8420468
OS 41.42859126 7.83649944
OS 41.42951582 7.83557488
OS 41.42951582 7.83465032
OS 41.43321406 7.82448016
OS 41.43506318 7.81523456
OS 41.4369123 7.80598896
OS 41.43783686 7.79766792
OS 41.43876142 7.79027144
OS 41.43876142 7.78472408
OS 41.43876142 7.78102584
OS 41.43876142 7.78010128
OS 41.01438838 7.78010128
OS 41.01438838 7.8559152
OS 41.32966334 7.8559152
OS 41.31856862 7.87163272
OS 41.31302126 7.87810464
OS 41.30839846 7.88457656
OS 41.30377566 7.89012392
OS 41.30007742 7.89382216
OS 41.29730374 7.89659584
OS 41.29637918 7.8975204
OS 41.29175638 7.9021432
OS 41.28620902 7.906766
OS 41.27326518 7.91878528
OS 41.25847222 7.93265368
OS 41.2427547 7.94652208
OS 41.22796174 7.95854136
OS 41.22148982 7.96408872
OS 41.21594246 7.96963608
OS 41.21131966 7.97333432
OS 41.20762142 7.976108
OS 41.2057723 7.97795712
OS 41.20484774 7.97888168
OS 41.19005478 7.99182552
OS 41.17526182 8.0038448
OS 41.16231798 8.01586408
OS 41.1502987 8.02603424
OS 41.13920398 8.0362044
OS 41.12995838 8.04545
OS 41.12071278 8.05377104
OS 41.1133163 8.06116752
OS 41.10591982 8.068564
OS 41.10037246 8.07411136
OS 41.09574966 8.07873416
OS 41.09112686 8.08335696
OS 41.08650406 8.08890432
OS 41.08465494 8.09075344
OS 41.0717111 8.10647096
OS 41.06061638 8.12033936
OS 41.05137078 8.13420776
OS 41.0439743 8.14530248
OS 41.03842694 8.15547264
OS 41.0347287 8.16286912
OS 41.03287958 8.16749192
OS 41.03195502 8.16934104
OS 41.02640766 8.18320944
OS 41.02270942 8.19707784
OS 41.01901118 8.21002168
OS 41.01716206 8.2211164
OS 41.0162375 8.23128656
OS 41.01531294 8.23868304
OS 41.01531294 8.24330584
OS 41.01531294 8.24515496
OS 41.0162375 8.25902336
OS 41.01808662 8.2719672
OS 41.01993574 8.28491104
OS 41.02363398 8.29600576
OS 41.03287958 8.3181952
OS 41.04212518 8.33576184
OS 41.04767254 8.34408288
OS 41.05229534 8.3505548
OS 41.05691814 8.35702672
OS 41.06154094 8.36164952
OS 41.06523918 8.36534776
OS 41.0670883 8.369046
OS 41.06893742 8.36997056
OS 41.06986198 8.37089512
OS 41.08003214 8.38014072
OS 41.09112686 8.38846176
OS 41.10314614 8.39493368
OS 41.11516542 8.40048104
OS 41.13920398 8.40972664
OS 41.16324254 8.41619856
OS 41.1734127 8.41804768
OS 41.18358286 8.4198968
OS 41.19282846 8.42082136
OS 41.20022494 8.42174592
OE
SE
S P 0
OB 48.49040086 -36.61402634 I
OS 48.17420134 -36.61402634
OS 48.17420134 -37.45999874
OS 48.04661206 -37.45999874
OS 48.04661206 -36.61402634
OS 47.73041254 -36.61402634
OS 47.73041254 -36.50030546
OS 48.49040086 -36.50030546
OS 48.49040086 -36.61402634
OE
OB 47.69990206 -37.45999874 I
OS 47.5556707 -37.45999874
OS 47.44333666 -37.16876234
OS 47.04115306 -37.16876234
OS 46.93714006 -37.45999874
OS 46.80261658 -37.45999874
OS 47.16874234 -36.50030546
OS 47.30742634 -36.50030546
OS 47.69990206 -37.45999874
OE
OB 49.31834434 -36.61402634 I
OS 48.75112678 -36.61402634
OS 48.75112678 -36.90664958
OS 49.2822865 -36.90664958
OS 49.2822865 -37.02037046
OS 48.75112678 -37.02037046
OS 48.75112678 -37.34627786
OS 49.34053378 -37.34627786
OS 49.34053378 -37.45999874
OS 48.6235375 -37.45999874
OS 48.6235375 -36.50030546
OS 49.31834434 -36.50030546
OS 49.31834434 -36.61402634
OE
OB 46.33386466 -36.5016923 I
OS 46.36160146 -36.50307914
OS 46.38933826 -36.50585282
OS 46.41707506 -36.51001334
OS 46.44065134 -36.51417386
OS 46.44203818 -36.51417386
OS 46.44481186 -36.5155607
OS 46.44897238 -36.5155607
OS 46.45451974 -36.51833438
OS 46.46977498 -36.5224949
OS 46.48919074 -36.5294291
OS 46.51138018 -36.53913698
OS 46.53495646 -36.55161854
OS 46.55853274 -36.56548694
OS 46.58072218 -36.58351586
OS 46.58210902 -36.5849027
OS 46.58349586 -36.58628954
OS 46.58765638 -36.59045006
OS 46.59320374 -36.59461058
OS 46.60707214 -36.60847898
OS 46.62371422 -36.62789474
OS 46.64174314 -36.65147102
OS 46.6611589 -36.67920782
OS 46.67918782 -36.71110514
OS 46.69444306 -36.74716298
OS 46.69444306 -36.74854982
OS 46.6958299 -36.7513235
OS 46.69860358 -36.75687086
OS 46.69999042 -36.7651919
OS 46.70415094 -36.77489978
OS 46.70692462 -36.7859945
OS 46.7096983 -36.79847606
OS 46.71385882 -36.8137313
OS 46.71801934 -36.82898654
OS 46.72079302 -36.84701546
OS 46.72772722 -36.88584698
OS 46.73188774 -36.92883902
OS 46.73327458 -36.97599158
OS 46.73327458 -36.97737842
OS 46.73327458 -36.9801521
OS 46.73327458 -36.9870863
OS 46.73327458 -36.9940205
OS 46.73188774 -37.00372838
OS 46.73188774 -37.0148231
OS 46.7305009 -37.04117306
OS 46.72634038 -37.07168354
OS 46.72217986 -37.10358086
OS 46.71524566 -37.13686502
OS 46.70692462 -37.17014918
OS 46.70692462 -37.17153602
OS 46.70553778 -37.1743097
OS 46.70415094 -37.17847022
OS 46.7027641 -37.18401758
OS 46.69721674 -37.19927282
OS 46.6888957 -37.21868858
OS 46.68057466 -37.24087802
OS 46.66947994 -37.26306746
OS 46.65561154 -37.28664374
OS 46.64174314 -37.30883318
OS 46.6403563 -37.31160686
OS 46.63480894 -37.31854106
OS 46.6264879 -37.32824894
OS 46.61539318 -37.3407305
OS 46.60291162 -37.3545989
OS 46.58765638 -37.3684673
OS 46.57240114 -37.38372254
OS 46.55437222 -37.3962041
OS 46.55159854 -37.39759094
OS 46.54605118 -37.40175146
OS 46.5363433 -37.40729882
OS 46.5224749 -37.41423302
OS 46.50583282 -37.42255406
OS 46.48641706 -37.42948826
OS 46.46422762 -37.4378093
OS 46.4392645 -37.4447435
OS 46.43649082 -37.4447435
OS 46.4323303 -37.44613034
OS 46.42816978 -37.44751718
OS 46.41430138 -37.44890402
OS 46.39488562 -37.4516777
OS 46.37269618 -37.45445138
OS 46.34634622 -37.45722506
OS 46.31722258 -37.4586119
OS 46.28532526 -37.45999874
OS 45.9400021 -37.45999874
OS 45.9400021 -36.50030546
OS 46.30890154 -36.50030546
OS 46.33386466 -36.5016923
OE
OB 46.28948578 -36.61402634 H
OS 46.06759138 -36.61402634
OS 46.06759138 -37.34627786
OS 46.29503314 -37.34627786
OS 46.30474102 -37.34489102
OS 46.32554362 -37.34350418
OS 46.3491199 -37.34211734
OS 46.37408302 -37.33934366
OS 46.39904614 -37.33518314
OS 46.41984874 -37.32963578
OS 46.42262242 -37.32824894
OS 46.42955662 -37.3268621
OS 46.4392645 -37.32270158
OS 46.45174606 -37.31715422
OS 46.46561446 -37.30883318
OS 46.47948286 -37.30051214
OS 46.49335126 -37.29080426
OS 46.50721966 -37.27970954
OS 46.5086065 -37.27693586
OS 46.51415386 -37.2713885
OS 46.5224749 -37.26168062
OS 46.53218278 -37.24781222
OS 46.5432775 -37.2297833
OS 46.55575906 -37.2089807
OS 46.56685378 -37.18540442
OS 46.57656166 -37.15905446
OS 46.57656166 -37.15766762
OS 46.5779485 -37.15489394
OS 46.57933534 -37.15073342
OS 46.58072218 -37.14518606
OS 46.58210902 -37.13825186
OS 46.5848827 -37.12854398
OS 46.58765638 -37.1188361
OS 46.59043006 -37.10774138
OS 46.59459058 -37.08000458
OS 46.5987511 -37.04810726
OS 46.60152478 -37.01204942
OS 46.60291162 -36.9732179
OS 46.60291162 -36.97183106
OS 46.60291162 -36.9662837
OS 46.60291162 -36.9593495
OS 46.60152478 -36.94825478
OS 46.60152478 -36.93577322
OS 46.60013794 -36.92190482
OS 46.5987511 -36.90526274
OS 46.59736426 -36.88862066
OS 46.59043006 -36.85117598
OS 46.58210902 -36.81234446
OS 46.56962746 -36.77628662
OS 46.56130642 -36.7582577
OS 46.55298538 -36.74300246
OS 46.55298538 -36.74161562
OS 46.5502117 -36.73884194
OS 46.54743802 -36.73468142
OS 46.54466434 -36.72913406
OS 46.53356962 -36.71526566
OS 46.51970122 -36.69862358
OS 46.5016723 -36.68059466
OS 46.4808697 -36.66256574
OS 46.45729342 -36.6473105
OS 46.4323303 -36.63482894
OS 46.42955662 -36.6334421
OS 46.42262242 -36.63205526
OS 46.41014086 -36.62789474
OS 46.39211194 -36.62373422
OS 46.3699225 -36.62096054
OS 46.3421857 -36.61680002
OS 46.32554362 -36.61541318
OS 46.3075147 -36.61541318
OS 46.28948578 -36.61402634
OE
OB 47.23531066 -36.60015794 H
OS 47.23531066 -36.60154478
OS 47.23392382 -36.60431846
OS 47.23392382 -36.60986582
OS 47.23115014 -36.61541318
OS 47.2297633 -36.62512106
OS 47.22698962 -36.63482894
OS 47.22144226 -36.65840522
OS 47.21450806 -36.68614202
OS 47.20480018 -36.7166525
OS 47.1950923 -36.74993666
OS 47.18261074 -36.78460766
OS 47.07859774 -37.06474934
OS 47.4031183 -37.06474934
OS 47.30326582 -36.80124974
OS 47.30326582 -36.7998629
OS 47.30187898 -36.79570238
OS 47.2991053 -36.78876818
OS 47.29633162 -36.78044714
OS 47.2921711 -36.77073926
OS 47.28801058 -36.7582577
OS 47.28385006 -36.7443893
OS 47.2783027 -36.7305209
OS 47.26720798 -36.69862358
OS 47.25611326 -36.66533942
OS 47.24501854 -36.63205526
OS 47.23531066 -36.60015794
OE
SE
S P 0
OB 53.57408132 -38.30725892 I
OS 53.5861006 -38.30910804
OS 53.60089356 -38.31188172
OS 53.61753564 -38.31650452
OS 53.63417772 -38.32205188
OS 53.6508198 -38.32944836
OS 53.65174436 -38.32944836
OS 53.65266892 -38.33037292
OS 53.65821628 -38.3331466
OS 53.66653732 -38.33869396
OS 53.67578292 -38.34516588
OS 53.68687764 -38.35441148
OS 53.69797236 -38.36458164
OS 53.70906708 -38.37660092
OS 53.71831268 -38.39046932
OS 53.71923724 -38.39231844
OS 53.72201092 -38.39694124
OS 53.72570916 -38.40526228
OS 53.73033196 -38.41543244
OS 53.73495476 -38.42745172
OS 53.738653 -38.44132012
OS 53.74142668 -38.45703764
OS 53.74235124 -38.47275516
OS 53.74235124 -38.47460428
OS 53.74235124 -38.48015164
OS 53.74142668 -38.48754812
OS 53.73957756 -38.49771828
OS 53.73680388 -38.50973756
OS 53.73218108 -38.5226814
OS 53.72663372 -38.53562524
OS 53.71923724 -38.54856908
OS 53.71831268 -38.5504182
OS 53.715539 -38.55411644
OS 53.70999164 -38.56058836
OS 53.70259516 -38.56798484
OS 53.69334956 -38.57630588
OS 53.68225484 -38.58555148
OS 53.669311 -38.59387252
OS 53.65359348 -38.60219356
OS 53.65451804 -38.60219356
OS 53.65636716 -38.60311812
OS 53.65914084 -38.60404268
OS 53.66283908 -38.60496724
OS 53.67300924 -38.60866548
OS 53.68595308 -38.61421284
OS 53.70074604 -38.62160932
OS 53.715539 -38.63085492
OS 53.7294074 -38.6428742
OS 53.74235124 -38.6567426
OS 53.7432758 -38.65859172
OS 53.74697404 -38.66413908
OS 53.7525214 -38.67338468
OS 53.75806876 -38.68540396
OS 53.76361612 -38.70019692
OS 53.76916348 -38.71776356
OS 53.77286172 -38.73810388
OS 53.77378628 -38.76029332
OS 53.77378628 -38.76121788
OS 53.77378628 -38.76399156
OS 53.77378628 -38.76861436
OS 53.77286172 -38.77416172
OS 53.77193716 -38.7815582
OS 53.77008804 -38.78987924
OS 53.76823892 -38.79912484
OS 53.7663898 -38.809295
OS 53.75899332 -38.83148444
OS 53.75344596 -38.84350372
OS 53.7478986 -38.85459844
OS 53.74050212 -38.86661772
OS 53.73218108 -38.878637
OS 53.72293548 -38.89065628
OS 53.71184076 -38.901751
OS 53.7109162 -38.90267556
OS 53.70906708 -38.90452468
OS 53.70536884 -38.90729836
OS 53.70074604 -38.9109966
OS 53.69519868 -38.9156194
OS 53.6878022 -38.9202422
OS 53.67948116 -38.92578956
OS 53.669311 -38.93041236
OS 53.65914084 -38.93595972
OS 53.64712156 -38.94150708
OS 53.63510228 -38.94612988
OS 53.62123388 -38.95075268
OS 53.60644092 -38.95445092
OS 53.5907234 -38.9572246
OS 53.57500588 -38.95907372
OS 53.55743924 -38.95999828
OS 53.5491182 -38.95999828
OS 53.54357084 -38.95907372
OS 53.53617436 -38.95814916
OS 53.52785332 -38.9572246
OS 53.51860772 -38.95537548
OS 53.50843756 -38.95352636
OS 53.48624812 -38.947979
OS 53.46313412 -38.9387334
OS 53.45111484 -38.93318604
OS 53.44002012 -38.92671412
OS 53.4289254 -38.91839308
OS 53.41783068 -38.91007204
OS 53.41690612 -38.90914748
OS 53.415057 -38.90729836
OS 53.41228332 -38.90452468
OS 53.40950964 -38.90082644
OS 53.40488684 -38.89620364
OS 53.40026404 -38.88973172
OS 53.39471668 -38.8832598
OS 53.38916932 -38.87493876
OS 53.38362196 -38.86569316
OS 53.3780746 -38.85644756
OS 53.36790444 -38.83425812
OS 53.3595834 -38.80837044
OS 53.35680972 -38.79450204
OS 53.3549606 -38.77970908
OS 53.4335482 -38.76953892
OS 53.4335482 -38.77046348
OS 53.43447276 -38.7723126
OS 53.43539732 -38.77601084
OS 53.43632188 -38.78063364
OS 53.43724644 -38.786181
OS 53.43909556 -38.79265292
OS 53.44371836 -38.80652132
OS 53.45019028 -38.8231634
OS 53.45851132 -38.83888092
OS 53.46775692 -38.85367388
OS 53.47885164 -38.86661772
OS 53.48070076 -38.86754228
OS 53.484399 -38.87124052
OS 53.49179548 -38.87586332
OS 53.50104108 -38.88048612
OS 53.5121358 -38.88603348
OS 53.5260042 -38.89065628
OS 53.54172172 -38.89435452
OS 53.5583638 -38.89527908
OS 53.56391116 -38.89527908
OS 53.5676094 -38.89435452
OS 53.57777956 -38.89342996
OS 53.5907234 -38.89065628
OS 53.60551636 -38.88603348
OS 53.62123388 -38.87956156
OS 53.6369514 -38.87031596
OS 53.65174436 -38.85737212
OS 53.65359348 -38.855523
OS 53.65821628 -38.84997564
OS 53.66376364 -38.8416546
OS 53.67116012 -38.83055988
OS 53.6785566 -38.81669148
OS 53.68410396 -38.80097396
OS 53.68872676 -38.78248276
OS 53.69057588 -38.76214244
OS 53.69057588 -38.76121788
OS 53.69057588 -38.75936876
OS 53.69057588 -38.75659508
OS 53.68965132 -38.75289684
OS 53.68872676 -38.74272668
OS 53.68595308 -38.7307074
OS 53.68225484 -38.71591444
OS 53.67578292 -38.70112148
OS 53.66653732 -38.68632852
OS 53.65451804 -38.67246012
OS 53.65266892 -38.670611
OS 53.64804612 -38.66691276
OS 53.64064964 -38.6613654
OS 53.63047948 -38.65489348
OS 53.61753564 -38.64842156
OS 53.60181812 -38.6428742
OS 53.58425148 -38.63917596
OS 53.56483572 -38.63732684
OS 53.55651468 -38.63732684
OS 53.55004276 -38.6382514
OS 53.54172172 -38.63917596
OS 53.53247612 -38.64102508
OS 53.5213814 -38.6428742
OS 53.50936212 -38.64564788
OS 53.51860772 -38.57630588
OS 53.52323052 -38.57630588
OS 53.52692876 -38.57723044
OS 53.53894804 -38.57723044
OS 53.5491182 -38.57538132
OS 53.56113748 -38.5735322
OS 53.57500588 -38.57075852
OS 53.5907234 -38.56613572
OS 53.60551636 -38.5596638
OS 53.62123388 -38.55134276
OS 53.62215844 -38.55134276
OS 53.623083 -38.5504182
OS 53.6277058 -38.54671996
OS 53.63417772 -38.54024804
OS 53.6415742 -38.531927
OS 53.64897068 -38.51990772
OS 53.6554426 -38.50603932
OS 53.6600654 -38.4903218
OS 53.66191452 -38.4810762
OS 53.66191452 -38.47090604
OS 53.66191452 -38.46998148
OS 53.66191452 -38.46905692
OS 53.66191452 -38.46350956
OS 53.6600654 -38.45611308
OS 53.65821628 -38.44594292
OS 53.65451804 -38.4348482
OS 53.64989524 -38.42282892
OS 53.64249876 -38.41080964
OS 53.6323286 -38.39971492
OS 53.63140404 -38.39879036
OS 53.62678124 -38.39509212
OS 53.62030932 -38.39046932
OS 53.61198828 -38.38492196
OS 53.60089356 -38.38029916
OS 53.58794972 -38.37567636
OS 53.57315676 -38.37197812
OS 53.55651468 -38.37105356
OS 53.5491182 -38.37105356
OS 53.54079716 -38.37290268
OS 53.52970244 -38.3747518
OS 53.51768316 -38.37845004
OS 53.50566388 -38.38307284
OS 53.49272004 -38.39046932
OS 53.48070076 -38.39971492
OS 53.4797762 -38.40063948
OS 53.47607796 -38.40526228
OS 53.4705306 -38.4117342
OS 53.46405868 -38.4209798
OS 53.45758676 -38.43299908
OS 53.45111484 -38.44779204
OS 53.44556748 -38.46535868
OS 53.44186924 -38.485699
OS 53.36328164 -38.4718306
OS 53.36328164 -38.47090604
OS 53.3642062 -38.46813236
OS 53.36513076 -38.46443412
OS 53.36605532 -38.45888676
OS 53.36790444 -38.45241484
OS 53.37067812 -38.44501836
OS 53.37622548 -38.42745172
OS 53.38547108 -38.4071114
OS 53.3965658 -38.38677108
OS 53.4104342 -38.36735532
OS 53.42800084 -38.34978868
OS 53.4289254 -38.34886412
OS 53.43077452 -38.34793956
OS 53.4335482 -38.34609044
OS 53.43724644 -38.34331676
OS 53.44186924 -38.33961852
OS 53.44834116 -38.33592028
OS 53.45481308 -38.33222204
OS 53.46313412 -38.32759924
OS 53.48162532 -38.32020276
OS 53.5028902 -38.31280628
OS 53.52785332 -38.30818348
OS 53.54079716 -38.30633436
OS 53.56391116 -38.30633436
OS 53.57408132 -38.30725892
OE
OB 54.07889108 -38.30725892 I
OS 54.09091036 -38.30910804
OS 54.10477876 -38.31188172
OS 54.11957172 -38.31557996
OS 54.13528924 -38.32020276
OS 54.1500822 -38.32759924
OS 54.15100676 -38.32759924
OS 54.15193132 -38.3285238
OS 54.15655412 -38.33129748
OS 54.1639506 -38.33592028
OS 54.1731962 -38.3423922
OS 54.18336636 -38.3516378
OS 54.19446108 -38.36180796
OS 54.20463124 -38.37382724
OS 54.2148014 -38.38769564
OS 54.21572596 -38.38954476
OS 54.2194242 -38.39416756
OS 54.22312244 -38.4024886
OS 54.22959436 -38.41450788
OS 54.23514172 -38.42837628
OS 54.2425382 -38.4440938
OS 54.24901012 -38.462585
OS 54.25455748 -38.48292532
OS 54.25455748 -38.48384988
OS 54.25548204 -38.485699
OS 54.2564066 -38.48847268
OS 54.25733116 -38.49309548
OS 54.25825572 -38.49864284
OS 54.25918028 -38.50511476
OS 54.2610294 -38.5134358
OS 54.26195396 -38.5226814
OS 54.26380308 -38.53285156
OS 54.26472764 -38.54394628
OS 54.2656522 -38.55689012
OS 54.26750132 -38.56983396
OS 54.26842588 -38.58462692
OS 54.26842588 -38.59941988
OS 54.26935044 -38.61606196
OS 54.26935044 -38.6336286
OS 54.26935044 -38.63455316
OS 54.26935044 -38.6382514
OS 54.26935044 -38.64472332
OS 54.26935044 -38.6521198
OS 54.26842588 -38.66228996
OS 54.26842588 -38.67338468
OS 54.26750132 -38.68540396
OS 54.26657676 -38.6983478
OS 54.26380308 -38.72793372
OS 54.25918028 -38.7584442
OS 54.25363292 -38.78803012
OS 54.24993468 -38.80189852
OS 54.24531188 -38.81576692
OS 54.24531188 -38.81669148
OS 54.24438732 -38.8185406
OS 54.2425382 -38.82223884
OS 54.24068908 -38.82686164
OS 54.23883996 -38.83333356
OS 54.23514172 -38.83980548
OS 54.22774524 -38.855523
OS 54.21849964 -38.87216508
OS 54.20648036 -38.89065628
OS 54.19261196 -38.90729836
OS 54.17596988 -38.92301588
OS 54.17504532 -38.92301588
OS 54.17412076 -38.924865
OS 54.17134708 -38.92671412
OS 54.16764884 -38.92856324
OS 54.16302604 -38.93133692
OS 54.15840324 -38.93503516
OS 54.14453484 -38.94150708
OS 54.12789276 -38.947979
OS 54.108477 -38.95445092
OS 54.085363 -38.95814916
OS 54.06039988 -38.95999828
OS 54.05115428 -38.95999828
OS 54.04468236 -38.95907372
OS 54.03728588 -38.95814916
OS 54.02804028 -38.95630004
OS 54.01787012 -38.95445092
OS 54.0067754 -38.95167724
OS 53.99568068 -38.947979
OS 53.9836614 -38.94428076
OS 53.97164212 -38.9387334
OS 53.95962284 -38.93226148
OS 53.94760356 -38.924865
OS 53.93558428 -38.9156194
OS 53.92448956 -38.90544924
OS 53.9143194 -38.89435452
OS 53.91339484 -38.89342996
OS 53.91154572 -38.89065628
OS 53.90877204 -38.88603348
OS 53.90414924 -38.878637
OS 53.89952644 -38.87031596
OS 53.89490364 -38.85922124
OS 53.88843172 -38.8462774
OS 53.88288436 -38.83148444
OS 53.877337 -38.81484236
OS 53.87178964 -38.7954266
OS 53.86624228 -38.77416172
OS 53.86161948 -38.75012316
OS 53.85699668 -38.72423548
OS 53.854223 -38.69649868
OS 53.85237388 -38.6659882
OS 53.85144932 -38.6336286
OS 53.85144932 -38.63270404
OS 53.85144932 -38.6290058
OS 53.85144932 -38.62253388
OS 53.85144932 -38.6151374
OS 53.85237388 -38.60496724
OS 53.85237388 -38.59387252
OS 53.85329844 -38.58185324
OS 53.854223 -38.56798484
OS 53.85699668 -38.53932348
OS 53.86161948 -38.508813
OS 53.86716684 -38.47830252
OS 53.87086508 -38.46443412
OS 53.87456332 -38.45056572
OS 53.87456332 -38.44964116
OS 53.87548788 -38.44779204
OS 53.877337 -38.4440938
OS 53.87918612 -38.439471
OS 53.88103524 -38.43299908
OS 53.88473348 -38.42652716
OS 53.89212996 -38.41080964
OS 53.90137556 -38.39416756
OS 53.91339484 -38.37660092
OS 53.92726324 -38.35903428
OS 53.94390532 -38.34424132
OS 53.94482988 -38.34424132
OS 53.94575444 -38.3423922
OS 53.94852812 -38.34054308
OS 53.95222636 -38.33869396
OS 53.95684916 -38.33499572
OS 53.96239652 -38.33222204
OS 53.97626492 -38.32482556
OS 53.992907 -38.31835364
OS 54.01232276 -38.31188172
OS 54.03543676 -38.30818348
OS 54.06039988 -38.30633436
OS 54.06872092 -38.30633436
OS 54.07889108 -38.30725892
OE
OB 53.23846604 -38.94890356 I
OS 53.14878372 -38.94890356
OS 53.14878372 -38.85922124
OS 53.23846604 -38.85922124
OS 53.23846604 -38.94890356
OE
OB 53.00177868 -38.39231844 I
OS 52.74567556 -38.39231844
OS 52.71146684 -38.56521116
OS 52.7123914 -38.5642866
OS 52.71424052 -38.56336204
OS 52.7170142 -38.56151292
OS 52.721637 -38.55873924
OS 52.72718436 -38.55596556
OS 52.73365628 -38.55226732
OS 52.74844924 -38.54487084
OS 52.76694044 -38.53747436
OS 52.78728076 -38.53100244
OS 52.8094702 -38.52637964
OS 52.82056492 -38.52453052
OS 52.84090524 -38.52453052
OS 52.8464526 -38.52545508
OS 52.85384908 -38.52637964
OS 52.86217012 -38.5273042
OS 52.87141572 -38.52915332
OS 52.88158588 -38.531927
OS 52.90377532 -38.53839892
OS 52.9157946 -38.54302172
OS 52.92781388 -38.54949364
OS 52.93983316 -38.55596556
OS 52.95185244 -38.56336204
OS 52.96294716 -38.57260764
OS 52.97404188 -38.5827778
OS 52.97496644 -38.58370236
OS 52.97681556 -38.58555148
OS 52.97958924 -38.58832516
OS 52.98328748 -38.59294796
OS 52.98791028 -38.59941988
OS 52.99253308 -38.6058918
OS 52.99808044 -38.61421284
OS 53.0036278 -38.62345844
OS 53.0082506 -38.6336286
OS 53.01379796 -38.64472332
OS 53.01842076 -38.65766716
OS 53.02304356 -38.670611
OS 53.0267418 -38.6844794
OS 53.02951548 -38.70019692
OS 53.0313646 -38.71591444
OS 53.03228916 -38.73255652
OS 53.03228916 -38.73348108
OS 53.03228916 -38.73625476
OS 53.03228916 -38.74087756
OS 53.0313646 -38.74734948
OS 53.03044004 -38.75474596
OS 53.02951548 -38.763067
OS 53.02766636 -38.77323716
OS 53.02581724 -38.78340732
OS 53.02026988 -38.80744588
OS 53.01102428 -38.832409
OS 53.00547692 -38.84535284
OS 52.99808044 -38.85737212
OS 52.99068396 -38.87031596
OS 52.98143836 -38.88233524
OS 52.9805138 -38.8832598
OS 52.97866468 -38.88603348
OS 52.97496644 -38.88973172
OS 52.97034364 -38.89435452
OS 52.96387172 -38.89990188
OS 52.95647524 -38.90729836
OS 52.94722964 -38.91377028
OS 52.93705948 -38.92116676
OS 52.92596476 -38.92856324
OS 52.91302092 -38.93503516
OS 52.89915252 -38.94150708
OS 52.88435956 -38.947979
OS 52.86864204 -38.9526018
OS 52.8510754 -38.95630004
OS 52.8325842 -38.95907372
OS 52.81316844 -38.95999828
OS 52.8048474 -38.95999828
OS 52.79837548 -38.95907372
OS 52.790979 -38.95814916
OS 52.78265796 -38.9572246
OS 52.7724878 -38.95630004
OS 52.76231764 -38.95352636
OS 52.73920364 -38.947979
OS 52.71608964 -38.93965796
OS 52.70407036 -38.9341106
OS 52.69205108 -38.92763868
OS 52.68095636 -38.9202422
OS 52.66986164 -38.91192116
OS 52.66893708 -38.9109966
OS 52.66708796 -38.91007204
OS 52.66523884 -38.9063738
OS 52.6615406 -38.90267556
OS 52.6569178 -38.89805276
OS 52.652295 -38.8925054
OS 52.64674764 -38.88510892
OS 52.64212484 -38.87678788
OS 52.63657748 -38.86846684
OS 52.63103012 -38.85829668
OS 52.62085996 -38.83610724
OS 52.61253892 -38.81021956
OS 52.60976524 -38.79635116
OS 52.60791612 -38.7815582
OS 52.69020196 -38.77508628
OS 52.69020196 -38.77601084
OS 52.69020196 -38.77785996
OS 52.69112652 -38.78063364
OS 52.69205108 -38.78525644
OS 52.69482476 -38.7954266
OS 52.698523 -38.809295
OS 52.70407036 -38.8231634
OS 52.71146684 -38.83888092
OS 52.72071244 -38.85274932
OS 52.73180716 -38.86569316
OS 52.73365628 -38.86661772
OS 52.73735452 -38.87031596
OS 52.744751 -38.87493876
OS 52.75492116 -38.88048612
OS 52.76601588 -38.88603348
OS 52.77988428 -38.89065628
OS 52.7956018 -38.89435452
OS 52.81316844 -38.89527908
OS 52.8187158 -38.89527908
OS 52.82241404 -38.89435452
OS 52.83350876 -38.89342996
OS 52.8464526 -38.88973172
OS 52.86217012 -38.88510892
OS 52.87788764 -38.87771244
OS 52.89452972 -38.86661772
OS 52.9019262 -38.8601458
OS 52.90932268 -38.85274932
OS 52.91024724 -38.85182476
OS 52.9111718 -38.8509002
OS 52.91302092 -38.84812652
OS 52.9157946 -38.84535284
OS 52.92226652 -38.83518268
OS 52.929663 -38.82223884
OS 52.93613492 -38.80652132
OS 52.94260684 -38.78710556
OS 52.94722964 -38.76399156
OS 52.94907876 -38.75197228
OS 52.94907876 -38.73902844
OS 52.94907876 -38.73810388
OS 52.94907876 -38.73625476
OS 52.94907876 -38.73255652
OS 52.9481542 -38.72793372
OS 52.9481542 -38.72238636
OS 52.94722964 -38.71591444
OS 52.94445596 -38.70112148
OS 52.93983316 -38.68355484
OS 52.93336124 -38.6659882
OS 52.92411564 -38.64934612
OS 52.9111718 -38.6336286
OS 52.9111718 -38.63270404
OS 52.90932268 -38.63177948
OS 52.90469988 -38.62715668
OS 52.89637884 -38.62068476
OS 52.88528412 -38.61328828
OS 52.87049116 -38.60681636
OS 52.85384908 -38.60034444
OS 52.83443332 -38.59572164
OS 52.8233386 -38.59387252
OS 52.80577196 -38.59387252
OS 52.79837548 -38.59479708
OS 52.78912988 -38.59572164
OS 52.77803516 -38.59849532
OS 52.76694044 -38.601269
OS 52.75492116 -38.6058918
OS 52.74290188 -38.61143916
OS 52.74197732 -38.61236372
OS 52.73827908 -38.61421284
OS 52.73273172 -38.61883564
OS 52.72533524 -38.62345844
OS 52.71793876 -38.62993036
OS 52.71054228 -38.6382514
OS 52.70222124 -38.64657244
OS 52.69574932 -38.6567426
OS 52.62178452 -38.64657244
OS 52.68373004 -38.31742908
OS 53.00177868 -38.31742908
OS 53.00177868 -38.39231844
OE
OB 53.23846604 -38.57445676 I
OS 53.14878372 -38.57445676
OS 53.14878372 -38.48477444
OS 53.23846604 -38.48477444
OS 53.23846604 -38.57445676
OE
OB 54.48199924 -38.57445676 I
OS 54.39231692 -38.57445676
OS 54.39231692 -38.48477444
OS 54.48199924 -38.48477444
OS 54.48199924 -38.57445676
OE
OB 56.14990548 -38.3100326 I
OS 56.165623 -38.31095716
OS 56.18226508 -38.31188172
OS 56.1979826 -38.31373084
OS 56.211851 -38.31557996
OS 56.21370012 -38.31557996
OS 56.22017204 -38.31742908
OS 56.22849308 -38.3192782
OS 56.2395878 -38.32205188
OS 56.25160708 -38.32667468
OS 56.26455092 -38.33222204
OS 56.27841932 -38.33869396
OS 56.2904386 -38.34609044
OS 56.29228772 -38.347015
OS 56.29598596 -38.34978868
OS 56.30153332 -38.35533604
OS 56.3089298 -38.36180796
OS 56.31725084 -38.370129
OS 56.32557188 -38.38122372
OS 56.33481748 -38.393243
OS 56.34221396 -38.4071114
OS 56.34313852 -38.40896052
OS 56.34498764 -38.41358332
OS 56.34868588 -38.42190436
OS 56.35238412 -38.43299908
OS 56.3551578 -38.44594292
OS 56.35885604 -38.46073588
OS 56.36070516 -38.47737796
OS 56.36162972 -38.4949446
OS 56.36162972 -38.49586916
OS 56.36162972 -38.49864284
OS 56.36162972 -38.50234108
OS 56.36070516 -38.508813
OS 56.3597806 -38.51528492
OS 56.35885604 -38.52360596
OS 56.35700692 -38.53285156
OS 56.3551578 -38.54302172
OS 56.34868588 -38.5642866
OS 56.34498764 -38.57538132
OS 56.33944028 -38.5874006
OS 56.33296836 -38.59941988
OS 56.32649644 -38.6105146
OS 56.3181754 -38.62160932
OS 56.3089298 -38.63270404
OS 56.30800524 -38.6336286
OS 56.30615612 -38.63547772
OS 56.30338244 -38.6382514
OS 56.29875964 -38.64102508
OS 56.29321228 -38.64564788
OS 56.2858158 -38.65027068
OS 56.2765702 -38.65581804
OS 56.26640004 -38.66044084
OS 56.25438076 -38.6659882
OS 56.24051236 -38.67153556
OS 56.2257194 -38.67615836
OS 56.20815276 -38.6798566
OS 56.18966156 -38.68355484
OS 56.16932124 -38.68632852
OS 56.14620724 -38.68817764
OS 56.12216868 -38.6891022
OS 55.95852156 -38.6891022
OS 55.95852156 -38.94890356
OS 55.87346204 -38.94890356
OS 55.87346204 -38.30910804
OS 56.13603708 -38.30910804
OS 56.14990548 -38.3100326
OE
OB 57.07723916 -38.94890356 I
OS 56.99587788 -38.94890356
OS 56.99587788 -38.41358332
OS 56.80911676 -38.94890356
OS 56.73330284 -38.94890356
OS 56.54839084 -38.40433772
OS 56.54839084 -38.94890356
OS 56.46702956 -38.94890356
OS 56.46702956 -38.30910804
OS 56.59369428 -38.30910804
OS 56.74532212 -38.763067
OS 56.74532212 -38.76399156
OS 56.74624668 -38.76584068
OS 56.74717124 -38.76861436
OS 56.74902036 -38.77323716
OS 56.7527186 -38.78433188
OS 56.7573414 -38.79820028
OS 56.7619642 -38.8139178
OS 56.76751156 -38.82963532
OS 56.77213436 -38.84442828
OS 56.7758326 -38.85737212
OS 56.77675716 -38.855523
OS 56.77768172 -38.8509002
OS 56.7804554 -38.84257916
OS 56.78415364 -38.83148444
OS 56.78877644 -38.81669148
OS 56.79524836 -38.79912484
OS 56.80172028 -38.77878452
OS 56.81004132 -38.75474596
OS 56.96351828 -38.30910804
OS 57.07723916 -38.30910804
OS 57.07723916 -38.94890356
OE
OB 55.3150278 -38.30725892 I
OS 55.32704708 -38.30910804
OS 55.34184004 -38.31188172
OS 55.35848212 -38.31650452
OS 55.3751242 -38.32205188
OS 55.39176628 -38.32944836
OS 55.39269084 -38.32944836
OS 55.3936154 -38.33037292
OS 55.39916276 -38.3331466
OS 55.4074838 -38.33869396
OS 55.4167294 -38.34516588
OS 55.42782412 -38.35441148
OS 55.43891884 -38.36458164
OS 55.45001356 -38.37660092
OS 55.45925916 -38.39046932
OS 55.46018372 -38.39231844
OS 55.4629574 -38.39694124
OS 55.46665564 -38.40526228
OS 55.47127844 -38.41543244
OS 55.47590124 -38.42745172
OS 55.47959948 -38.44132012
OS 55.48237316 -38.45703764
OS 55.48329772 -38.47275516
OS 55.48329772 -38.47460428
OS 55.48329772 -38.48015164
OS 55.48237316 -38.48754812
OS 55.48052404 -38.49771828
OS 55.47775036 -38.50973756
OS 55.47312756 -38.5226814
OS 55.4675802 -38.53562524
OS 55.46018372 -38.54856908
OS 55.45925916 -38.5504182
OS 55.45648548 -38.55411644
OS 55.45093812 -38.56058836
OS 55.44354164 -38.56798484
OS 55.43429604 -38.57630588
OS 55.42320132 -38.58555148
OS 55.41025748 -38.59387252
OS 55.39453996 -38.60219356
OS 55.39546452 -38.60219356
OS 55.39731364 -38.60311812
OS 55.40008732 -38.60404268
OS 55.40378556 -38.60496724
OS 55.41395572 -38.60866548
OS 55.42689956 -38.61421284
OS 55.44169252 -38.62160932
OS 55.45648548 -38.63085492
OS 55.47035388 -38.6428742
OS 55.48329772 -38.6567426
OS 55.48422228 -38.65859172
OS 55.48792052 -38.66413908
OS 55.49346788 -38.67338468
OS 55.49901524 -38.68540396
OS 55.5045626 -38.70019692
OS 55.51010996 -38.71776356
OS 55.5138082 -38.73810388
OS 55.51473276 -38.76029332
OS 55.51473276 -38.76121788
OS 55.51473276 -38.76399156
OS 55.51473276 -38.76861436
OS 55.5138082 -38.77416172
OS 55.51288364 -38.7815582
OS 55.51103452 -38.78987924
OS 55.5091854 -38.79912484
OS 55.50733628 -38.809295
OS 55.4999398 -38.83148444
OS 55.49439244 -38.84350372
OS 55.48884508 -38.85459844
OS 55.4814486 -38.86661772
OS 55.47312756 -38.878637
OS 55.46388196 -38.89065628
OS 55.45278724 -38.901751
OS 55.45186268 -38.90267556
OS 55.45001356 -38.90452468
OS 55.44631532 -38.90729836
OS 55.44169252 -38.9109966
OS 55.43614516 -38.9156194
OS 55.42874868 -38.9202422
OS 55.42042764 -38.92578956
OS 55.41025748 -38.93041236
OS 55.40008732 -38.93595972
OS 55.38806804 -38.94150708
OS 55.37604876 -38.94612988
OS 55.36218036 -38.95075268
OS 55.3473874 -38.95445092
OS 55.33166988 -38.9572246
OS 55.31595236 -38.95907372
OS 55.29838572 -38.95999828
OS 55.29006468 -38.95999828
OS 55.28451732 -38.95907372
OS 55.27712084 -38.95814916
OS 55.2687998 -38.9572246
OS 55.2595542 -38.95537548
OS 55.24938404 -38.95352636
OS 55.2271946 -38.947979
OS 55.2040806 -38.9387334
OS 55.19206132 -38.93318604
OS 55.1809666 -38.92671412
OS 55.16987188 -38.91839308
OS 55.15877716 -38.91007204
OS 55.1578526 -38.90914748
OS 55.15600348 -38.90729836
OS 55.1532298 -38.90452468
OS 55.15045612 -38.90082644
OS 55.14583332 -38.89620364
OS 55.14121052 -38.88973172
OS 55.13566316 -38.8832598
OS 55.1301158 -38.87493876
OS 55.12456844 -38.86569316
OS 55.11902108 -38.85644756
OS 55.10885092 -38.83425812
OS 55.10052988 -38.80837044
OS 55.0977562 -38.79450204
OS 55.09590708 -38.77970908
OS 55.17449468 -38.76953892
OS 55.17449468 -38.77046348
OS 55.17541924 -38.7723126
OS 55.1763438 -38.77601084
OS 55.17726836 -38.78063364
OS 55.17819292 -38.786181
OS 55.18004204 -38.79265292
OS 55.18466484 -38.80652132
OS 55.19113676 -38.8231634
OS 55.1994578 -38.83888092
OS 55.2087034 -38.85367388
OS 55.21979812 -38.86661772
OS 55.22164724 -38.86754228
OS 55.22534548 -38.87124052
OS 55.23274196 -38.87586332
OS 55.24198756 -38.88048612
OS 55.25308228 -38.88603348
OS 55.26695068 -38.89065628
OS 55.2826682 -38.89435452
OS 55.29931028 -38.89527908
OS 55.30485764 -38.89527908
OS 55.30855588 -38.89435452
OS 55.31872604 -38.89342996
OS 55.33166988 -38.89065628
OS 55.34646284 -38.88603348
OS 55.36218036 -38.87956156
OS 55.37789788 -38.87031596
OS 55.39269084 -38.85737212
OS 55.39453996 -38.855523
OS 55.39916276 -38.84997564
OS 55.40471012 -38.8416546
OS 55.4121066 -38.83055988
OS 55.41950308 -38.81669148
OS 55.42505044 -38.80097396
OS 55.42967324 -38.78248276
OS 55.43152236 -38.76214244
OS 55.43152236 -38.76121788
OS 55.43152236 -38.75936876
OS 55.43152236 -38.75659508
OS 55.4305978 -38.75289684
OS 55.42967324 -38.74272668
OS 55.42689956 -38.7307074
OS 55.42320132 -38.71591444
OS 55.4167294 -38.70112148
OS 55.4074838 -38.68632852
OS 55.39546452 -38.67246012
OS 55.3936154 -38.670611
OS 55.3889926 -38.66691276
OS 55.38159612 -38.6613654
OS 55.37142596 -38.65489348
OS 55.35848212 -38.64842156
OS 55.3427646 -38.6428742
OS 55.32519796 -38.63917596
OS 55.3057822 -38.63732684
OS 55.29746116 -38.63732684
OS 55.29098924 -38.6382514
OS 55.2826682 -38.63917596
OS 55.2734226 -38.64102508
OS 55.26232788 -38.6428742
OS 55.2503086 -38.64564788
OS 55.2595542 -38.57630588
OS 55.264177 -38.57630588
OS 55.26787524 -38.57723044
OS 55.27989452 -38.57723044
OS 55.29006468 -38.57538132
OS 55.30208396 -38.5735322
OS 55.31595236 -38.57075852
OS 55.33166988 -38.56613572
OS 55.34646284 -38.5596638
OS 55.36218036 -38.55134276
OS 55.36310492 -38.55134276
OS 55.36402948 -38.5504182
OS 55.36865228 -38.54671996
OS 55.3751242 -38.54024804
OS 55.38252068 -38.531927
OS 55.38991716 -38.51990772
OS 55.39638908 -38.50603932
OS 55.40101188 -38.4903218
OS 55.402861 -38.4810762
OS 55.402861 -38.47090604
OS 55.402861 -38.46998148
OS 55.402861 -38.46905692
OS 55.402861 -38.46350956
OS 55.40101188 -38.45611308
OS 55.39916276 -38.44594292
OS 55.39546452 -38.4348482
OS 55.39084172 -38.42282892
OS 55.38344524 -38.41080964
OS 55.37327508 -38.39971492
OS 55.37235052 -38.39879036
OS 55.36772772 -38.39509212
OS 55.3612558 -38.39046932
OS 55.35293476 -38.38492196
OS 55.34184004 -38.38029916
OS 55.3288962 -38.37567636
OS 55.31410324 -38.37197812
OS 55.29746116 -38.37105356
OS 55.29006468 -38.37105356
OS 55.28174364 -38.37290268
OS 55.27064892 -38.3747518
OS 55.25862964 -38.37845004
OS 55.24661036 -38.38307284
OS 55.23366652 -38.39046932
OS 55.22164724 -38.39971492
OS 55.22072268 -38.40063948
OS 55.21702444 -38.40526228
OS 55.21147708 -38.4117342
OS 55.20500516 -38.4209798
OS 55.19853324 -38.43299908
OS 55.19206132 -38.44779204
OS 55.18651396 -38.46535868
OS 55.18281572 -38.485699
OS 55.10422812 -38.4718306
OS 55.10422812 -38.47090604
OS 55.10515268 -38.46813236
OS 55.10607724 -38.46443412
OS 55.1070018 -38.45888676
OS 55.10885092 -38.45241484
OS 55.1116246 -38.44501836
OS 55.11717196 -38.42745172
OS 55.12641756 -38.4071114
OS 55.13751228 -38.38677108
OS 55.15138068 -38.36735532
OS 55.16894732 -38.34978868
OS 55.16987188 -38.34886412
OS 55.171721 -38.34793956
OS 55.17449468 -38.34609044
OS 55.17819292 -38.34331676
OS 55.18281572 -38.33961852
OS 55.18928764 -38.33592028
OS 55.19575956 -38.33222204
OS 55.2040806 -38.32759924
OS 55.2225718 -38.32020276
OS 55.24383668 -38.31280628
OS 55.2687998 -38.30818348
OS 55.28174364 -38.30633436
OS 55.30485764 -38.30633436
OS 55.3150278 -38.30725892
OE
OB 54.48199924 -38.94890356 I
OS 54.39231692 -38.94890356
OS 54.39231692 -38.85922124
OS 54.48199924 -38.85922124
OS 54.48199924 -38.94890356
OE
OB 54.9914318 -38.39231844 I
OS 54.73532868 -38.39231844
OS 54.70111996 -38.56521116
OS 54.70204452 -38.5642866
OS 54.70389364 -38.56336204
OS 54.70666732 -38.56151292
OS 54.71129012 -38.55873924
OS 54.71683748 -38.55596556
OS 54.7233094 -38.55226732
OS 54.73810236 -38.54487084
OS 54.75659356 -38.53747436
OS 54.77693388 -38.53100244
OS 54.79912332 -38.52637964
OS 54.81021804 -38.52453052
OS 54.83055836 -38.52453052
OS 54.83610572 -38.52545508
OS 54.8435022 -38.52637964
OS 54.85182324 -38.5273042
OS 54.86106884 -38.52915332
OS 54.871239 -38.531927
OS 54.89342844 -38.53839892
OS 54.90544772 -38.54302172
OS 54.917467 -38.54949364
OS 54.92948628 -38.55596556
OS 54.94150556 -38.56336204
OS 54.95260028 -38.57260764
OS 54.963695 -38.5827778
OS 54.96461956 -38.58370236
OS 54.96646868 -38.58555148
OS 54.96924236 -38.58832516
OS 54.9729406 -38.59294796
OS 54.9775634 -38.59941988
OS 54.9821862 -38.6058918
OS 54.98773356 -38.61421284
OS 54.99328092 -38.62345844
OS 54.99790372 -38.6336286
OS 55.00345108 -38.64472332
OS 55.00807388 -38.65766716
OS 55.01269668 -38.670611
OS 55.01639492 -38.6844794
OS 55.0191686 -38.70019692
OS 55.02101772 -38.71591444
OS 55.02194228 -38.73255652
OS 55.02194228 -38.73348108
OS 55.02194228 -38.73625476
OS 55.02194228 -38.74087756
OS 55.02101772 -38.74734948
OS 55.02009316 -38.75474596
OS 55.0191686 -38.763067
OS 55.01731948 -38.77323716
OS 55.01547036 -38.78340732
OS 55.009923 -38.80744588
OS 55.0006774 -38.832409
OS 54.99513004 -38.84535284
OS 54.98773356 -38.85737212
OS 54.98033708 -38.87031596
OS 54.97109148 -38.88233524
OS 54.97016692 -38.8832598
OS 54.9683178 -38.88603348
OS 54.96461956 -38.88973172
OS 54.95999676 -38.89435452
OS 54.95352484 -38.89990188
OS 54.94612836 -38.90729836
OS 54.93688276 -38.91377028
OS 54.9267126 -38.92116676
OS 54.91561788 -38.92856324
OS 54.90267404 -38.93503516
OS 54.88880564 -38.94150708
OS 54.87401268 -38.947979
OS 54.85829516 -38.9526018
OS 54.84072852 -38.95630004
OS 54.82223732 -38.95907372
OS 54.80282156 -38.95999828
OS 54.79450052 -38.95999828
OS 54.7880286 -38.95907372
OS 54.78063212 -38.95814916
OS 54.77231108 -38.9572246
OS 54.76214092 -38.95630004
OS 54.75197076 -38.95352636
OS 54.72885676 -38.947979
OS 54.70574276 -38.93965796
OS 54.69372348 -38.9341106
OS 54.6817042 -38.92763868
OS 54.67060948 -38.9202422
OS 54.65951476 -38.91192116
OS 54.6585902 -38.9109966
OS 54.65674108 -38.91007204
OS 54.65489196 -38.9063738
OS 54.65119372 -38.90267556
OS 54.64657092 -38.89805276
OS 54.64194812 -38.8925054
OS 54.63640076 -38.88510892
OS 54.63177796 -38.87678788
OS 54.6262306 -38.86846684
OS 54.62068324 -38.85829668
OS 54.61051308 -38.83610724
OS 54.60219204 -38.81021956
OS 54.59941836 -38.79635116
OS 54.59756924 -38.7815582
OS 54.67985508 -38.77508628
OS 54.67985508 -38.77601084
OS 54.67985508 -38.77785996
OS 54.68077964 -38.78063364
OS 54.6817042 -38.78525644
OS 54.68447788 -38.7954266
OS 54.68817612 -38.809295
OS 54.69372348 -38.8231634
OS 54.70111996 -38.83888092
OS 54.71036556 -38.85274932
OS 54.72146028 -38.86569316
OS 54.7233094 -38.86661772
OS 54.72700764 -38.87031596
OS 54.73440412 -38.87493876
OS 54.74457428 -38.88048612
OS 54.755669 -38.88603348
OS 54.7695374 -38.89065628
OS 54.78525492 -38.89435452
OS 54.80282156 -38.89527908
OS 54.80836892 -38.89527908
OS 54.81206716 -38.89435452
OS 54.82316188 -38.89342996
OS 54.83610572 -38.88973172
OS 54.85182324 -38.88510892
OS 54.86754076 -38.87771244
OS 54.88418284 -38.86661772
OS 54.89157932 -38.8601458
OS 54.8989758 -38.85274932
OS 54.89990036 -38.85182476
OS 54.90082492 -38.8509002
OS 54.90267404 -38.84812652
OS 54.90544772 -38.84535284
OS 54.91191964 -38.83518268
OS 54.91931612 -38.82223884
OS 54.92578804 -38.80652132
OS 54.93225996 -38.78710556
OS 54.93688276 -38.76399156
OS 54.93873188 -38.75197228
OS 54.93873188 -38.73902844
OS 54.93873188 -38.73810388
OS 54.93873188 -38.73625476
OS 54.93873188 -38.73255652
OS 54.93780732 -38.72793372
OS 54.93780732 -38.72238636
OS 54.93688276 -38.71591444
OS 54.93410908 -38.70112148
OS 54.92948628 -38.68355484
OS 54.92301436 -38.6659882
OS 54.91376876 -38.64934612
OS 54.90082492 -38.6336286
OS 54.90082492 -38.63270404
OS 54.8989758 -38.63177948
OS 54.894353 -38.62715668
OS 54.88603196 -38.62068476
OS 54.87493724 -38.61328828
OS 54.86014428 -38.60681636
OS 54.8435022 -38.60034444
OS 54.82408644 -38.59572164
OS 54.81299172 -38.59387252
OS 54.79542508 -38.59387252
OS 54.7880286 -38.59479708
OS 54.778783 -38.59572164
OS 54.76768828 -38.59849532
OS 54.75659356 -38.601269
OS 54.74457428 -38.6058918
OS 54.732555 -38.61143916
OS 54.73163044 -38.61236372
OS 54.7279322 -38.61421284
OS 54.72238484 -38.61883564
OS 54.71498836 -38.62345844
OS 54.70759188 -38.62993036
OS 54.7001954 -38.6382514
OS 54.69187436 -38.64657244
OS 54.68540244 -38.6567426
OS 54.61143764 -38.64657244
OS 54.67338316 -38.31742908
OS 54.9914318 -38.31742908
OS 54.9914318 -38.39231844
OE
OB 49.95350436 -38.72331092 I
OS 50.040413 -38.72331092
OS 50.040413 -38.7954266
OS 49.95350436 -38.7954266
OS 49.95350436 -38.94890356
OS 49.87491676 -38.94890356
OS 49.87491676 -38.7954266
OS 49.5966242 -38.7954266
OS 49.5966242 -38.72331092
OS 49.88970972 -38.30910804
OS 49.95350436 -38.30910804
OS 49.95350436 -38.72331092
OE
OB 50.1467374 -38.95999828 I
OS 50.08386732 -38.95999828
OS 50.26970388 -38.29801332
OS 50.33257396 -38.29801332
OS 50.1467374 -38.95999828
OE
OB 49.35346492 -38.30725892 I
OS 49.3608614 -38.30818348
OS 49.370107 -38.30910804
OS 49.38027716 -38.31095716
OS 49.39044732 -38.31280628
OS 49.41448588 -38.3192782
OS 49.43852444 -38.3285238
OS 49.45054372 -38.33407116
OS 49.462563 -38.34054308
OS 49.47365772 -38.34886412
OS 49.48382788 -38.35810972
OS 49.48475244 -38.35903428
OS 49.48660156 -38.35995884
OS 49.48845068 -38.36365708
OS 49.49214892 -38.36735532
OS 49.49677172 -38.37197812
OS 49.50139452 -38.37845004
OS 49.50601732 -38.38492196
OS 49.51156468 -38.393243
OS 49.52081028 -38.41080964
OS 49.53005588 -38.43299908
OS 49.53375412 -38.4440938
OS 49.53560324 -38.45703764
OS 49.53745236 -38.46998148
OS 49.53837692 -38.48384988
OS 49.53837692 -38.485699
OS 49.53837692 -38.4903218
OS 49.53745236 -38.49771828
OS 49.5365278 -38.50788844
OS 49.53467868 -38.51898316
OS 49.53098044 -38.531927
OS 49.5272822 -38.5457954
OS 49.52173484 -38.5596638
OS 49.52081028 -38.56151292
OS 49.51896116 -38.56613572
OS 49.51526292 -38.5735322
OS 49.50971556 -38.58370236
OS 49.50231908 -38.59479708
OS 49.49307348 -38.60866548
OS 49.48197876 -38.62253388
OS 49.46903492 -38.6382514
OS 49.4671858 -38.64010052
OS 49.462563 -38.64564788
OS 49.4579402 -38.65027068
OS 49.4533174 -38.65489348
OS 49.44777004 -38.66044084
OS 49.44037356 -38.66783732
OS 49.43297708 -38.6752338
OS 49.42373148 -38.68355484
OS 49.41448588 -38.69280044
OS 49.40339116 -38.7029706
OS 49.39137188 -38.71314076
OS 49.37842804 -38.72516004
OS 49.36363508 -38.73717932
OS 49.34884212 -38.75012316
OS 49.34791756 -38.75104772
OS 49.34606844 -38.75289684
OS 49.3423702 -38.75567052
OS 49.3377474 -38.75936876
OS 49.33220004 -38.76491612
OS 49.32572812 -38.77046348
OS 49.31093516 -38.78248276
OS 49.29521764 -38.79635116
OS 49.28042468 -38.81021956
OS 49.26748084 -38.82223884
OS 49.26193348 -38.82686164
OS 49.25731068 -38.83148444
OS 49.25638612 -38.832409
OS 49.25361244 -38.83518268
OS 49.2499142 -38.83888092
OS 49.2452914 -38.84442828
OS 49.2406686 -38.8509002
OS 49.23512124 -38.85737212
OS 49.22402652 -38.87308964
OS 49.53930148 -38.87308964
OS 49.53930148 -38.94890356
OS 49.11492844 -38.94890356
OS 49.11492844 -38.947979
OS 49.11492844 -38.94428076
OS 49.11492844 -38.9387334
OS 49.115853 -38.93133692
OS 49.11677756 -38.92301588
OS 49.11862668 -38.91377028
OS 49.1204758 -38.90452468
OS 49.12417404 -38.89435452
OS 49.12417404 -38.89342996
OS 49.1250986 -38.8925054
OS 49.12694772 -38.88695804
OS 49.13064596 -38.878637
OS 49.13619332 -38.86754228
OS 49.1435898 -38.85459844
OS 49.1528354 -38.83980548
OS 49.16300556 -38.82501252
OS 49.1759494 -38.809295
OS 49.1759494 -38.80837044
OS 49.17779852 -38.80744588
OS 49.18242132 -38.80189852
OS 49.19074236 -38.79357748
OS 49.20276164 -38.7815582
OS 49.21663004 -38.7676898
OS 49.23419668 -38.75104772
OS 49.25546156 -38.73255652
OS 49.27857556 -38.71314076
OS 49.27950012 -38.7122162
OS 49.28319836 -38.70944252
OS 49.28874572 -38.70481972
OS 49.29521764 -38.69927236
OS 49.30353868 -38.69187588
OS 49.31370884 -38.68355484
OS 49.323879 -38.67430924
OS 49.33589828 -38.66413908
OS 49.35901228 -38.64194964
OS 49.38212628 -38.6197602
OS 49.393221 -38.60866548
OS 49.40339116 -38.59757076
OS 49.41263676 -38.5874006
OS 49.42003324 -38.57723044
OS 49.42003324 -38.57630588
OS 49.42188236 -38.57538132
OS 49.42373148 -38.57260764
OS 49.4255806 -38.5689094
OS 49.43205252 -38.55873924
OS 49.439449 -38.54671996
OS 49.44592092 -38.531927
OS 49.45239284 -38.51620948
OS 49.45609108 -38.49864284
OS 49.4579402 -38.48200076
OS 49.4579402 -38.4810762
OS 49.4579402 -38.48015164
OS 49.45701564 -38.47460428
OS 49.45609108 -38.46535868
OS 49.4533174 -38.45518852
OS 49.44961916 -38.44224468
OS 49.44314724 -38.42930084
OS 49.4348262 -38.416357
OS 49.42373148 -38.40341316
OS 49.42188236 -38.40156404
OS 49.41725956 -38.3978658
OS 49.41078764 -38.393243
OS 49.40061748 -38.38677108
OS 49.38767364 -38.38122372
OS 49.37288068 -38.37567636
OS 49.35531404 -38.37197812
OS 49.33589828 -38.37105356
OS 49.33035092 -38.37105356
OS 49.32665268 -38.37197812
OS 49.31555796 -38.37290268
OS 49.30261412 -38.37567636
OS 49.28874572 -38.3793746
OS 49.2730282 -38.38584652
OS 49.25823524 -38.39416756
OS 49.24436684 -38.40526228
OS 49.24251772 -38.4071114
OS 49.23881948 -38.4117342
OS 49.23327212 -38.41913068
OS 49.22772476 -38.4302254
OS 49.22125284 -38.44316924
OS 49.21570548 -38.45981132
OS 49.21200724 -38.47830252
OS 49.21015812 -38.4995674
OS 49.1297214 -38.49124636
OS 49.1297214 -38.4903218
OS 49.13064596 -38.48754812
OS 49.13064596 -38.48292532
OS 49.13157052 -38.4764534
OS 49.13341964 -38.46905692
OS 49.13526876 -38.46073588
OS 49.13804244 -38.45056572
OS 49.14081612 -38.44039556
OS 49.1482126 -38.41820612
OS 49.15930732 -38.39601668
OS 49.16577924 -38.38492196
OS 49.17410028 -38.37382724
OS 49.18242132 -38.36365708
OS 49.19166692 -38.35441148
OS 49.19259148 -38.35348692
OS 49.1944406 -38.35256236
OS 49.19721428 -38.34978868
OS 49.20183708 -38.347015
OS 49.20738444 -38.34331676
OS 49.21385636 -38.33961852
OS 49.22125284 -38.33499572
OS 49.23049844 -38.33037292
OS 49.2406686 -38.32575012
OS 49.25176332 -38.32112732
OS 49.2637826 -38.31742908
OS 49.27672644 -38.31373084
OS 49.29059484 -38.31095716
OS 49.3053878 -38.30818348
OS 49.32110532 -38.30725892
OS 49.3377474 -38.30633436
OS 49.346993 -38.30633436
OS 49.35346492 -38.30725892
OE
OB 48.67576244 -38.94890356 I
OS 48.59717484 -38.94890356
OS 48.59717484 -38.4487166
OS 48.59625028 -38.44964116
OS 48.59162748 -38.4533394
OS 48.58608012 -38.45888676
OS 48.57683452 -38.46535868
OS 48.56666436 -38.47367972
OS 48.55372052 -38.48292532
OS 48.53892756 -38.49309548
OS 48.52228548 -38.50326564
OS 48.52136092 -38.50326564
OS 48.52043636 -38.5041902
OS 48.514889 -38.50788844
OS 48.5056434 -38.51251124
OS 48.49454868 -38.5180586
OS 48.48160484 -38.52453052
OS 48.46773644 -38.53100244
OS 48.45386804 -38.53747436
OS 48.43999964 -38.54302172
OS 48.43999964 -38.4672078
OS 48.4409242 -38.4672078
OS 48.44277332 -38.46535868
OS 48.44647156 -38.46443412
OS 48.45109436 -38.46166044
OS 48.45664172 -38.45888676
OS 48.46311364 -38.45518852
OS 48.47883116 -38.44594292
OS 48.49732236 -38.43577276
OS 48.51581356 -38.42282892
OS 48.53522932 -38.40803596
OS 48.55464508 -38.39231844
OS 48.55556964 -38.39139388
OS 48.5564942 -38.39046932
OS 48.55926788 -38.38769564
OS 48.56296612 -38.38492196
OS 48.57128716 -38.37567636
OS 48.58238188 -38.36458164
OS 48.5934766 -38.3516378
OS 48.60549588 -38.33684484
OS 48.61566604 -38.32205188
OS 48.62491164 -38.30633436
OS 48.67576244 -38.30633436
OS 48.67576244 -38.94890356
OE
OB 48.9032042 -38.95999828 I
OS 48.84033412 -38.95999828
OS 49.02617068 -38.29801332
OS 49.08904076 -38.29801332
OS 48.9032042 -38.95999828
OE
OB 50.59699812 -38.30725892 I
OS 50.6043946 -38.30818348
OS 50.6136402 -38.30910804
OS 50.62381036 -38.31095716
OS 50.63398052 -38.31280628
OS 50.65801908 -38.3192782
OS 50.68205764 -38.3285238
OS 50.69407692 -38.33407116
OS 50.7060962 -38.34054308
OS 50.71719092 -38.34886412
OS 50.72736108 -38.35810972
OS 50.72828564 -38.35903428
OS 50.73013476 -38.35995884
OS 50.73198388 -38.36365708
OS 50.73568212 -38.36735532
OS 50.74030492 -38.37197812
OS 50.74492772 -38.37845004
OS 50.74955052 -38.38492196
OS 50.75509788 -38.393243
OS 50.76434348 -38.41080964
OS 50.77358908 -38.43299908
OS 50.77728732 -38.4440938
OS 50.77913644 -38.45703764
OS 50.78098556 -38.46998148
OS 50.78191012 -38.48384988
OS 50.78191012 -38.485699
OS 50.78191012 -38.4903218
OS 50.78098556 -38.49771828
OS 50.780061 -38.50788844
OS 50.77821188 -38.51898316
OS 50.77451364 -38.531927
OS 50.7708154 -38.5457954
OS 50.76526804 -38.5596638
OS 50.76434348 -38.56151292
OS 50.76249436 -38.56613572
OS 50.75879612 -38.5735322
OS 50.75324876 -38.58370236
OS 50.74585228 -38.59479708
OS 50.73660668 -38.60866548
OS 50.72551196 -38.62253388
OS 50.71256812 -38.6382514
OS 50.710719 -38.64010052
OS 50.7060962 -38.64564788
OS 50.7014734 -38.65027068
OS 50.6968506 -38.65489348
OS 50.69130324 -38.66044084
OS 50.68390676 -38.66783732
OS 50.67651028 -38.6752338
OS 50.66726468 -38.68355484
OS 50.65801908 -38.69280044
OS 50.64692436 -38.7029706
OS 50.63490508 -38.71314076
OS 50.62196124 -38.72516004
OS 50.60716828 -38.73717932
OS 50.59237532 -38.75012316
OS 50.59145076 -38.75104772
OS 50.58960164 -38.75289684
OS 50.5859034 -38.75567052
OS 50.5812806 -38.75936876
OS 50.57573324 -38.76491612
OS 50.56926132 -38.77046348
OS 50.55446836 -38.78248276
OS 50.53875084 -38.79635116
OS 50.52395788 -38.81021956
OS 50.51101404 -38.82223884
OS 50.50546668 -38.82686164
OS 50.50084388 -38.83148444
OS 50.49991932 -38.832409
OS 50.49714564 -38.83518268
OS 50.4934474 -38.83888092
OS 50.4888246 -38.84442828
OS 50.4842018 -38.8509002
OS 50.47865444 -38.85737212
OS 50.46755972 -38.87308964
OS 50.78283468 -38.87308964
OS 50.78283468 -38.94890356
OS 50.35846164 -38.94890356
OS 50.35846164 -38.947979
OS 50.35846164 -38.94428076
OS 50.35846164 -38.9387334
OS 50.3593862 -38.93133692
OS 50.36031076 -38.92301588
OS 50.36215988 -38.91377028
OS 50.364009 -38.90452468
OS 50.36770724 -38.89435452
OS 50.36770724 -38.89342996
OS 50.3686318 -38.8925054
OS 50.37048092 -38.88695804
OS 50.37417916 -38.878637
OS 50.37972652 -38.86754228
OS 50.387123 -38.85459844
OS 50.3963686 -38.83980548
OS 50.40653876 -38.82501252
OS 50.4194826 -38.809295
OS 50.4194826 -38.80837044
OS 50.42133172 -38.80744588
OS 50.42595452 -38.80189852
OS 50.43427556 -38.79357748
OS 50.44629484 -38.7815582
OS 50.46016324 -38.7676898
OS 50.47772988 -38.75104772
OS 50.49899476 -38.73255652
OS 50.52210876 -38.71314076
OS 50.52303332 -38.7122162
OS 50.52673156 -38.70944252
OS 50.53227892 -38.70481972
OS 50.53875084 -38.69927236
OS 50.54707188 -38.69187588
OS 50.55724204 -38.68355484
OS 50.5674122 -38.67430924
OS 50.57943148 -38.66413908
OS 50.60254548 -38.64194964
OS 50.62565948 -38.6197602
OS 50.6367542 -38.60866548
OS 50.64692436 -38.59757076
OS 50.65616996 -38.5874006
OS 50.66356644 -38.57723044
OS 50.66356644 -38.57630588
OS 50.66541556 -38.57538132
OS 50.66726468 -38.57260764
OS 50.6691138 -38.5689094
OS 50.67558572 -38.55873924
OS 50.6829822 -38.54671996
OS 50.68945412 -38.531927
OS 50.69592604 -38.51620948
OS 50.69962428 -38.49864284
OS 50.7014734 -38.48200076
OS 50.7014734 -38.4810762
OS 50.7014734 -38.48015164
OS 50.70054884 -38.47460428
OS 50.69962428 -38.46535868
OS 50.6968506 -38.45518852
OS 50.69315236 -38.44224468
OS 50.68668044 -38.42930084
OS 50.6783594 -38.416357
OS 50.66726468 -38.40341316
OS 50.66541556 -38.40156404
OS 50.66079276 -38.3978658
OS 50.65432084 -38.393243
OS 50.64415068 -38.38677108
OS 50.63120684 -38.38122372
OS 50.61641388 -38.37567636
OS 50.59884724 -38.37197812
OS 50.57943148 -38.37105356
OS 50.57388412 -38.37105356
OS 50.57018588 -38.37197812
OS 50.55909116 -38.37290268
OS 50.54614732 -38.37567636
OS 50.53227892 -38.3793746
OS 50.5165614 -38.38584652
OS 50.50176844 -38.39416756
OS 50.48790004 -38.40526228
OS 50.48605092 -38.4071114
OS 50.48235268 -38.4117342
OS 50.47680532 -38.41913068
OS 50.47125796 -38.4302254
OS 50.46478604 -38.44316924
OS 50.45923868 -38.45981132
OS 50.45554044 -38.47830252
OS 50.45369132 -38.4995674
OS 50.3732546 -38.49124636
OS 50.3732546 -38.4903218
OS 50.37417916 -38.48754812
OS 50.37417916 -38.48292532
OS 50.37510372 -38.4764534
OS 50.37695284 -38.46905692
OS 50.37880196 -38.46073588
OS 50.38157564 -38.45056572
OS 50.38434932 -38.44039556
OS 50.3917458 -38.41820612
OS 50.40284052 -38.39601668
OS 50.40931244 -38.38492196
OS 50.41763348 -38.37382724
OS 50.42595452 -38.36365708
OS 50.43520012 -38.35441148
OS 50.43612468 -38.35348692
OS 50.4379738 -38.35256236
OS 50.44074748 -38.34978868
OS 50.44537028 -38.347015
OS 50.45091764 -38.34331676
OS 50.45738956 -38.33961852
OS 50.46478604 -38.33499572
OS 50.47403164 -38.33037292
OS 50.4842018 -38.32575012
OS 50.49529652 -38.32112732
OS 50.5073158 -38.31742908
OS 50.52025964 -38.31373084
OS 50.53412804 -38.31095716
OS 50.548921 -38.30818348
OS 50.56463852 -38.30725892
OS 50.5812806 -38.30633436
OS 50.5905262 -38.30633436
OS 50.59699812 -38.30725892
OE
OB 51.0944114 -38.30725892 I
OS 51.10643068 -38.30910804
OS 51.12029908 -38.31188172
OS 51.13509204 -38.31557996
OS 51.15080956 -38.32020276
OS 51.16560252 -38.32759924
OS 51.16652708 -38.32759924
OS 51.16745164 -38.3285238
OS 51.17207444 -38.33129748
OS 51.17947092 -38.33592028
OS 51.18871652 -38.3423922
OS 51.19888668 -38.3516378
OS 51.2099814 -38.36180796
OS 51.22015156 -38.37382724
OS 51.23032172 -38.38769564
OS 51.23124628 -38.38954476
OS 51.23494452 -38.39416756
OS 51.23864276 -38.4024886
OS 51.24511468 -38.41450788
OS 51.25066204 -38.42837628
OS 51.25805852 -38.4440938
OS 51.26453044 -38.462585
OS 51.2700778 -38.48292532
OS 51.2700778 -38.48384988
OS 51.27100236 -38.485699
OS 51.27192692 -38.48847268
OS 51.27285148 -38.49309548
OS 51.27377604 -38.49864284
OS 51.2747006 -38.50511476
OS 51.27654972 -38.5134358
OS 51.27747428 -38.5226814
OS 51.2793234 -38.53285156
OS 51.28024796 -38.54394628
OS 51.28117252 -38.55689012
OS 51.28302164 -38.56983396
OS 51.2839462 -38.58462692
OS 51.2839462 -38.59941988
OS 51.28487076 -38.61606196
OS 51.28487076 -38.6336286
OS 51.28487076 -38.63455316
OS 51.28487076 -38.6382514
OS 51.28487076 -38.64472332
OS 51.28487076 -38.6521198
OS 51.2839462 -38.66228996
OS 51.2839462 -38.67338468
OS 51.28302164 -38.68540396
OS 51.28209708 -38.6983478
OS 51.2793234 -38.72793372
OS 51.2747006 -38.7584442
OS 51.26915324 -38.78803012
OS 51.265455 -38.80189852
OS 51.2608322 -38.81576692
OS 51.2608322 -38.81669148
OS 51.25990764 -38.8185406
OS 51.25805852 -38.82223884
OS 51.2562094 -38.82686164
OS 51.25436028 -38.83333356
OS 51.25066204 -38.83980548
OS 51.24326556 -38.855523
OS 51.23401996 -38.87216508
OS 51.22200068 -38.89065628
OS 51.20813228 -38.90729836
OS 51.1914902 -38.92301588
OS 51.19056564 -38.92301588
OS 51.18964108 -38.924865
OS 51.1868674 -38.92671412
OS 51.18316916 -38.92856324
OS 51.17854636 -38.93133692
OS 51.17392356 -38.93503516
OS 51.16005516 -38.94150708
OS 51.14341308 -38.947979
OS 51.12399732 -38.95445092
OS 51.10088332 -38.95814916
OS 51.0759202 -38.95999828
OS 51.0666746 -38.95999828
OS 51.06020268 -38.95907372
OS 51.0528062 -38.95814916
OS 51.0435606 -38.95630004
OS 51.03339044 -38.95445092
OS 51.02229572 -38.95167724
OS 51.011201 -38.947979
OS 50.99918172 -38.94428076
OS 50.98716244 -38.9387334
OS 50.97514316 -38.93226148
OS 50.96312388 -38.924865
OS 50.9511046 -38.9156194
OS 50.94000988 -38.90544924
OS 50.92983972 -38.89435452
OS 50.92891516 -38.89342996
OS 50.92706604 -38.89065628
OS 50.92429236 -38.88603348
OS 50.91966956 -38.878637
OS 50.91504676 -38.87031596
OS 50.91042396 -38.85922124
OS 50.90395204 -38.8462774
OS 50.89840468 -38.83148444
OS 50.89285732 -38.81484236
OS 50.88730996 -38.7954266
OS 50.8817626 -38.77416172
OS 50.8771398 -38.75012316
OS 50.872517 -38.72423548
OS 50.86974332 -38.69649868
OS 50.8678942 -38.6659882
OS 50.86696964 -38.6336286
OS 50.86696964 -38.63270404
OS 50.86696964 -38.6290058
OS 50.86696964 -38.62253388
OS 50.86696964 -38.6151374
OS 50.8678942 -38.60496724
OS 50.8678942 -38.59387252
OS 50.86881876 -38.58185324
OS 50.86974332 -38.56798484
OS 50.872517 -38.53932348
OS 50.8771398 -38.508813
OS 50.88268716 -38.47830252
OS 50.8863854 -38.46443412
OS 50.89008364 -38.45056572
OS 50.89008364 -38.44964116
OS 50.8910082 -38.44779204
OS 50.89285732 -38.4440938
OS 50.89470644 -38.439471
OS 50.89655556 -38.43299908
OS 50.9002538 -38.42652716
OS 50.90765028 -38.41080964
OS 50.91689588 -38.39416756
OS 50.92891516 -38.37660092
OS 50.94278356 -38.35903428
OS 50.95942564 -38.34424132
OS 50.9603502 -38.34424132
OS 50.96127476 -38.3423922
OS 50.96404844 -38.34054308
OS 50.96774668 -38.33869396
OS 50.97236948 -38.33499572
OS 50.97791684 -38.33222204
OS 50.99178524 -38.32482556
OS 51.00842732 -38.31835364
OS 51.02784308 -38.31188172
OS 51.05095708 -38.30818348
OS 51.0759202 -38.30633436
OS 51.08424124 -38.30633436
OS 51.0944114 -38.30725892
OE
OB 51.59182468 -38.30725892 I
OS 51.59922116 -38.30818348
OS 51.60846676 -38.30910804
OS 51.61863692 -38.31095716
OS 51.62880708 -38.31280628
OS 51.65284564 -38.3192782
OS 51.6768842 -38.3285238
OS 51.68890348 -38.33407116
OS 51.70092276 -38.34054308
OS 51.71201748 -38.34886412
OS 51.72218764 -38.35810972
OS 51.7231122 -38.35903428
OS 51.72496132 -38.35995884
OS 51.72681044 -38.36365708
OS 51.73050868 -38.36735532
OS 51.73513148 -38.37197812
OS 51.73975428 -38.37845004
OS 51.74437708 -38.38492196
OS 51.74992444 -38.393243
OS 51.75917004 -38.41080964
OS 51.76841564 -38.43299908
OS 51.77211388 -38.4440938
OS 51.773963 -38.45703764
OS 51.77581212 -38.46998148
OS 51.77673668 -38.48384988
OS 51.77673668 -38.485699
OS 51.77673668 -38.4903218
OS 51.77581212 -38.49771828
OS 51.77488756 -38.50788844
OS 51.77303844 -38.51898316
OS 51.7693402 -38.531927
OS 51.76564196 -38.5457954
OS 51.7600946 -38.5596638
OS 51.75917004 -38.56151292
OS 51.75732092 -38.56613572
OS 51.75362268 -38.5735322
OS 51.74807532 -38.58370236
OS 51.74067884 -38.59479708
OS 51.73143324 -38.60866548
OS 51.72033852 -38.62253388
OS 51.70739468 -38.6382514
OS 51.70554556 -38.64010052
OS 51.70092276 -38.64564788
OS 51.69629996 -38.65027068
OS 51.69167716 -38.65489348
OS 51.6861298 -38.66044084
OS 51.67873332 -38.66783732
OS 51.67133684 -38.6752338
OS 51.66209124 -38.68355484
OS 51.65284564 -38.69280044
OS 51.64175092 -38.7029706
OS 51.62973164 -38.71314076
OS 51.6167878 -38.72516004
OS 51.60199484 -38.73717932
OS 51.58720188 -38.75012316
OS 51.58627732 -38.75104772
OS 51.5844282 -38.75289684
OS 51.58072996 -38.75567052
OS 51.57610716 -38.75936876
OS 51.5705598 -38.76491612
OS 51.56408788 -38.77046348
OS 51.54929492 -38.78248276
OS 51.5335774 -38.79635116
OS 51.51878444 -38.81021956
OS 51.5058406 -38.82223884
OS 51.50029324 -38.82686164
OS 51.49567044 -38.83148444
OS 51.49474588 -38.832409
OS 51.4919722 -38.83518268
OS 51.48827396 -38.83888092
OS 51.48365116 -38.84442828
OS 51.47902836 -38.8509002
OS 51.473481 -38.85737212
OS 51.46238628 -38.87308964
OS 51.77766124 -38.87308964
OS 51.77766124 -38.94890356
OS 51.3532882 -38.94890356
OS 51.3532882 -38.947979
OS 51.3532882 -38.94428076
OS 51.3532882 -38.9387334
OS 51.35421276 -38.93133692
OS 51.35513732 -38.92301588
OS 51.35698644 -38.91377028
OS 51.35883556 -38.90452468
OS 51.3625338 -38.89435452
OS 51.3625338 -38.89342996
OS 51.36345836 -38.8925054
OS 51.36530748 -38.88695804
OS 51.36900572 -38.878637
OS 51.37455308 -38.86754228
OS 51.38194956 -38.85459844
OS 51.39119516 -38.83980548
OS 51.40136532 -38.82501252
OS 51.41430916 -38.809295
OS 51.41430916 -38.80837044
OS 51.41615828 -38.80744588
OS 51.42078108 -38.80189852
OS 51.42910212 -38.79357748
OS 51.4411214 -38.7815582
OS 51.4549898 -38.7676898
OS 51.47255644 -38.75104772
OS 51.49382132 -38.73255652
OS 51.51693532 -38.71314076
OS 51.51785988 -38.7122162
OS 51.52155812 -38.70944252
OS 51.52710548 -38.70481972
OS 51.5335774 -38.69927236
OS 51.54189844 -38.69187588
OS 51.5520686 -38.68355484
OS 51.56223876 -38.67430924
OS 51.57425804 -38.66413908
OS 51.59737204 -38.64194964
OS 51.62048604 -38.6197602
OS 51.63158076 -38.60866548
OS 51.64175092 -38.59757076
OS 51.65099652 -38.5874006
OS 51.658393 -38.57723044
OS 51.658393 -38.57630588
OS 51.66024212 -38.57538132
OS 51.66209124 -38.57260764
OS 51.66394036 -38.5689094
OS 51.67041228 -38.55873924
OS 51.67780876 -38.54671996
OS 51.68428068 -38.531927
OS 51.6907526 -38.51620948
OS 51.69445084 -38.49864284
OS 51.69629996 -38.48200076
OS 51.69629996 -38.4810762
OS 51.69629996 -38.48015164
OS 51.6953754 -38.47460428
OS 51.69445084 -38.46535868
OS 51.69167716 -38.45518852
OS 51.68797892 -38.44224468
OS 51.681507 -38.42930084
OS 51.67318596 -38.416357
OS 51.66209124 -38.40341316
OS 51.66024212 -38.40156404
OS 51.65561932 -38.3978658
OS 51.6491474 -38.393243
OS 51.63897724 -38.38677108
OS 51.6260334 -38.38122372
OS 51.61124044 -38.37567636
OS 51.5936738 -38.37197812
OS 51.57425804 -38.37105356
OS 51.56871068 -38.37105356
OS 51.56501244 -38.37197812
OS 51.55391772 -38.37290268
OS 51.54097388 -38.37567636
OS 51.52710548 -38.3793746
OS 51.51138796 -38.38584652
OS 51.496595 -38.39416756
OS 51.4827266 -38.40526228
OS 51.48087748 -38.4071114
OS 51.47717924 -38.4117342
OS 51.47163188 -38.41913068
OS 51.46608452 -38.4302254
OS 51.4596126 -38.44316924
OS 51.45406524 -38.45981132
OS 51.450367 -38.47830252
OS 51.44851788 -38.4995674
OS 51.36808116 -38.49124636
OS 51.36808116 -38.4903218
OS 51.36900572 -38.48754812
OS 51.36900572 -38.48292532
OS 51.36993028 -38.4764534
OS 51.3717794 -38.46905692
OS 51.37362852 -38.46073588
OS 51.3764022 -38.45056572
OS 51.37917588 -38.44039556
OS 51.38657236 -38.41820612
OS 51.39766708 -38.39601668
OS 51.404139 -38.38492196
OS 51.41246004 -38.37382724
OS 51.42078108 -38.36365708
OS 51.43002668 -38.35441148
OS 51.43095124 -38.35348692
OS 51.43280036 -38.35256236
OS 51.43557404 -38.34978868
OS 51.44019684 -38.347015
OS 51.4457442 -38.34331676
OS 51.45221612 -38.33961852
OS 51.4596126 -38.33499572
OS 51.4688582 -38.33037292
OS 51.47902836 -38.32575012
OS 51.49012308 -38.32112732
OS 51.50214236 -38.31742908
OS 51.5150862 -38.31373084
OS 51.5289546 -38.31095716
OS 51.54374756 -38.30818348
OS 51.55946508 -38.30725892
OS 51.57610716 -38.30633436
OS 51.58535276 -38.30633436
OS 51.59182468 -38.30725892
OE
OB 52.08184148 -38.30725892 I
OS 52.09386076 -38.30910804
OS 52.10865372 -38.31188172
OS 52.1252958 -38.31650452
OS 52.14193788 -38.32205188
OS 52.15857996 -38.32944836
OS 52.15950452 -38.32944836
OS 52.16042908 -38.33037292
OS 52.16597644 -38.3331466
OS 52.17429748 -38.33869396
OS 52.18354308 -38.34516588
OS 52.1946378 -38.35441148
OS 52.20573252 -38.36458164
OS 52.21682724 -38.37660092
OS 52.22607284 -38.39046932
OS 52.2269974 -38.39231844
OS 52.22977108 -38.39694124
OS 52.23346932 -38.40526228
OS 52.23809212 -38.41543244
OS 52.24271492 -38.42745172
OS 52.24641316 -38.44132012
OS 52.24918684 -38.45703764
OS 52.2501114 -38.47275516
OS 52.2501114 -38.47460428
OS 52.2501114 -38.48015164
OS 52.24918684 -38.48754812
OS 52.24733772 -38.49771828
OS 52.24456404 -38.50973756
OS 52.23994124 -38.5226814
OS 52.23439388 -38.53562524
OS 52.2269974 -38.54856908
OS 52.22607284 -38.5504182
OS 52.22329916 -38.55411644
OS 52.2177518 -38.56058836
OS 52.21035532 -38.56798484
OS 52.20110972 -38.57630588
OS 52.190015 -38.58555148
OS 52.17707116 -38.59387252
OS 52.16135364 -38.60219356
OS 52.1622782 -38.60219356
OS 52.16412732 -38.60311812
OS 52.166901 -38.60404268
OS 52.17059924 -38.60496724
OS 52.1807694 -38.60866548
OS 52.19371324 -38.61421284
OS 52.2085062 -38.62160932
OS 52.22329916 -38.63085492
OS 52.23716756 -38.6428742
OS 52.2501114 -38.6567426
OS 52.25103596 -38.65859172
OS 52.2547342 -38.66413908
OS 52.26028156 -38.67338468
OS 52.26582892 -38.68540396
OS 52.27137628 -38.70019692
OS 52.27692364 -38.71776356
OS 52.28062188 -38.73810388
OS 52.28154644 -38.76029332
OS 52.28154644 -38.76121788
OS 52.28154644 -38.76399156
OS 52.28154644 -38.76861436
OS 52.28062188 -38.77416172
OS 52.27969732 -38.7815582
OS 52.2778482 -38.78987924
OS 52.27599908 -38.79912484
OS 52.27414996 -38.809295
OS 52.26675348 -38.83148444
OS 52.26120612 -38.84350372
OS 52.25565876 -38.85459844
OS 52.24826228 -38.86661772
OS 52.23994124 -38.878637
OS 52.23069564 -38.89065628
OS 52.21960092 -38.901751
OS 52.21867636 -38.90267556
OS 52.21682724 -38.90452468
OS 52.213129 -38.90729836
OS 52.2085062 -38.9109966
OS 52.20295884 -38.9156194
OS 52.19556236 -38.9202422
OS 52.18724132 -38.92578956
OS 52.17707116 -38.93041236
OS 52.166901 -38.93595972
OS 52.15488172 -38.94150708
OS 52.14286244 -38.94612988
OS 52.12899404 -38.95075268
OS 52.11420108 -38.95445092
OS 52.09848356 -38.9572246
OS 52.08276604 -38.95907372
OS 52.0651994 -38.95999828
OS 52.05687836 -38.95999828
OS 52.051331 -38.95907372
OS 52.04393452 -38.95814916
OS 52.03561348 -38.9572246
OS 52.02636788 -38.95537548
OS 52.01619772 -38.95352636
OS 51.99400828 -38.947979
OS 51.97089428 -38.9387334
OS 51.958875 -38.93318604
OS 51.94778028 -38.92671412
OS 51.93668556 -38.91839308
OS 51.92559084 -38.91007204
OS 51.92466628 -38.90914748
OS 51.92281716 -38.90729836
OS 51.92004348 -38.90452468
OS 51.9172698 -38.90082644
OS 51.912647 -38.89620364
OS 51.9080242 -38.88973172
OS 51.90247684 -38.8832598
OS 51.89692948 -38.87493876
OS 51.89138212 -38.86569316
OS 51.88583476 -38.85644756
OS 51.8756646 -38.83425812
OS 51.86734356 -38.80837044
OS 51.86456988 -38.79450204
OS 51.86272076 -38.77970908
OS 51.94130836 -38.76953892
OS 51.94130836 -38.77046348
OS 51.94223292 -38.7723126
OS 51.94315748 -38.77601084
OS 51.94408204 -38.78063364
OS 51.9450066 -38.786181
OS 51.94685572 -38.79265292
OS 51.95147852 -38.80652132
OS 51.95795044 -38.8231634
OS 51.96627148 -38.83888092
OS 51.97551708 -38.85367388
OS 51.9866118 -38.86661772
OS 51.98846092 -38.86754228
OS 51.99215916 -38.87124052
OS 51.99955564 -38.87586332
OS 52.00880124 -38.88048612
OS 52.01989596 -38.88603348
OS 52.03376436 -38.89065628
OS 52.04948188 -38.89435452
OS 52.06612396 -38.89527908
OS 52.07167132 -38.89527908
OS 52.07536956 -38.89435452
OS 52.08553972 -38.89342996
OS 52.09848356 -38.89065628
OS 52.11327652 -38.88603348
OS 52.12899404 -38.87956156
OS 52.14471156 -38.87031596
OS 52.15950452 -38.85737212
OS 52.16135364 -38.855523
OS 52.16597644 -38.84997564
OS 52.1715238 -38.8416546
OS 52.17892028 -38.83055988
OS 52.18631676 -38.81669148
OS 52.19186412 -38.80097396
OS 52.19648692 -38.78248276
OS 52.19833604 -38.76214244
OS 52.19833604 -38.76121788
OS 52.19833604 -38.75936876
OS 52.19833604 -38.75659508
OS 52.19741148 -38.75289684
OS 52.19648692 -38.74272668
OS 52.19371324 -38.7307074
OS 52.190015 -38.71591444
OS 52.18354308 -38.70112148
OS 52.17429748 -38.68632852
OS 52.1622782 -38.67246012
OS 52.16042908 -38.670611
OS 52.15580628 -38.66691276
OS 52.1484098 -38.6613654
OS 52.13823964 -38.65489348
OS 52.1252958 -38.64842156
OS 52.10957828 -38.6428742
OS 52.09201164 -38.63917596
OS 52.07259588 -38.63732684
OS 52.06427484 -38.63732684
OS 52.05780292 -38.6382514
OS 52.04948188 -38.63917596
OS 52.04023628 -38.64102508
OS 52.02914156 -38.6428742
OS 52.01712228 -38.64564788
OS 52.02636788 -38.57630588
OS 52.03099068 -38.57630588
OS 52.03468892 -38.57723044
OS 52.0467082 -38.57723044
OS 52.05687836 -38.57538132
OS 52.06889764 -38.5735322
OS 52.08276604 -38.57075852
OS 52.09848356 -38.56613572
OS 52.11327652 -38.5596638
OS 52.12899404 -38.55134276
OS 52.1299186 -38.55134276
OS 52.13084316 -38.5504182
OS 52.13546596 -38.54671996
OS 52.14193788 -38.54024804
OS 52.14933436 -38.531927
OS 52.15673084 -38.51990772
OS 52.16320276 -38.50603932
OS 52.16782556 -38.4903218
OS 52.16967468 -38.4810762
OS 52.16967468 -38.47090604
OS 52.16967468 -38.46998148
OS 52.16967468 -38.46905692
OS 52.16967468 -38.46350956
OS 52.16782556 -38.45611308
OS 52.16597644 -38.44594292
OS 52.1622782 -38.4348482
OS 52.1576554 -38.42282892
OS 52.15025892 -38.41080964
OS 52.14008876 -38.39971492
OS 52.1391642 -38.39879036
OS 52.1345414 -38.39509212
OS 52.12806948 -38.39046932
OS 52.11974844 -38.38492196
OS 52.10865372 -38.38029916
OS 52.09570988 -38.37567636
OS 52.08091692 -38.37197812
OS 52.06427484 -38.37105356
OS 52.05687836 -38.37105356
OS 52.04855732 -38.37290268
OS 52.0374626 -38.3747518
OS 52.02544332 -38.37845004
OS 52.01342404 -38.38307284
OS 52.0004802 -38.39046932
OS 51.98846092 -38.39971492
OS 51.98753636 -38.40063948
OS 51.98383812 -38.40526228
OS 51.97829076 -38.4117342
OS 51.97181884 -38.4209798
OS 51.96534692 -38.43299908
OS 51.958875 -38.44779204
OS 51.95332764 -38.46535868
OS 51.9496294 -38.485699
OS 51.8710418 -38.4718306
OS 51.8710418 -38.47090604
OS 51.87196636 -38.46813236
OS 51.87289092 -38.46443412
OS 51.87381548 -38.45888676
OS 51.8756646 -38.45241484
OS 51.87843828 -38.44501836
OS 51.88398564 -38.42745172
OS 51.89323124 -38.4071114
OS 51.90432596 -38.38677108
OS 51.91819436 -38.36735532
OS 51.935761 -38.34978868
OS 51.93668556 -38.34886412
OS 51.93853468 -38.34793956
OS 51.94130836 -38.34609044
OS 51.9450066 -38.34331676
OS 51.9496294 -38.33961852
OS 51.95610132 -38.33592028
OS 51.96257324 -38.33222204
OS 51.97089428 -38.32759924
OS 51.98938548 -38.32020276
OS 52.01065036 -38.31280628
OS 52.03561348 -38.30818348
OS 52.04855732 -38.30633436
OS 52.07167132 -38.30633436
OS 52.08184148 -38.30725892
OE
OB 51.07499564 -38.37105356 H
OS 51.06944828 -38.37105356
OS 51.06575004 -38.37197812
OS 51.05557988 -38.37382724
OS 51.0435606 -38.37660092
OS 51.0296922 -38.38214828
OS 51.01489924 -38.39046932
OS 51.00750276 -38.39601668
OS 51.00010628 -38.40156404
OS 50.99363436 -38.40896052
OS 50.98716244 -38.41728156
OS 50.98716244 -38.41820612
OS 50.98531332 -38.42005524
OS 50.9834642 -38.42375348
OS 50.98069052 -38.42837628
OS 50.97791684 -38.43577276
OS 50.9742186 -38.4440938
OS 50.97144492 -38.45426396
OS 50.96774668 -38.46628324
OS 50.96404844 -38.48015164
OS 50.9603502 -38.49586916
OS 50.95665196 -38.5134358
OS 50.95387828 -38.53285156
OS 50.9511046 -38.555041
OS 50.94925548 -38.57907956
OS 50.94833092 -38.60496724
OS 50.94740636 -38.6336286
OS 50.94740636 -38.63547772
OS 50.94740636 -38.64010052
OS 50.94740636 -38.64842156
OS 50.94833092 -38.65951628
OS 50.94833092 -38.67153556
OS 50.94925548 -38.68632852
OS 50.95018004 -38.70204604
OS 50.95202916 -38.71868812
OS 50.95665196 -38.75474596
OS 50.95942564 -38.7723126
OS 50.96312388 -38.78895468
OS 50.96682212 -38.8046722
OS 50.97236948 -38.81946516
OS 50.97791684 -38.832409
OS 50.98438876 -38.84350372
OS 50.98438876 -38.84442828
OS 50.98623788 -38.84535284
OS 50.99086068 -38.85182476
OS 50.99918172 -38.8601458
OS 51.00935188 -38.8693914
OS 51.02322028 -38.878637
OS 51.0389378 -38.88695804
OS 51.05650444 -38.89342996
OS 51.06575004 -38.89435452
OS 51.0759202 -38.89527908
OS 51.08146756 -38.89527908
OS 51.0851658 -38.89435452
OS 51.0944114 -38.8925054
OS 51.10735524 -38.88880716
OS 51.12122364 -38.88233524
OS 51.13694116 -38.87308964
OS 51.14433764 -38.86754228
OS 51.15173412 -38.8601458
OS 51.1591306 -38.85274932
OS 51.16652708 -38.84350372
OS 51.16652708 -38.84257916
OS 51.1683762 -38.84073004
OS 51.17022532 -38.83795636
OS 51.17207444 -38.83333356
OS 51.17577268 -38.82686164
OS 51.17854636 -38.8185406
OS 51.1822446 -38.809295
OS 51.18594284 -38.79820028
OS 51.18871652 -38.78433188
OS 51.19241476 -38.76953892
OS 51.196113 -38.75197228
OS 51.19888668 -38.73348108
OS 51.2007358 -38.71129164
OS 51.20258492 -38.68817764
OS 51.20443404 -38.66228996
OS 51.20443404 -38.6336286
OS 51.20443404 -38.63270404
OS 51.20443404 -38.63177948
OS 51.20443404 -38.62715668
OS 51.20443404 -38.61883564
OS 51.20350948 -38.60774092
OS 51.20350948 -38.59572164
OS 51.20258492 -38.58092868
OS 51.20166036 -38.56521116
OS 51.19981124 -38.54764452
OS 51.19518844 -38.51251124
OS 51.19241476 -38.4949446
OS 51.18871652 -38.47830252
OS 51.18501828 -38.462585
OS 51.17947092 -38.44779204
OS 51.17392356 -38.4348482
OS 51.16745164 -38.42375348
OS 51.16745164 -38.42282892
OS 51.16560252 -38.42190436
OS 51.1637534 -38.41913068
OS 51.16097972 -38.41543244
OS 51.15265868 -38.4071114
OS 51.14248852 -38.39694124
OS 51.12862012 -38.38769564
OS 51.1129026 -38.3793746
OS 51.10458156 -38.37567636
OS 51.09533596 -38.37290268
OS 51.0851658 -38.37197812
OS 51.07499564 -38.37105356
OE
OB 54.05947532 -38.37105356 H
OS 54.05392796 -38.37105356
OS 54.05022972 -38.37197812
OS 54.04005956 -38.37382724
OS 54.02804028 -38.37660092
OS 54.01417188 -38.38214828
OS 53.99937892 -38.39046932
OS 53.99198244 -38.39601668
OS 53.98458596 -38.40156404
OS 53.97811404 -38.40896052
OS 53.97164212 -38.41728156
OS 53.97164212 -38.41820612
OS 53.969793 -38.42005524
OS 53.96794388 -38.42375348
OS 53.9651702 -38.42837628
OS 53.96239652 -38.43577276
OS 53.95869828 -38.4440938
OS 53.9559246 -38.45426396
OS 53.95222636 -38.46628324
OS 53.94852812 -38.48015164
OS 53.94482988 -38.49586916
OS 53.94113164 -38.5134358
OS 53.93835796 -38.53285156
OS 53.93558428 -38.555041
OS 53.93373516 -38.57907956
OS 53.9328106 -38.60496724
OS 53.93188604 -38.6336286
OS 53.93188604 -38.63547772
OS 53.93188604 -38.64010052
OS 53.93188604 -38.64842156
OS 53.9328106 -38.65951628
OS 53.9328106 -38.67153556
OS 53.93373516 -38.68632852
OS 53.93465972 -38.70204604
OS 53.93650884 -38.71868812
OS 53.94113164 -38.75474596
OS 53.94390532 -38.7723126
OS 53.94760356 -38.78895468
OS 53.9513018 -38.8046722
OS 53.95684916 -38.81946516
OS 53.96239652 -38.832409
OS 53.96886844 -38.84350372
OS 53.96886844 -38.84442828
OS 53.97071756 -38.84535284
OS 53.97534036 -38.85182476
OS 53.9836614 -38.8601458
OS 53.99383156 -38.8693914
OS 54.00769996 -38.878637
OS 54.02341748 -38.88695804
OS 54.04098412 -38.89342996
OS 54.05022972 -38.89435452
OS 54.06039988 -38.89527908
OS 54.06594724 -38.89527908
OS 54.06964548 -38.89435452
OS 54.07889108 -38.8925054
OS 54.09183492 -38.88880716
OS 54.10570332 -38.88233524
OS 54.12142084 -38.87308964
OS 54.12881732 -38.86754228
OS 54.1362138 -38.8601458
OS 54.14361028 -38.85274932
OS 54.15100676 -38.84350372
OS 54.15100676 -38.84257916
OS 54.15285588 -38.84073004
OS 54.154705 -38.83795636
OS 54.15655412 -38.83333356
OS 54.16025236 -38.82686164
OS 54.16302604 -38.8185406
OS 54.16672428 -38.809295
OS 54.17042252 -38.79820028
OS 54.1731962 -38.78433188
OS 54.17689444 -38.76953892
OS 54.18059268 -38.75197228
OS 54.18336636 -38.73348108
OS 54.18521548 -38.71129164
OS 54.1870646 -38.68817764
OS 54.18891372 -38.66228996
OS 54.18891372 -38.6336286
OS 54.18891372 -38.63270404
OS 54.18891372 -38.63177948
OS 54.18891372 -38.62715668
OS 54.18891372 -38.61883564
OS 54.18798916 -38.60774092
OS 54.18798916 -38.59572164
OS 54.1870646 -38.58092868
OS 54.18614004 -38.56521116
OS 54.18429092 -38.54764452
OS 54.17966812 -38.51251124
OS 54.17689444 -38.4949446
OS 54.1731962 -38.47830252
OS 54.16949796 -38.462585
OS 54.1639506 -38.44779204
OS 54.15840324 -38.4348482
OS 54.15193132 -38.42375348
OS 54.15193132 -38.42282892
OS 54.1500822 -38.42190436
OS 54.14823308 -38.41913068
OS 54.1454594 -38.41543244
OS 54.13713836 -38.4071114
OS 54.1269682 -38.39694124
OS 54.1130998 -38.38769564
OS 54.09738228 -38.3793746
OS 54.08906124 -38.37567636
OS 54.07981564 -38.37290268
OS 54.06964548 -38.37197812
OS 54.05947532 -38.37105356
OE
OB 49.87491676 -38.43669732 H
OS 49.67336268 -38.72331092
OS 49.87491676 -38.72331092
OS 49.87491676 -38.43669732
OE
OB 56.14158444 -38.38492196 H
OS 55.95852156 -38.38492196
OS 55.95852156 -38.61328828
OS 56.13048972 -38.61328828
OS 56.13696164 -38.61236372
OS 56.14343356 -38.61236372
OS 56.15083004 -38.61143916
OS 56.16839668 -38.60959004
OS 56.18781244 -38.6058918
OS 56.2072282 -38.60034444
OS 56.22479484 -38.59294796
OS 56.23311588 -38.58832516
OS 56.2395878 -38.5827778
OS 56.24143692 -38.58092868
OS 56.24513516 -38.57723044
OS 56.25068252 -38.56983396
OS 56.25715444 -38.56058836
OS 56.26362636 -38.54856908
OS 56.26917372 -38.53377612
OS 56.27287196 -38.51713404
OS 56.27472108 -38.49771828
OS 56.27472108 -38.49679372
OS 56.27472108 -38.49586916
OS 56.27472108 -38.49124636
OS 56.27379652 -38.48292532
OS 56.2719474 -38.47367972
OS 56.27009828 -38.46350956
OS 56.26640004 -38.45149028
OS 56.26085268 -38.44039556
OS 56.25438076 -38.42930084
OS 56.2534562 -38.42837628
OS 56.25068252 -38.42467804
OS 56.24605972 -38.42005524
OS 56.24051236 -38.41358332
OS 56.23219132 -38.4071114
OS 56.22294572 -38.40156404
OS 56.21277556 -38.39601668
OS 56.20075628 -38.39139388
OS 56.19983172 -38.39139388
OS 56.19613348 -38.39046932
OS 56.19058612 -38.38954476
OS 56.18318964 -38.38769564
OS 56.17209492 -38.38677108
OS 56.15822652 -38.38584652
OS 56.14158444 -38.38492196
OE
SE

### steps/pcb/layers/bottom_paste/features
UNITS=MM
#Layer_Color=128
#
#Feature symbol names
#
$0 r99.9998
$1 rect1050.00044x1749.99904
$2 rect1050.00044x900.00074
$3 rect569.99886x619.99876
$4 rect419.99916x439.99912
$5 r6200.0003
$6 rect2300.00048x3300.00102
$7 rect800.00094x1449.99964
$8 rect599.9988x299.9994
$9 rect299.9994x1725.00036
$10 rect1299.99994x1649.99924
$11 rect599.9988x619.99876
$12 rect459.99908x419.99916
$13 rect419.99916x459.99908
$14 rect619.99876x599.9988
$15 rect619.99876x569.99886

#
#Feature attribute names
#
@0 .nomenclature
@1 .string
@2 .string_angle
@3 .geometry
@4 .pad_usage

#
#Feature attribute text strings
#
&0 SMD_RectX1050.0004Y1749.9990
&1 SMD_RectX1050.0004Y900.0007
&2 SMD_RectX569.9989Y619.9988
&3 SMD_RectX419.9992Y439.9991
&4 SMD_RoundX6200.0003Y6200.0003
&5 SMD_RectX2300.0005Y3300.0010
&6 SMD_RectX800.0009Y1449.9996
&7 SMD_RectX599.9988Y299.9994
&8 SMD_RectX299.9994Y1725.0004
&9 SMD_RectX1299.9999Y1649.9992
&10 SMD_RectX599.9988Y619.9988
&11 SMD_RectX459.9991Y419.9992
&12 SMD_RectX419.9992Y459.9991
&13 SMD_RectX619.9988Y599.9988
&14 SMD_RectX619.9988Y569.9989

#
#Layer features
#
L -9.5600012 -24.45999934 40.4400004 -24.45999934 0 P 0
L -9.5600012 -35.9599992 -9.5600012 -24.45999934 0 P 0
L -9.5600012 -35.9599992 28.439999 -35.9599992 0 P 0
L -9.5600012 -39.45999982 -9.5600012 -35.9599992 0 P 0
L -9.5600012 -39.45999982 28.439999 -39.45999982 0 P 0
L -9.5600012 -42.96000044 -9.5600012 -39.45999982 0 P 0
L -9.5600012 -42.96000044 28.439999 -42.96000044 0 P 0
L -10.0600002 -23.96000034 62.93999858 -23.96000034 0 P 0
L -10.0600002 -43.45999944 -10.0600002 -23.96000034 0 P 0
L -10.0600002 -43.45999944 62.93999858 -43.45999944 0 P 0
L 28.439999 -35.96000174 45.44000056 -35.9599992 0 P 0
L 28.439999 -39.45999982 28.439999 -35.9599992 0 P 0
L 28.439999 -39.46000236 45.44000056 -39.45999982 0 P 0
L 28.439999 -42.96000044 28.439999 -39.45999982 0 P 0
L 28.439999 -42.96000298 45.44000056 -42.96000044 0 P 0
L 40.4400004 -24.45999934 62.43999958 -24.45999934 0 P 0
L 40.4400004 -35.9599992 40.4400004 -24.45999934 0 P 0
L 45.44000056 -35.9599992 62.43999958 -35.9599992 0 P 0
L 45.44000056 -39.45999982 62.43999958 -39.45999982 0 P 0
L 45.44000056 -42.96000044 45.44000056 -35.9599992 0 P 0
L 45.44000056 -42.96000044 62.43999958 -42.96000044 0 P 0
L 62.43999958 -35.9599992 62.43999958 -24.45999934 0 P 0
L 62.43999958 -42.96000044 62.43999958 -35.9599992 0 P 0
L 62.93999858 -43.45999944 62.93999858 -23.96000034 0 P 0
P 4.39999882 2.00000108 5 P 0 0 ;3=4,4=0
P 4.39999882 38.599999 5 P 0 0 ;3=4,4=0
P 13.9050014 18.0150008 3 P 0 0 ;3=2,4=0
P 13.9050014 19.16500104 3 P 0 0 ;3=2,4=0
P 14.86499948 18.0150008 3 P 0 0 ;3=2,4=0
P 14.86499948 19.16500104 3 P 0 0 ;3=2,4=0
P 14.86499948 20.21500148 13 P 0 0 ;3=12,4=0
P 14.86499948 20.87500016 13 P 0 0 ;3=12,4=0
P 15.86500002 20.21500148 4 P 0 0 ;3=3,4=0
P 15.86500002 20.89500012 4 P 0 0 ;3=3,4=0
P 15.91499992 7.38999792 10 P 0 0 ;3=9,4=0
P 15.91499992 9.7899982 10 P 0 0 ;3=9,4=0
P 15.91499992 12.39000062 10 P 0 0 ;3=9,4=0
P 16.29499916 22.29000114 12 P 0 0 ;3=11,4=0
P 16.31500166 18.04000202 8 P 0 0 ;3=7,4=0
P 16.31500166 18.49000112 8 P 0 0 ;3=7,4=0
P 16.31500166 18.94000276 8 P 0 0 ;3=7,4=0
P 16.41500146 16.99000158 7 P 0 0 ;3=6,4=0
P 16.65500352 14.7900009 11 P 0 0 ;3=10,4=0
P 16.95499784 20.21500148 15 P 0 0 ;3=14,4=0
P 16.95499784 21.17499956 15 P 0 0 ;3=14,4=0
P 16.95499784 22.29000114 12 P 0 0 ;3=11,4=0
P 17.1650025 16.85250122 9 P 0 0 ;3=8,4=0
P 17.57500168 14.7900009 11 P 0 0 ;3=10,4=0
P 17.7150014 7.38999792 10 P 0 0 ;3=9,4=0
P 17.7150014 9.7899982 10 P 0 0 ;3=9,4=0
P 17.7150014 12.39000062 10 P 0 0 ;3=9,4=0
P 17.915001 16.99000158 7 P 0 0 ;3=6,4=0
P 18.0150008 18.04000202 8 P 0 0 ;3=7,4=0
P 18.0150008 18.49000112 8 P 0 0 ;3=7,4=0
P 18.0150008 18.94000276 8 P 0 0 ;3=7,4=0
P 18.22000166 21.17499956 11 P 0 0 ;3=10,4=0
P 19.13999982 21.17499956 11 P 0 0 ;3=10,4=0
P 20.76500038 16.85250122 6 P 0 0 ;3=5,4=0
P 22.41500216 7.7900022 10 P 0 0 ;3=9,4=0
P 22.41500216 10.29000228 10 P 0 0 ;3=9,4=0
P 22.95500362 12.29000082 11 P 0 0 ;3=10,4=0
P 23.87500178 12.29000082 11 P 0 0 ;3=10,4=0
P 24.21500364 7.7900022 10 P 0 0 ;3=9,4=0
P 24.21500364 10.29000228 10 P 0 0 ;3=9,4=0
P 26.06499994 16.85250122 6 P 0 0 ;3=5,4=0
P 32.24000156 7.63999996 1 P 0 0 ;3=0,4=0
P 35.24000064 7.63999996 1 P 0 0 ;3=0,4=0
P 35.50000012 -1.00000054 5 P 0 0 ;3=4,4=0
P 36.20000126 40.10000108 5 P 0 0 ;3=4,4=0
P 37.8500005 9.94000044 11 P 0 0 ;3=10,4=0
P 38.76999866 9.94000044 11 P 0 0 ;3=10,4=0
P 39.78999916 14.51500018 2 P 0 0 ;3=1,4=0
P 39.78999916 15.96499982 2 P 0 0 ;3=1,4=0
P 40.0900011 7.63999996 14 P 0 0 ;3=13,4=0
P 40.0900011 8.55999812 14 P 0 0 ;3=13,4=0
S P 0
OB -2.41723418 -38.48662356 I
OS -2.41076226 -38.48754812
OS -2.39689386 -38.48939724
OS -2.38025178 -38.49309548
OS -2.36268514 -38.49864284
OS -2.3451185 -38.50696388
OS -2.32755186 -38.51713404
OS -2.3266273 -38.51713404
OS -2.32570274 -38.51898316
OS -2.32015538 -38.5226814
OS -2.31183434 -38.53007788
OS -2.30166418 -38.53932348
OS -2.29056946 -38.55134276
OS -2.27947474 -38.56613572
OS -2.26838002 -38.58370236
OS -2.25913442 -38.60311812
OS -2.25913442 -38.60404268
OS -2.25820986 -38.6058918
OS -2.2572853 -38.60866548
OS -2.25543618 -38.61236372
OS -2.25358706 -38.61791108
OS -2.25173794 -38.624383
OS -2.24711514 -38.63917596
OS -2.24249234 -38.65766716
OS -2.2387941 -38.67800748
OS -2.23602042 -38.70112148
OS -2.23509586 -38.72516004
OS -2.23509586 -38.7260846
OS -2.23509586 -38.72793372
OS -2.23509586 -38.73163196
OS -2.23509586 -38.73717932
OS -2.23602042 -38.74365124
OS -2.23602042 -38.75104772
OS -2.23786954 -38.7676898
OS -2.24156778 -38.78803012
OS -2.24619058 -38.809295
OS -2.2526625 -38.83148444
OS -2.26098354 -38.85367388
OS -2.26098354 -38.85459844
OS -2.2619081 -38.85644756
OS -2.26375722 -38.85922124
OS -2.26560634 -38.86291948
OS -2.27207826 -38.87308964
OS -2.2803993 -38.88603348
OS -2.29056946 -38.89990188
OS -2.3035133 -38.91377028
OS -2.31830626 -38.92763868
OS -2.3358729 -38.94058252
OS -2.33679746 -38.94058252
OS -2.33772202 -38.94150708
OS -2.3404957 -38.9433562
OS -2.34419394 -38.94520532
OS -2.35343954 -38.94982812
OS -2.36638338 -38.95537548
OS -2.3821009 -38.96092284
OS -2.39874298 -38.96554564
OS -2.41815874 -38.96924388
OS -2.4375745 -38.97016844
OS -2.44404642 -38.97016844
OS -2.4514429 -38.96924388
OS -2.4606885 -38.96831932
OS -2.47178322 -38.9664702
OS -2.4838025 -38.96369652
OS -2.49582178 -38.95999828
OS -2.50784106 -38.95445092
OS -2.50876562 -38.95352636
OS -2.51338842 -38.95167724
OS -2.51893578 -38.947979
OS -2.52633226 -38.94243164
OS -2.53372874 -38.93688428
OS -2.54297434 -38.9294878
OS -2.55129538 -38.92116676
OS -2.55869186 -38.91192116
OS -2.55869186 -39.1375138
OS -2.63727946 -39.1375138
OS -2.63727946 -38.49586916
OS -2.56608834 -38.49586916
OS -2.56608834 -38.55689012
OS -2.56516378 -38.555041
OS -2.56146554 -38.55134276
OS -2.55684274 -38.54487084
OS -2.54944626 -38.53747436
OS -2.54112522 -38.52822876
OS -2.53187962 -38.51990772
OS -2.5207849 -38.51158668
OS -2.50969018 -38.5041902
OS -2.50784106 -38.50326564
OS -2.50414282 -38.50141652
OS -2.49674634 -38.49864284
OS -2.48750074 -38.4949446
OS -2.47640602 -38.49124636
OS -2.46346218 -38.48847268
OS -2.44866922 -38.48662356
OS -2.43202714 -38.485699
OS -2.42185698 -38.485699
OS -2.41723418 -38.48662356
OE
OB -1.92351914 -38.48662356 I
OS -1.90965074 -38.48754812
OS -1.89393322 -38.48939724
OS -1.8782157 -38.49217092
OS -1.86249818 -38.49586916
OS -1.84770522 -38.50049196
OS -1.8458561 -38.50141652
OS -1.8412333 -38.50326564
OS -1.83476138 -38.50603932
OS -1.82644034 -38.50973756
OS -1.81719474 -38.51528492
OS -1.80794914 -38.52083228
OS -1.7996281 -38.52822876
OS -1.79223162 -38.53562524
OS -1.79130706 -38.5365498
OS -1.78945794 -38.53932348
OS -1.78668426 -38.54394628
OS -1.78298602 -38.54949364
OS -1.77836322 -38.55781468
OS -1.77466498 -38.56613572
OS -1.77096674 -38.57630588
OS -1.76819306 -38.58832516
OS -1.76819306 -38.58924972
OS -1.7672685 -38.5920234
OS -1.76634394 -38.59757076
OS -1.76541938 -38.60496724
OS -1.76541938 -38.6151374
OS -1.76449482 -38.62715668
OS -1.76357026 -38.6428742
OS -1.76357026 -38.66044084
OS -1.76357026 -38.76584068
OS -1.76357026 -38.76676524
OS -1.76357026 -38.77046348
OS -1.76357026 -38.77601084
OS -1.76357026 -38.78340732
OS -1.76357026 -38.79172836
OS -1.76357026 -38.80189852
OS -1.7626457 -38.82408796
OS -1.7626457 -38.84720196
OS -1.76172114 -38.87031596
OS -1.76079658 -38.88048612
OS -1.76079658 -38.88973172
OS -1.75987202 -38.89805276
OS -1.75894746 -38.90452468
OS -1.75894746 -38.90544924
OS -1.7580229 -38.90914748
OS -1.75709834 -38.91469484
OS -1.75432466 -38.92209132
OS -1.75247554 -38.93041236
OS -1.7487773 -38.93965796
OS -1.7441545 -38.94982812
OS -1.7395317 -38.95999828
OS -1.82181754 -38.95999828
OS -1.8227421 -38.95907372
OS -1.82366666 -38.95537548
OS -1.82551578 -38.95075268
OS -1.82828946 -38.9433562
OS -1.83106314 -38.93503516
OS -1.83291226 -38.924865
OS -1.83476138 -38.91377028
OS -1.8366105 -38.901751
OS -1.83753506 -38.901751
OS -1.83845962 -38.90360012
OS -1.84400698 -38.90822292
OS -1.85232802 -38.91469484
OS -1.86342274 -38.92301588
OS -1.87729114 -38.93133692
OS -1.89115954 -38.94058252
OS -1.9059525 -38.94890356
OS -1.92167002 -38.95537548
OS -1.92351914 -38.95630004
OS -1.9290665 -38.9572246
OS -1.93738754 -38.95999828
OS -1.9475577 -38.96277196
OS -1.96050154 -38.96554564
OS -1.9752945 -38.96739476
OS -1.99193658 -38.96924388
OS -2.00857866 -38.97016844
OS -2.01597514 -38.97016844
OS -2.0215225 -38.96924388
OS -2.02799442 -38.96924388
OS -2.0353909 -38.96831932
OS -2.05203298 -38.96554564
OS -2.07052418 -38.96092284
OS -2.0908645 -38.95445092
OS -2.1093557 -38.94520532
OS -2.12599778 -38.93318604
OS -2.1278469 -38.93133692
OS -2.1324697 -38.92671412
OS -2.13894162 -38.91839308
OS -2.1463381 -38.90729836
OS -2.15373458 -38.89342996
OS -2.1602065 -38.87771244
OS -2.1648293 -38.85829668
OS -2.16575386 -38.84905108
OS -2.16667842 -38.83795636
OS -2.16667842 -38.83610724
OS -2.16667842 -38.832409
OS -2.16575386 -38.82593708
OS -2.1648293 -38.81761604
OS -2.16298018 -38.80744588
OS -2.1602065 -38.79727572
OS -2.15650826 -38.786181
OS -2.15188546 -38.77601084
OS -2.1509609 -38.77508628
OS -2.14911178 -38.77138804
OS -2.14541354 -38.76584068
OS -2.14079074 -38.75936876
OS -2.13524338 -38.75197228
OS -2.1278469 -38.7445758
OS -2.12045042 -38.73717932
OS -2.11120482 -38.7307074
OS -2.11028026 -38.72978284
OS -2.10658202 -38.72793372
OS -2.10195922 -38.72423548
OS -2.09456274 -38.72053724
OS -2.0862417 -38.716839
OS -2.07607154 -38.7122162
OS -2.06590138 -38.70851796
OS -2.0538821 -38.70481972
OS -2.05295754 -38.70481972
OS -2.0492593 -38.70389516
OS -2.04371194 -38.70204604
OS -2.03631546 -38.70112148
OS -2.02706986 -38.69927236
OS -2.01505058 -38.69742324
OS -2.00118218 -38.69464956
OS -1.9845401 -38.69280044
OS -1.98361554 -38.69280044
OS -1.9799173 -38.69187588
OS -1.9752945 -38.69187588
OS -1.96882258 -38.69095132
OS -1.9614261 -38.69002676
OS -1.9521805 -38.68817764
OS -1.94201034 -38.68725308
OS -1.93091562 -38.68540396
OS -1.90872618 -38.68078116
OS -1.88468762 -38.67615836
OS -1.86342274 -38.670611
OS -1.85325258 -38.66783732
OS -1.84400698 -38.66506364
OS -1.84400698 -38.66413908
OS -1.84400698 -38.66228996
OS -1.84308242 -38.6567426
OS -1.84308242 -38.65027068
OS -1.84308242 -38.64657244
OS -1.84308242 -38.64472332
OS -1.84308242 -38.64379876
OS -1.84308242 -38.6428742
OS -1.84308242 -38.63732684
OS -1.84400698 -38.62808124
OS -1.8458561 -38.61791108
OS -1.84862978 -38.60681636
OS -1.85325258 -38.59572164
OS -1.85879994 -38.58555148
OS -1.86619642 -38.57723044
OS -1.86712098 -38.57630588
OS -1.87174378 -38.57260764
OS -1.87914026 -38.5689094
OS -1.88838586 -38.56336204
OS -1.9013297 -38.55873924
OS -1.91612266 -38.55411644
OS -1.93461386 -38.55134276
OS -1.95587874 -38.5504182
OS -1.96512434 -38.5504182
OS -1.97436994 -38.55134276
OS -1.98731378 -38.55319188
OS -2.00025762 -38.555041
OS -2.01412602 -38.55873924
OS -2.02706986 -38.56336204
OS -2.03816458 -38.56983396
OS -2.03908914 -38.57075852
OS -2.04278738 -38.5735322
OS -2.04741018 -38.578155
OS -2.05295754 -38.58555148
OS -2.0585049 -38.59479708
OS -2.06497682 -38.60681636
OS -2.07052418 -38.62160932
OS -2.07607154 -38.6382514
OS -2.15281002 -38.62808124
OS -2.15281002 -38.62715668
OS -2.15188546 -38.62623212
OS -2.15188546 -38.62345844
OS -2.1509609 -38.6197602
OS -2.14818722 -38.61143916
OS -2.14448898 -38.59941988
OS -2.13986618 -38.5874006
OS -2.13431882 -38.57445676
OS -2.12692234 -38.56151292
OS -2.1186013 -38.54949364
OS -2.11767674 -38.54856908
OS -2.1139785 -38.54487084
OS -2.10843114 -38.53932348
OS -2.10103466 -38.531927
OS -2.0908645 -38.52453052
OS -2.07884522 -38.51713404
OS -2.06497682 -38.508813
OS -2.0492593 -38.50234108
OS -2.04833474 -38.50234108
OS -2.04741018 -38.50141652
OS -2.0446365 -38.50049196
OS -2.04093826 -38.4995674
OS -2.03169266 -38.49679372
OS -2.01874882 -38.49402004
OS -2.00395586 -38.49124636
OS -1.98546466 -38.48847268
OS -1.9660489 -38.48662356
OS -1.94385946 -38.485699
OS -1.9336893 -38.485699
OS -1.92351914 -38.48662356
OE
OB -3.38339938 -38.48662356 I
OS -3.37692746 -38.48662356
OS -3.37045554 -38.48754812
OS -3.35473802 -38.4903218
OS -3.33809594 -38.4949446
OS -3.3205293 -38.50234108
OS -3.30296266 -38.51158668
OS -3.2881697 -38.52453052
OS -3.28632058 -38.52637964
OS -3.28262234 -38.531927
OS -3.27615042 -38.54024804
OS -3.27337674 -38.54671996
OS -3.2696785 -38.55319188
OS -3.26598026 -38.56151292
OS -3.26320658 -38.56983396
OS -3.25950834 -38.57907956
OS -3.25673466 -38.59017428
OS -3.25488554 -38.601269
OS -3.25303642 -38.61421284
OS -3.2511873 -38.62715668
OS -3.2511873 -38.64194964
OS -3.2511873 -38.95999828
OS -3.3297749 -38.95999828
OS -3.3297749 -38.66876188
OS -3.3297749 -38.66783732
OS -3.3297749 -38.66691276
OS -3.3297749 -38.6613654
OS -3.3297749 -38.65304436
OS -3.33069946 -38.6428742
OS -3.33162402 -38.63177948
OS -3.33254858 -38.62068476
OS -3.3343977 -38.60959004
OS -3.33717138 -38.601269
OS -3.33717138 -38.60034444
OS -3.3390205 -38.59757076
OS -3.34086962 -38.59387252
OS -3.3436433 -38.58924972
OS -3.34734154 -38.58370236
OS -3.35196434 -38.578155
OS -3.3575117 -38.57260764
OS -3.36490818 -38.56706028
OS -3.36583274 -38.56613572
OS -3.36860642 -38.56521116
OS -3.37230466 -38.56336204
OS -3.37877658 -38.56058836
OS -3.3852485 -38.55781468
OS -3.39356954 -38.55596556
OS -3.40189058 -38.555041
OS -3.41206074 -38.55411644
OS -3.41668354 -38.55411644
OS -3.42038178 -38.555041
OS -3.42962738 -38.55596556
OS -3.4407221 -38.55781468
OS -3.45366594 -38.56243748
OS -3.46753434 -38.56798484
OS -3.48140274 -38.57630588
OS -3.49434658 -38.5874006
OS -3.49527114 -38.58924972
OS -3.49896938 -38.59387252
OS -3.50451674 -38.601269
OS -3.5100641 -38.61236372
OS -3.51653602 -38.62715668
OS -3.52115882 -38.64472332
OS -3.52485706 -38.6659882
OS -3.52670618 -38.69095132
OS -3.52670618 -38.95999828
OS -3.60529378 -38.95999828
OS -3.60529378 -38.65951628
OS -3.60529378 -38.65859172
OS -3.60529378 -38.6567426
OS -3.60529378 -38.65489348
OS -3.60529378 -38.65119524
OS -3.60621834 -38.64102508
OS -3.60806746 -38.62993036
OS -3.60991658 -38.61698652
OS -3.61361482 -38.60404268
OS -3.61823762 -38.5920234
OS -3.62470954 -38.58092868
OS -3.6256341 -38.58000412
OS -3.62840778 -38.57630588
OS -3.63303058 -38.57260764
OS -3.6395025 -38.56706028
OS -3.64782354 -38.56243748
OS -3.65891826 -38.55781468
OS -3.6718621 -38.555041
OS -3.68757962 -38.55411644
OS -3.69312698 -38.55411644
OS -3.6995989 -38.555041
OS -3.70699538 -38.55596556
OS -3.71624098 -38.55873924
OS -3.7273357 -38.56151292
OS -3.73750586 -38.56613572
OS -3.74860058 -38.57168308
OS -3.74952514 -38.57260764
OS -3.75322338 -38.57538132
OS -3.75784618 -38.57907956
OS -3.7643181 -38.58462692
OS -3.77079002 -38.5920234
OS -3.77726194 -38.601269
OS -3.78373386 -38.61143916
OS -3.78928122 -38.62345844
OS -3.79020578 -38.62530756
OS -3.79113034 -38.62993036
OS -3.79297946 -38.63732684
OS -3.79575314 -38.647497
OS -3.79852682 -38.6613654
OS -3.80037594 -38.67800748
OS -3.8013005 -38.69742324
OS -3.80222506 -38.71961268
OS -3.80222506 -38.95999828
OS -3.88081266 -38.95999828
OS -3.88081266 -38.49586916
OS -3.8105461 -38.49586916
OS -3.8105461 -38.56243748
OS -3.80962154 -38.56058836
OS -3.80684786 -38.55689012
OS -3.8013005 -38.5504182
OS -3.79482858 -38.54302172
OS -3.78650754 -38.53377612
OS -3.77633738 -38.52453052
OS -3.76524266 -38.51528492
OS -3.75229882 -38.50696388
OS -3.7504497 -38.50603932
OS -3.7458269 -38.50326564
OS -3.73843042 -38.50049196
OS -3.72826026 -38.49586916
OS -3.71624098 -38.49217092
OS -3.70237258 -38.48939724
OS -3.68665506 -38.48662356
OS -3.67001298 -38.485699
OS -3.66169194 -38.485699
OS -3.65152178 -38.48662356
OS -3.64042706 -38.48847268
OS -3.62655866 -38.49124636
OS -3.61269026 -38.4949446
OS -3.59882186 -38.50049196
OS -3.58587802 -38.50788844
OS -3.5840289 -38.508813
OS -3.58033066 -38.51158668
OS -3.5747833 -38.51620948
OS -3.56738682 -38.52360596
OS -3.55999034 -38.531927
OS -3.5516693 -38.54209716
OS -3.54427282 -38.55411644
OS -3.53872546 -38.56798484
OS -3.5378009 -38.56706028
OS -3.53595178 -38.5642866
OS -3.5331781 -38.56058836
OS -3.5285553 -38.555041
OS -3.52300794 -38.54856908
OS -3.51653602 -38.54209716
OS -3.50913954 -38.53470068
OS -3.49989394 -38.52637964
OS -3.48972378 -38.51898316
OS -3.47955362 -38.51158668
OS -3.46753434 -38.50511476
OS -3.4545905 -38.49864284
OS -3.4407221 -38.49309548
OS -3.42592914 -38.48939724
OS -3.41113618 -38.48662356
OS -3.3944941 -38.485699
OS -3.38802218 -38.485699
OS -3.38339938 -38.48662356
OE
OB -2.6872057 -39.1375138 I
OS -3.20773298 -39.1375138
OS -3.20773298 -39.08111564
OS -2.6872057 -39.08111564
OS -2.6872057 -39.1375138
OE
OB -0.7410069 -38.48662356 I
OS -0.73361042 -38.48754812
OS -0.72436482 -38.48939724
OS -0.71419466 -38.49124636
OS -0.70217538 -38.49402004
OS -0.69108066 -38.49679372
OS -0.67813682 -38.50141652
OS -0.66611754 -38.50603932
OS -0.6531737 -38.51251124
OS -0.64022986 -38.51990772
OS -0.62728602 -38.52822876
OS -0.61526674 -38.53839892
OS -0.60417202 -38.54949364
OS -0.60324746 -38.5504182
OS -0.60139834 -38.55226732
OS -0.59862466 -38.55596556
OS -0.59492642 -38.56151292
OS -0.59030362 -38.56798484
OS -0.58568082 -38.57538132
OS -0.58013346 -38.58462692
OS -0.5745861 -38.59572164
OS -0.56903874 -38.60774092
OS -0.56349138 -38.62068476
OS -0.55886858 -38.63547772
OS -0.55424578 -38.65119524
OS -0.55054754 -38.66876188
OS -0.54777386 -38.68725308
OS -0.54592474 -38.70666884
OS -0.54500018 -38.72793372
OS -0.54500018 -38.72885828
OS -0.54500018 -38.73255652
OS -0.54500018 -38.73902844
OS -0.54592474 -38.74827404
OS -0.89263474 -38.74827404
OS -0.89263474 -38.7491986
OS -0.89263474 -38.75197228
OS -0.89171018 -38.75567052
OS -0.89171018 -38.76121788
OS -0.89078562 -38.7676898
OS -0.8889365 -38.77508628
OS -0.88616282 -38.79172836
OS -0.88061546 -38.81021956
OS -0.87321898 -38.83055988
OS -0.86304882 -38.84905108
OS -0.85010498 -38.86569316
OS -0.84918042 -38.86569316
OS -0.84825586 -38.86754228
OS -0.8427085 -38.87216508
OS -0.83438746 -38.878637
OS -0.82329274 -38.88510892
OS -0.80849978 -38.8925054
OS -0.7918577 -38.89897732
OS -0.7733665 -38.90360012
OS -0.76319634 -38.90452468
OS -0.75210162 -38.90544924
OS -0.74470514 -38.90544924
OS -0.7363841 -38.90452468
OS -0.72621394 -38.90267556
OS -0.71511922 -38.89990188
OS -0.70217538 -38.89620364
OS -0.6901561 -38.89065628
OS -0.67813682 -38.8832598
OS -0.67721226 -38.88233524
OS -0.67258946 -38.878637
OS -0.6670421 -38.87308964
OS -0.66057018 -38.86569316
OS -0.6531737 -38.855523
OS -0.64485266 -38.84257916
OS -0.63653162 -38.8277862
OS -0.62913514 -38.81021956
OS -0.54777386 -38.82038972
OS -0.54777386 -38.82131428
OS -0.54869842 -38.8231634
OS -0.54962298 -38.82686164
OS -0.5514721 -38.832409
OS -0.55424578 -38.83795636
OS -0.55701946 -38.84535284
OS -0.56441594 -38.86107036
OS -0.57366154 -38.878637
OS -0.58660538 -38.8971282
OS -0.60139834 -38.91469484
OS -0.61988954 -38.93133692
OS -0.6208141 -38.93133692
OS -0.62266322 -38.93318604
OS -0.6254369 -38.93503516
OS -0.62913514 -38.93780884
OS -0.6346825 -38.94058252
OS -0.64022986 -38.9433562
OS -0.64762634 -38.94705444
OS -0.65594738 -38.95075268
OS -0.66519298 -38.95445092
OS -0.67443858 -38.95814916
OS -0.69755258 -38.96369652
OS -0.72344026 -38.96831932
OS -0.75210162 -38.97016844
OS -0.76227178 -38.97016844
OS -0.7687437 -38.96924388
OS -0.77706474 -38.96831932
OS -0.7872349 -38.9664702
OS -0.79832962 -38.96462108
OS -0.8103489 -38.96277196
OS -0.83623658 -38.95537548
OS -0.85010498 -38.94982812
OS -0.86304882 -38.94428076
OS -0.87691722 -38.93688428
OS -0.88986106 -38.92856324
OS -0.90188034 -38.91931764
OS -0.91389962 -38.90822292
OS -0.91482418 -38.90729836
OS -0.9166733 -38.90544924
OS -0.91944698 -38.901751
OS -0.92314522 -38.89620364
OS -0.92776802 -38.88973172
OS -0.93239082 -38.88233524
OS -0.93793818 -38.87308964
OS -0.94348554 -38.86291948
OS -0.9490329 -38.8509002
OS -0.95458026 -38.83795636
OS -0.95920306 -38.8231634
OS -0.96382586 -38.80744588
OS -0.9675241 -38.7908038
OS -0.97029778 -38.7723126
OS -0.9721469 -38.75289684
OS -0.97307146 -38.73255652
OS -0.97307146 -38.73163196
OS -0.97307146 -38.72700916
OS -0.97307146 -38.7214618
OS -0.9721469 -38.71314076
OS -0.97122234 -38.7029706
OS -0.97029778 -38.69187588
OS -0.96844866 -38.67893204
OS -0.96567498 -38.6659882
OS -0.9582785 -38.63640228
OS -0.9536557 -38.62160932
OS -0.94810834 -38.6058918
OS -0.94071186 -38.59109884
OS -0.93239082 -38.57723044
OS -0.92314522 -38.56336204
OS -0.91297506 -38.5504182
OS -0.9120505 -38.54949364
OS -0.91020138 -38.54764452
OS -0.90650314 -38.54487084
OS -0.90188034 -38.54024804
OS -0.89633298 -38.53562524
OS -0.8889365 -38.53007788
OS -0.88061546 -38.52360596
OS -0.8704453 -38.5180586
OS -0.86027514 -38.51158668
OS -0.84825586 -38.50603932
OS -0.83531202 -38.50049196
OS -0.82144362 -38.49586916
OS -0.80665066 -38.49124636
OS -0.79093314 -38.48847268
OS -0.77429106 -38.48662356
OS -0.75672442 -38.485699
OS -0.74747882 -38.485699
OS -0.7410069 -38.48662356
OE
OB -0.37857938 -38.42745172 I
OS -0.39984426 -38.54671996
OS -0.44884594 -38.54671996
OS -0.4682617 -38.42745172
OS -0.4682617 -38.32020276
OS -0.37857938 -38.32020276
OS -0.37857938 -38.42745172
OE
OB -1.4714093 -38.48662356 I
OS -1.4575409 -38.48754812
OS -1.44274794 -38.48939724
OS -1.42703042 -38.49309548
OS -1.41038834 -38.49679372
OS -1.39467082 -38.50234108
OS -1.39374626 -38.50234108
OS -1.3928217 -38.50326564
OS -1.3881989 -38.50511476
OS -1.38080242 -38.508813
OS -1.37155682 -38.5134358
OS -1.36138666 -38.51990772
OS -1.3512165 -38.5273042
OS -1.3419709 -38.53562524
OS -1.33364986 -38.54487084
OS -1.3327253 -38.5457954
OS -1.33087618 -38.54949364
OS -1.32717794 -38.55596556
OS -1.32255514 -38.56336204
OS -1.31793234 -38.57445676
OS -1.31330954 -38.58647604
OS -1.3096113 -38.60034444
OS -1.30591306 -38.61606196
OS -1.38265154 -38.62623212
OS -1.38265154 -38.624383
OS -1.3835761 -38.62068476
OS -1.38542522 -38.61421284
OS -1.3881989 -38.6058918
OS -1.3928217 -38.59757076
OS -1.39836906 -38.58832516
OS -1.40484098 -38.57907956
OS -1.41408658 -38.57075852
OS -1.41501114 -38.56983396
OS -1.41870938 -38.56798484
OS -1.42425674 -38.5642866
OS -1.43257778 -38.56058836
OS -1.44182338 -38.55689012
OS -1.45384266 -38.55319188
OS -1.46863562 -38.55134276
OS -1.48435314 -38.5504182
OS -1.49359874 -38.5504182
OS -1.50284434 -38.55134276
OS -1.51486362 -38.55226732
OS -1.5268829 -38.555041
OS -1.53982674 -38.55781468
OS -1.55184602 -38.56243748
OS -1.56201618 -38.5689094
OS -1.56294074 -38.56983396
OS -1.56571442 -38.57168308
OS -1.56941266 -38.57538132
OS -1.5731109 -38.58092868
OS -1.5777337 -38.58647604
OS -1.58143194 -38.59387252
OS -1.58420562 -38.60219356
OS -1.58513018 -38.6105146
OS -1.58513018 -38.61143916
OS -1.58513018 -38.61328828
OS -1.58420562 -38.61606196
OS -1.58420562 -38.6197602
OS -1.58143194 -38.6290058
OS -1.57588458 -38.6382514
OS -1.57496002 -38.63917596
OS -1.57403546 -38.64010052
OS -1.57218634 -38.6428742
OS -1.5684881 -38.64564788
OS -1.56478986 -38.64842156
OS -1.5592425 -38.6521198
OS -1.55277058 -38.65489348
OS -1.5453741 -38.65859172
OS -1.54444954 -38.65859172
OS -1.54260042 -38.65951628
OS -1.53890218 -38.66044084
OS -1.53243026 -38.66321452
OS -1.52318466 -38.6659882
OS -1.51116538 -38.66876188
OS -1.5037689 -38.67153556
OS -1.49544786 -38.67338468
OS -1.48620226 -38.67615836
OS -1.4760321 -38.67893204
OS -1.47510754 -38.67893204
OS -1.47233386 -38.6798566
OS -1.46771106 -38.68078116
OS -1.4621637 -38.68263028
OS -1.45569178 -38.6844794
OS -1.44737074 -38.68632852
OS -1.4298041 -38.69187588
OS -1.41038834 -38.69742324
OS -1.39097258 -38.70389516
OS -1.37340594 -38.71036708
OS -1.36600946 -38.71314076
OS -1.35953754 -38.71591444
OS -1.35768842 -38.716839
OS -1.35399018 -38.71868812
OS -1.34844282 -38.7214618
OS -1.34012178 -38.7260846
OS -1.33180074 -38.73163196
OS -1.3234797 -38.73902844
OS -1.31515866 -38.74734948
OS -1.30776218 -38.75659508
OS -1.30683762 -38.75751964
OS -1.3049885 -38.76121788
OS -1.30129026 -38.76676524
OS -1.29759202 -38.77508628
OS -1.29481834 -38.78525644
OS -1.2911201 -38.79635116
OS -1.28927098 -38.809295
OS -1.28834642 -38.82408796
OS -1.28834642 -38.82593708
OS -1.28834642 -38.83055988
OS -1.28927098 -38.83795636
OS -1.2911201 -38.84812652
OS -1.29389378 -38.85922124
OS -1.29851658 -38.87124052
OS -1.30406394 -38.88510892
OS -1.31146042 -38.89805276
OS -1.31238498 -38.89990188
OS -1.31608322 -38.90360012
OS -1.32070602 -38.91007204
OS -1.3281025 -38.91746852
OS -1.33827266 -38.92578956
OS -1.34936738 -38.93503516
OS -1.36231122 -38.9433562
OS -1.37802874 -38.95167724
OS -1.3789533 -38.95167724
OS -1.37987786 -38.9526018
OS -1.38542522 -38.95445092
OS -1.39467082 -38.9572246
OS -1.4066901 -38.96092284
OS -1.42148306 -38.96462108
OS -1.43812514 -38.96739476
OS -1.45569178 -38.96924388
OS -1.4760321 -38.97016844
OS -1.48435314 -38.97016844
OS -1.49082506 -38.96924388
OS -1.49822154 -38.96924388
OS -1.50746714 -38.96831932
OS -1.51671274 -38.96739476
OS -1.5268829 -38.96554564
OS -1.54907234 -38.96092284
OS -1.57218634 -38.95445092
OS -1.59437578 -38.94520532
OS -1.60454594 -38.93965796
OS -1.61379154 -38.93318604
OS -1.6147161 -38.93226148
OS -1.61564066 -38.93133692
OS -1.62118802 -38.92578956
OS -1.62950906 -38.91746852
OS -1.63875466 -38.90452468
OS -1.64892482 -38.88880716
OS -1.65909498 -38.87031596
OS -1.66741602 -38.84720196
OS -1.67388794 -38.82131428
OS -1.5962249 -38.809295
OS -1.5962249 -38.81021956
OS -1.5962249 -38.81114412
OS -1.59437578 -38.81669148
OS -1.59252666 -38.82593708
OS -1.58882842 -38.83610724
OS -1.58420562 -38.84720196
OS -1.57865826 -38.85922124
OS -1.57033722 -38.87124052
OS -1.56016706 -38.88141068
OS -1.55831794 -38.88233524
OS -1.5546197 -38.88510892
OS -1.54722322 -38.88880716
OS -1.53797762 -38.89342996
OS -1.52595834 -38.89805276
OS -1.51208994 -38.901751
OS -1.49544786 -38.90452468
OS -1.4760321 -38.90544924
OS -1.4667865 -38.90544924
OS -1.4575409 -38.90452468
OS -1.44552162 -38.90267556
OS -1.43257778 -38.89990188
OS -1.41870938 -38.89620364
OS -1.4066901 -38.89158084
OS -1.39559538 -38.88418436
OS -1.39467082 -38.8832598
OS -1.39097258 -38.88048612
OS -1.38727434 -38.87586332
OS -1.38172698 -38.8693914
OS -1.37710418 -38.86199492
OS -1.37248138 -38.85274932
OS -1.3697077 -38.84350372
OS -1.36878314 -38.832409
OS -1.36878314 -38.83148444
OS -1.36878314 -38.8277862
OS -1.3697077 -38.8231634
OS -1.37155682 -38.81669148
OS -1.3743305 -38.81021956
OS -1.3789533 -38.80374764
OS -1.38450066 -38.79635116
OS -1.3928217 -38.7908038
OS -1.39374626 -38.78987924
OS -1.39651994 -38.78895468
OS -1.40114274 -38.786181
OS -1.40853922 -38.78340732
OS -1.41963394 -38.77970908
OS -1.42610586 -38.7769354
OS -1.43350234 -38.77508628
OS -1.44182338 -38.7723126
OS -1.45106898 -38.76953892
OS -1.46123914 -38.76676524
OS -1.47325842 -38.76399156
OS -1.47418298 -38.76399156
OS -1.47695666 -38.763067
OS -1.48157946 -38.76214244
OS -1.48712682 -38.76029332
OS -1.4945233 -38.7584442
OS -1.50284434 -38.75567052
OS -1.52041098 -38.75104772
OS -1.5407513 -38.7445758
OS -1.56016706 -38.73902844
OS -1.57865826 -38.73255652
OS -1.5869793 -38.72885828
OS -1.59345122 -38.7260846
OS -1.59530034 -38.72516004
OS -1.59899858 -38.72331092
OS -1.60454594 -38.71961268
OS -1.61194242 -38.71498988
OS -1.62026346 -38.70851796
OS -1.6285845 -38.70112148
OS -1.63690554 -38.69280044
OS -1.64430202 -38.68263028
OS -1.64522658 -38.68170572
OS -1.6470757 -38.67800748
OS -1.64984938 -38.67153556
OS -1.65262306 -38.66413908
OS -1.65539674 -38.65489348
OS -1.65817042 -38.64379876
OS -1.66001954 -38.63270404
OS -1.6609441 -38.6197602
OS -1.6609441 -38.61791108
OS -1.6609441 -38.61421284
OS -1.66001954 -38.60866548
OS -1.65909498 -38.60034444
OS -1.65724586 -38.5920234
OS -1.65539674 -38.58185324
OS -1.6516985 -38.57260764
OS -1.6470757 -38.56243748
OS -1.64615114 -38.56151292
OS -1.64430202 -38.55781468
OS -1.64152834 -38.55319188
OS -1.63690554 -38.54671996
OS -1.63135818 -38.54024804
OS -1.62488626 -38.531927
OS -1.61748978 -38.52453052
OS -1.60824418 -38.5180586
OS -1.60731962 -38.51713404
OS -1.60454594 -38.51620948
OS -1.6008477 -38.5134358
OS -1.59530034 -38.51066212
OS -1.58790386 -38.50696388
OS -1.57958282 -38.50326564
OS -1.56941266 -38.4995674
OS -1.55831794 -38.49586916
OS -1.55646882 -38.4949446
OS -1.55277058 -38.49402004
OS -1.54629866 -38.49217092
OS -1.53797762 -38.4903218
OS -1.52780746 -38.48847268
OS -1.51671274 -38.48754812
OS -1.5037689 -38.485699
OS -1.48157946 -38.485699
OS -1.4714093 -38.48662356
OE
OB -1.10343442 -38.49586916 I
OS -1.02392226 -38.49586916
OS -1.02392226 -38.55689012
OS -1.10343442 -38.55689012
OS -1.10343442 -38.82963532
OS -1.10343442 -38.83148444
OS -1.10343442 -38.83518268
OS -1.10343442 -38.84073004
OS -1.10250986 -38.84720196
OS -1.1015853 -38.86199492
OS -1.10066074 -38.86846684
OS -1.09973618 -38.87308964
OS -1.09881162 -38.87493876
OS -1.09603794 -38.878637
OS -1.0923397 -38.8832598
OS -1.08586778 -38.8878826
OS -1.08401866 -38.88880716
OS -1.07939586 -38.89065628
OS -1.07107482 -38.8925054
OS -1.05905554 -38.89342996
OS -1.04980994 -38.89342996
OS -1.04518714 -38.8925054
OS -1.03871522 -38.8925054
OS -1.03131874 -38.89158084
OS -1.02392226 -38.89065628
OS -1.0137521 -38.95999828
OS -1.01560122 -38.95999828
OS -1.01929946 -38.96092284
OS -1.02577138 -38.9618474
OS -1.03409242 -38.96277196
OS -1.04333802 -38.96462108
OS -1.05350818 -38.96554564
OS -1.0738485 -38.9664702
OS -1.08124498 -38.9664702
OS -1.08864146 -38.96554564
OS -1.09788706 -38.96462108
OS -1.10898178 -38.96369652
OS -1.1200765 -38.96092284
OS -1.13024666 -38.95814916
OS -1.14041682 -38.95352636
OS -1.14134138 -38.9526018
OS -1.14411506 -38.95075268
OS -1.1478133 -38.947979
OS -1.15336066 -38.9433562
OS -1.15798346 -38.9387334
OS -1.16353082 -38.93226148
OS -1.16907818 -38.92578956
OS -1.17277642 -38.91746852
OS -1.17277642 -38.91654396
OS -1.17462554 -38.91284572
OS -1.1755501 -38.9063738
OS -1.17739922 -38.8971282
OS -1.17924834 -38.88510892
OS -1.1801729 -38.87771244
OS -1.1801729 -38.8693914
OS -1.18109746 -38.85922124
OS -1.18202202 -38.84905108
OS -1.18202202 -38.83795636
OS -1.18202202 -38.82501252
OS -1.18202202 -38.55689012
OS -1.2402693 -38.55689012
OS -1.2402693 -38.49586916
OS -1.18202202 -38.49586916
OS -1.18202202 -38.38122372
OS -1.10343442 -38.33407116
OS -1.10343442 -38.49586916
OE
OB -4.17389818 -38.48662356 I
OS -4.16557714 -38.48754812
OS -4.15633154 -38.48939724
OS -4.14616138 -38.49124636
OS -4.1341421 -38.49309548
OS -4.10917898 -38.50141652
OS -4.09623514 -38.50603932
OS -4.0832913 -38.51251124
OS -4.07034746 -38.51898316
OS -4.05740362 -38.52822876
OS -4.04538434 -38.53747436
OS -4.03336506 -38.54856908
OS -4.0324405 -38.54949364
OS -4.03059138 -38.55134276
OS -4.0278177 -38.555041
OS -4.02411946 -38.5596638
OS -4.01949666 -38.56613572
OS -4.0139493 -38.57445676
OS -4.00840194 -38.58370236
OS -4.00285458 -38.59387252
OS -3.99730722 -38.60496724
OS -3.99175986 -38.61883564
OS -3.9862125 -38.63270404
OS -3.9815897 -38.64842156
OS -3.97789146 -38.66506364
OS -3.97511778 -38.68263028
OS -3.97326866 -38.70112148
OS -3.9723441 -38.7214618
OS -3.9723441 -38.72238636
OS -3.9723441 -38.72516004
OS -3.9723441 -38.72978284
OS -3.9723441 -38.73625476
OS -3.97326866 -38.74365124
OS -3.97419322 -38.75289684
OS -3.97419322 -38.76214244
OS -3.97604234 -38.7723126
OS -3.97881602 -38.7954266
OS -3.98436338 -38.8185406
OS -3.9908353 -38.8416546
OS -4.0000809 -38.86291948
OS -4.0000809 -38.86384404
OS -4.00100546 -38.8647686
OS -4.00285458 -38.86754228
OS -4.0047037 -38.87124052
OS -4.01117562 -38.88048612
OS -4.01949666 -38.89158084
OS -4.03059138 -38.90452468
OS -4.04445978 -38.91746852
OS -4.0601773 -38.93041236
OS -4.0786685 -38.94243164
OS -4.07959306 -38.94243164
OS -4.08051762 -38.9433562
OS -4.0832913 -38.94520532
OS -4.0879141 -38.94705444
OS -4.0925369 -38.94890356
OS -4.09808426 -38.95075268
OS -4.11195266 -38.95630004
OS -4.12767018 -38.96092284
OS -4.14708594 -38.96554564
OS -4.16742626 -38.96924388
OS -4.1896157 -38.97016844
OS -4.1988613 -38.97016844
OS -4.20625778 -38.96924388
OS -4.21457882 -38.96831932
OS -4.22382442 -38.9664702
OS -4.23491914 -38.96462108
OS -4.24601386 -38.96277196
OS -4.27097698 -38.95537548
OS -4.28484538 -38.94982812
OS -4.29778922 -38.94428076
OS -4.31073306 -38.93688428
OS -4.3236769 -38.92856324
OS -4.33569618 -38.91931764
OS -4.34771546 -38.90822292
OS -4.34864002 -38.90729836
OS -4.35048914 -38.90544924
OS -4.35326282 -38.901751
OS -4.35696106 -38.89620364
OS -4.36158386 -38.88973172
OS -4.36620666 -38.88233524
OS -4.37175402 -38.87308964
OS -4.37730138 -38.86199492
OS -4.38284874 -38.84997564
OS -4.3883961 -38.83610724
OS -4.3930189 -38.82131428
OS -4.3976417 -38.80559676
OS -4.40133994 -38.78803012
OS -4.40411362 -38.76953892
OS -4.40596274 -38.7491986
OS -4.4068873 -38.72793372
OS -4.4068873 -38.7260846
OS -4.4068873 -38.72238636
OS -4.40596274 -38.71591444
OS -4.40596274 -38.70666884
OS -4.40503818 -38.69649868
OS -4.40318906 -38.68355484
OS -4.40133994 -38.670611
OS -4.3976417 -38.65581804
OS -4.39394346 -38.64102508
OS -4.38932066 -38.62530756
OS -4.3837733 -38.60866548
OS -4.37637682 -38.59294796
OS -4.36898034 -38.578155
OS -4.35881018 -38.56336204
OS -4.34864002 -38.54949364
OS -4.33569618 -38.53747436
OS -4.33477162 -38.5365498
OS -4.3329225 -38.53562524
OS -4.32922426 -38.53285156
OS -4.32460146 -38.52915332
OS -4.3190541 -38.52545508
OS -4.31165762 -38.52083228
OS -4.30426114 -38.51620948
OS -4.29501554 -38.51158668
OS -4.28484538 -38.50696388
OS -4.27375066 -38.50234108
OS -4.24878754 -38.49402004
OS -4.22012618 -38.48754812
OS -4.20533322 -38.48662356
OS -4.1896157 -38.485699
OS -4.1803701 -38.485699
OS -4.17389818 -38.48662356
OE
OB -5.16872474 -38.48662356 I
OS -5.1604037 -38.48754812
OS -5.1511581 -38.48939724
OS -5.14098794 -38.49124636
OS -5.12896866 -38.49309548
OS -5.10400554 -38.50141652
OS -5.0910617 -38.50603932
OS -5.07811786 -38.51251124
OS -5.06517402 -38.51898316
OS -5.05223018 -38.52822876
OS -5.0402109 -38.53747436
OS -5.02819162 -38.54856908
OS -5.02726706 -38.54949364
OS -5.02541794 -38.55134276
OS -5.02264426 -38.555041
OS -5.01894602 -38.5596638
OS -5.01432322 -38.56613572
OS -5.00877586 -38.57445676
OS -5.0032285 -38.58370236
OS -4.99768114 -38.59387252
OS -4.99213378 -38.60496724
OS -4.98658642 -38.61883564
OS -4.98103906 -38.63270404
OS -4.97641626 -38.64842156
OS -4.97271802 -38.66506364
OS -4.96994434 -38.68263028
OS -4.96809522 -38.70112148
OS -4.96717066 -38.7214618
OS -4.96717066 -38.72238636
OS -4.96717066 -38.72516004
OS -4.96717066 -38.72978284
OS -4.96717066 -38.73625476
OS -4.96809522 -38.74365124
OS -4.96901978 -38.75289684
OS -4.96901978 -38.76214244
OS -4.9708689 -38.7723126
OS -4.97364258 -38.7954266
OS -4.97918994 -38.8185406
OS -4.98566186 -38.8416546
OS -4.99490746 -38.86291948
OS -4.99490746 -38.86384404
OS -4.99583202 -38.8647686
OS -4.99768114 -38.86754228
OS -4.99953026 -38.87124052
OS -5.00600218 -38.88048612
OS -5.01432322 -38.89158084
OS -5.02541794 -38.90452468
OS -5.03928634 -38.91746852
OS -5.05500386 -38.93041236
OS -5.07349506 -38.94243164
OS -5.07441962 -38.94243164
OS -5.07534418 -38.9433562
OS -5.07811786 -38.94520532
OS -5.08274066 -38.94705444
OS -5.08736346 -38.94890356
OS -5.09291082 -38.95075268
OS -5.10677922 -38.95630004
OS -5.12249674 -38.96092284
OS -5.1419125 -38.96554564
OS -5.16225282 -38.96924388
OS -5.18444226 -38.97016844
OS -5.19368786 -38.97016844
OS -5.20108434 -38.96924388
OS -5.20940538 -38.96831932
OS -5.21865098 -38.9664702
OS -5.2297457 -38.96462108
OS -5.24084042 -38.96277196
OS -5.26580354 -38.95537548
OS -5.27967194 -38.94982812
OS -5.29261578 -38.94428076
OS -5.30555962 -38.93688428
OS -5.31850346 -38.92856324
OS -5.33052274 -38.91931764
OS -5.34254202 -38.90822292
OS -5.34346658 -38.90729836
OS -5.3453157 -38.90544924
OS -5.34808938 -38.901751
OS -5.35178762 -38.89620364
OS -5.35641042 -38.88973172
OS -5.36103322 -38.88233524
OS -5.36658058 -38.87308964
OS -5.37212794 -38.86199492
OS -5.3776753 -38.84997564
OS -5.38322266 -38.83610724
OS -5.38784546 -38.82131428
OS -5.39246826 -38.80559676
OS -5.3961665 -38.78803012
OS -5.39894018 -38.76953892
OS -5.4007893 -38.7491986
OS -5.40171386 -38.72793372
OS -5.40171386 -38.7260846
OS -5.40171386 -38.72238636
OS -5.4007893 -38.71591444
OS -5.4007893 -38.70666884
OS -5.39986474 -38.69649868
OS -5.39801562 -38.68355484
OS -5.3961665 -38.670611
OS -5.39246826 -38.65581804
OS -5.38877002 -38.64102508
OS -5.38414722 -38.62530756
OS -5.37859986 -38.60866548
OS -5.37120338 -38.59294796
OS -5.3638069 -38.578155
OS -5.35363674 -38.56336204
OS -5.34346658 -38.54949364
OS -5.33052274 -38.53747436
OS -5.32959818 -38.5365498
OS -5.32774906 -38.53562524
OS -5.32405082 -38.53285156
OS -5.31942802 -38.52915332
OS -5.31388066 -38.52545508
OS -5.30648418 -38.52083228
OS -5.2990877 -38.51620948
OS -5.2898421 -38.51158668
OS -5.27967194 -38.50696388
OS -5.26857722 -38.50234108
OS -5.2436141 -38.49402004
OS -5.21495274 -38.48754812
OS -5.20015978 -38.48662356
OS -5.18444226 -38.485699
OS -5.17519666 -38.485699
OS -5.16872474 -38.48662356
OE
OB -5.97031826 -38.42745172 I
OS -5.99158314 -38.54671996
OS -6.04058482 -38.54671996
OS -6.06000058 -38.42745172
OS -6.06000058 -38.32020276
OS -5.97031826 -38.32020276
OS -5.97031826 -38.42745172
OE
OB -5.79280274 -38.54856908 I
OS -5.79187818 -38.54764452
OS -5.79095362 -38.5457954
OS -5.78817994 -38.54302172
OS -5.78355714 -38.53839892
OS -5.77893434 -38.53377612
OS -5.77338698 -38.52822876
OS -5.7659905 -38.5226814
OS -5.75859402 -38.51713404
OS -5.74010282 -38.50511476
OS -5.71883794 -38.49586916
OS -5.70681866 -38.49124636
OS -5.69387482 -38.48847268
OS -5.68000642 -38.48662356
OS -5.66613802 -38.485699
OS -5.65874154 -38.485699
OS -5.6504205 -38.48662356
OS -5.64025034 -38.48754812
OS -5.62823106 -38.4903218
OS -5.61436266 -38.49309548
OS -5.5995697 -38.49771828
OS -5.5857013 -38.50326564
OS -5.58385218 -38.5041902
OS -5.57922938 -38.50603932
OS -5.5718329 -38.51066212
OS -5.56351186 -38.51620948
OS -5.5533417 -38.5226814
OS -5.54317154 -38.53100244
OS -5.53207682 -38.5411726
OS -5.52283122 -38.55226732
OS -5.52190666 -38.55319188
OS -5.51913298 -38.55781468
OS -5.51451018 -38.5642866
OS -5.50896282 -38.57260764
OS -5.5024909 -38.58370236
OS -5.49601898 -38.5966462
OS -5.48954706 -38.61143916
OS -5.4839997 -38.62715668
OS -5.4839997 -38.62808124
OS -5.48307514 -38.6290058
OS -5.48215058 -38.63177948
OS -5.48122602 -38.63455316
OS -5.4793769 -38.64379876
OS -5.47660322 -38.65581804
OS -5.47382954 -38.66968644
OS -5.47105586 -38.68540396
OS -5.4701313 -38.7029706
OS -5.46920674 -38.7214618
OS -5.46920674 -38.72238636
OS -5.46920674 -38.72700916
OS -5.46920674 -38.73255652
OS -5.4701313 -38.74087756
OS -5.47105586 -38.75104772
OS -5.47198042 -38.76214244
OS -5.47382954 -38.77508628
OS -5.47660322 -38.78895468
OS -5.4839997 -38.8185406
OS -5.4886225 -38.83425812
OS -5.49416986 -38.84905108
OS -5.50064178 -38.8647686
OS -5.50896282 -38.878637
OS -5.51820842 -38.8925054
OS -5.52837858 -38.90544924
OS -5.52930314 -38.9063738
OS -5.53115226 -38.90822292
OS -5.53392594 -38.9109966
OS -5.53854874 -38.9156194
OS -5.54502066 -38.9202422
OS -5.55149258 -38.92578956
OS -5.55888906 -38.93133692
OS -5.56813466 -38.93780884
OS -5.57830482 -38.9433562
OS -5.58847498 -38.94982812
OS -5.6134381 -38.95999828
OS -5.62638194 -38.96462108
OS -5.64025034 -38.96739476
OS -5.6550433 -38.96924388
OS -5.66983626 -38.97016844
OS -5.6735345 -38.97016844
OS -5.6781573 -38.96924388
OS -5.68370466 -38.96924388
OS -5.69017658 -38.96831932
OS -5.69849762 -38.9664702
OS -5.71698882 -38.9618474
OS -5.72715898 -38.95814916
OS -5.73732914 -38.95352636
OS -5.74842386 -38.947979
OS -5.75859402 -38.94150708
OS -5.76968874 -38.93318604
OS -5.7798589 -38.92394044
OS -5.7891045 -38.91377028
OS -5.7983501 -38.901751
OS -5.7983501 -38.95999828
OS -5.87139034 -38.95999828
OS -5.87139034 -38.32020276
OS -5.79280274 -38.32020276
OS -5.79280274 -38.54856908
OE
OB -4.78318322 -38.49586916 I
OS -4.70367106 -38.49586916
OS -4.70367106 -38.55689012
OS -4.78318322 -38.55689012
OS -4.78318322 -38.82963532
OS -4.78318322 -38.83148444
OS -4.78318322 -38.83518268
OS -4.78318322 -38.84073004
OS -4.78225866 -38.84720196
OS -4.7813341 -38.86199492
OS -4.78040954 -38.86846684
OS -4.77948498 -38.87308964
OS -4.77856042 -38.87493876
OS -4.77578674 -38.878637
OS -4.7720885 -38.8832598
OS -4.76561658 -38.8878826
OS -4.76376746 -38.88880716
OS -4.75914466 -38.89065628
OS -4.75082362 -38.8925054
OS -4.73880434 -38.89342996
OS -4.72955874 -38.89342996
OS -4.72493594 -38.8925054
OS -4.71846402 -38.8925054
OS -4.71106754 -38.89158084
OS -4.70367106 -38.89065628
OS -4.6935009 -38.95999828
OS -4.69535002 -38.95999828
OS -4.69904826 -38.96092284
OS -4.70552018 -38.9618474
OS -4.71384122 -38.96277196
OS -4.72308682 -38.96462108
OS -4.73325698 -38.96554564
OS -4.7535973 -38.9664702
OS -4.76099378 -38.9664702
OS -4.76839026 -38.96554564
OS -4.77763586 -38.96462108
OS -4.78873058 -38.96369652
OS -4.7998253 -38.96092284
OS -4.80999546 -38.95814916
OS -4.82016562 -38.95352636
OS -4.82109018 -38.9526018
OS -4.82386386 -38.95075268
OS -4.8275621 -38.947979
OS -4.83310946 -38.9433562
OS -4.83773226 -38.9387334
OS -4.84327962 -38.93226148
OS -4.84882698 -38.92578956
OS -4.85252522 -38.91746852
OS -4.85252522 -38.91654396
OS -4.85437434 -38.91284572
OS -4.8552989 -38.9063738
OS -4.85714802 -38.8971282
OS -4.85899714 -38.88510892
OS -4.8599217 -38.87771244
OS -4.8599217 -38.8693914
OS -4.86084626 -38.85922124
OS -4.86177082 -38.84905108
OS -4.86177082 -38.83795636
OS -4.86177082 -38.82501252
OS -4.86177082 -38.55689012
OS -4.9200181 -38.55689012
OS -4.9200181 -38.49586916
OS -4.86177082 -38.49586916
OS -4.86177082 -38.38122372
OS -4.78318322 -38.33407116
OS -4.78318322 -38.49586916
OE
OB -4.53447658 -38.49586916 I
OS -4.45496442 -38.49586916
OS -4.45496442 -38.55689012
OS -4.53447658 -38.55689012
OS -4.53447658 -38.82963532
OS -4.53447658 -38.83148444
OS -4.53447658 -38.83518268
OS -4.53447658 -38.84073004
OS -4.53355202 -38.84720196
OS -4.53262746 -38.86199492
OS -4.5317029 -38.86846684
OS -4.53077834 -38.87308964
OS -4.52985378 -38.87493876
OS -4.5270801 -38.878637
OS -4.52338186 -38.8832598
OS -4.51690994 -38.8878826
OS -4.51506082 -38.88880716
OS -4.51043802 -38.89065628
OS -4.50211698 -38.8925054
OS -4.4900977 -38.89342996
OS -4.4808521 -38.89342996
OS -4.4762293 -38.8925054
OS -4.46975738 -38.8925054
OS -4.4623609 -38.89158084
OS -4.45496442 -38.89065628
OS -4.44479426 -38.95999828
OS -4.44664338 -38.95999828
OS -4.45034162 -38.96092284
OS -4.45681354 -38.9618474
OS -4.46513458 -38.96277196
OS -4.47438018 -38.96462108
OS -4.48455034 -38.96554564
OS -4.50489066 -38.9664702
OS -4.51228714 -38.9664702
OS -4.51968362 -38.96554564
OS -4.52892922 -38.96462108
OS -4.54002394 -38.96369652
OS -4.55111866 -38.96092284
OS -4.56128882 -38.95814916
OS -4.57145898 -38.95352636
OS -4.57238354 -38.9526018
OS -4.57515722 -38.95075268
OS -4.57885546 -38.947979
OS -4.58440282 -38.9433562
OS -4.58902562 -38.9387334
OS -4.59457298 -38.93226148
OS -4.60012034 -38.92578956
OS -4.60381858 -38.91746852
OS -4.60381858 -38.91654396
OS -4.6056677 -38.91284572
OS -4.60659226 -38.9063738
OS -4.60844138 -38.8971282
OS -4.6102905 -38.88510892
OS -4.61121506 -38.87771244
OS -4.61121506 -38.8693914
OS -4.61213962 -38.85922124
OS -4.61306418 -38.84905108
OS -4.61306418 -38.83795636
OS -4.61306418 -38.82501252
OS -4.61306418 -38.55689012
OS -4.67131146 -38.55689012
OS -4.67131146 -38.49586916
OS -4.61306418 -38.49586916
OS -4.61306418 -38.38122372
OS -4.53447658 -38.33407116
OS -4.53447658 -38.49586916
OE
OB -5.6642889 -38.5504182 H
OS -5.6781573 -38.5504182
OS -5.68185554 -38.55134276
OS -5.6920257 -38.55319188
OS -5.70404498 -38.55596556
OS -5.71791338 -38.56151292
OS -5.73270634 -38.56983396
OS -5.74010282 -38.57445676
OS -5.7474993 -38.58092868
OS -5.75489578 -38.5874006
OS -5.76229226 -38.59572164
OS -5.76229226 -38.5966462
OS -5.76414138 -38.59757076
OS -5.7659905 -38.60034444
OS -5.76783962 -38.60404268
OS -5.7706133 -38.60866548
OS -5.77431154 -38.61421284
OS -5.77708522 -38.62068476
OS -5.78078346 -38.62808124
OS -5.7844817 -38.63732684
OS -5.78725538 -38.64657244
OS -5.79095362 -38.65766716
OS -5.7937273 -38.66876188
OS -5.79557642 -38.68170572
OS -5.79742554 -38.69557412
OS -5.79927466 -38.70944252
OS -5.79927466 -38.72516004
OS -5.79927466 -38.7260846
OS -5.79927466 -38.72885828
OS -5.79927466 -38.73348108
OS -5.79927466 -38.73902844
OS -5.7983501 -38.74550036
OS -5.7983501 -38.7538214
OS -5.79650098 -38.77138804
OS -5.7937273 -38.7908038
OS -5.79002906 -38.81114412
OS -5.7844817 -38.82963532
OS -5.78078346 -38.83795636
OS -5.77708522 -38.84535284
OS -5.77708522 -38.8462774
OS -5.7752361 -38.84812652
OS -5.77338698 -38.8509002
OS -5.7706133 -38.85459844
OS -5.76229226 -38.8647686
OS -5.75027298 -38.87493876
OS -5.73640458 -38.88603348
OS -5.71883794 -38.89620364
OS -5.70959234 -38.89990188
OS -5.69849762 -38.90267556
OS -5.68832746 -38.90452468
OS -5.67630818 -38.90544924
OS -5.67168538 -38.90544924
OS -5.66798714 -38.90452468
OS -5.65781698 -38.90267556
OS -5.6457977 -38.89990188
OS -5.6319293 -38.89435452
OS -5.61713634 -38.88695804
OS -5.60234338 -38.87586332
OS -5.5949469 -38.86846684
OS -5.58755042 -38.86107036
OS -5.58755042 -38.8601458
OS -5.5857013 -38.85922124
OS -5.58385218 -38.85644756
OS -5.58200306 -38.85274932
OS -5.57830482 -38.84812652
OS -5.57553114 -38.84257916
OS -5.5718329 -38.83518268
OS -5.56813466 -38.8277862
OS -5.56536098 -38.8185406
OS -5.56166274 -38.809295
OS -5.5579645 -38.79820028
OS -5.55519082 -38.786181
OS -5.5533417 -38.77323716
OS -5.55149258 -38.75936876
OS -5.54964346 -38.74365124
OS -5.54964346 -38.72793372
OS -5.54964346 -38.72700916
OS -5.54964346 -38.72423548
OS -5.54964346 -38.71961268
OS -5.55056802 -38.71314076
OS -5.55056802 -38.70574428
OS -5.55149258 -38.69649868
OS -5.55426626 -38.67708292
OS -5.5579645 -38.65581804
OS -5.56443642 -38.63270404
OS -5.57368202 -38.61236372
OS -5.57922938 -38.60219356
OS -5.5857013 -38.59387252
OS -5.5857013 -38.59294796
OS -5.58755042 -38.5920234
OS -5.59217322 -38.5874006
OS -5.5995697 -38.58000412
OS -5.60973986 -38.57168308
OS -5.6226837 -38.5642866
OS -5.63747666 -38.55689012
OS -5.6550433 -38.55226732
OS -5.6642889 -38.5504182
OE
OB -0.75579986 -38.5504182 H
OS -0.76134722 -38.5504182
OS -0.76504546 -38.55134276
OS -0.77521562 -38.55226732
OS -0.7872349 -38.555041
OS -0.80202786 -38.5596638
OS -0.81774538 -38.56613572
OS -0.83253834 -38.57538132
OS -0.8473313 -38.5874006
OS -0.84918042 -38.58924972
OS -0.85287866 -38.59387252
OS -0.85935058 -38.60219356
OS -0.8658225 -38.61328828
OS -0.87321898 -38.62623212
OS -0.8796909 -38.6428742
OS -0.88523826 -38.66228996
OS -0.88801194 -38.68355484
OS -0.62821058 -38.68355484
OS -0.62821058 -38.68263028
OS -0.62821058 -38.68078116
OS -0.62913514 -38.67800748
OS -0.62913514 -38.67430924
OS -0.63098426 -38.66321452
OS -0.63375794 -38.65119524
OS -0.63838074 -38.63640228
OS -0.64300354 -38.62253388
OS -0.65040002 -38.60866548
OS -0.65872106 -38.5966462
OS -0.65872106 -38.59572164
OS -0.66057018 -38.59479708
OS -0.66519298 -38.58924972
OS -0.67351402 -38.58185324
OS -0.68460874 -38.5735322
OS -0.69847714 -38.56521116
OS -0.71511922 -38.55781468
OS -0.73453498 -38.55226732
OS -0.74470514 -38.55134276
OS -0.75579986 -38.5504182
OE
OB -4.1896157 -38.5504182 H
OS -4.19516306 -38.5504182
OS -4.19978586 -38.55134276
OS -4.20995602 -38.55226732
OS -4.22382442 -38.55596556
OS -4.23954194 -38.56151292
OS -4.25618402 -38.5689094
OS -4.27190154 -38.58000412
OS -4.28022258 -38.5874006
OS -4.28761906 -38.59479708
OS -4.28761906 -38.59572164
OS -4.28946818 -38.5966462
OS -4.2913173 -38.59941988
OS -4.29409098 -38.60311812
OS -4.29686466 -38.60774092
OS -4.29963834 -38.61328828
OS -4.30333658 -38.62068476
OS -4.30703482 -38.62808124
OS -4.31073306 -38.63732684
OS -4.3144313 -38.64657244
OS -4.31720498 -38.65766716
OS -4.31997866 -38.66968644
OS -4.32275234 -38.68263028
OS -4.32460146 -38.69649868
OS -4.32552602 -38.7122162
OS -4.32645058 -38.72793372
OS -4.32645058 -38.72885828
OS -4.32645058 -38.73163196
OS -4.32645058 -38.73625476
OS -4.32552602 -38.74272668
OS -4.32552602 -38.75012316
OS -4.32460146 -38.7584442
OS -4.32182778 -38.77785996
OS -4.31720498 -38.8000494
OS -4.3098085 -38.82223884
OS -4.3005629 -38.84350372
OS -4.29409098 -38.85274932
OS -4.28761906 -38.86199492
OS -4.2866945 -38.86199492
OS -4.28576994 -38.86384404
OS -4.28022258 -38.86846684
OS -4.27190154 -38.87586332
OS -4.26080682 -38.8832598
OS -4.24693842 -38.89158084
OS -4.23029634 -38.89897732
OS -4.21088058 -38.90360012
OS -4.20071042 -38.90452468
OS -4.1896157 -38.90544924
OS -4.18406834 -38.90544924
OS -4.17944554 -38.90452468
OS -4.16927538 -38.90267556
OS -4.15540698 -38.89990188
OS -4.14061402 -38.89435452
OS -4.12397194 -38.88695804
OS -4.10825442 -38.87586332
OS -4.09993338 -38.86846684
OS -4.0925369 -38.86107036
OS -4.09161234 -38.8601458
OS -4.09068778 -38.85922124
OS -4.08883866 -38.85644756
OS -4.08606498 -38.85274932
OS -4.0832913 -38.84812652
OS -4.07959306 -38.84257916
OS -4.07589482 -38.83518268
OS -4.07219658 -38.8277862
OS -4.06849834 -38.8185406
OS -4.06572466 -38.80837044
OS -4.06202642 -38.79727572
OS -4.05925274 -38.78525644
OS -4.05647906 -38.77138804
OS -4.05462994 -38.75751964
OS -4.05278082 -38.74180212
OS -4.05278082 -38.72516004
OS -4.05278082 -38.72423548
OS -4.05278082 -38.7214618
OS -4.05278082 -38.716839
OS -4.05370538 -38.71129164
OS -4.05370538 -38.70389516
OS -4.05462994 -38.69557412
OS -4.05740362 -38.67615836
OS -4.06202642 -38.65581804
OS -4.0694229 -38.6336286
OS -4.07959306 -38.61328828
OS -4.08514042 -38.60311812
OS -4.0925369 -38.59479708
OS -4.0925369 -38.59387252
OS -4.09438602 -38.59294796
OS -4.09993338 -38.5874006
OS -4.10825442 -38.58092868
OS -4.11934914 -38.57260764
OS -4.13321754 -38.5642866
OS -4.14985962 -38.55689012
OS -4.16835082 -38.55226732
OS -4.17852098 -38.55134276
OS -4.1896157 -38.5504182
OE
OB -2.43942362 -38.54764452 H
OS -2.44404642 -38.54764452
OS -2.44774466 -38.54856908
OS -2.45699026 -38.5504182
OS -2.46900954 -38.55319188
OS -2.48287794 -38.55873924
OS -2.4976709 -38.56706028
OS -2.50599194 -38.57260764
OS -2.51338842 -38.57907956
OS -2.5207849 -38.58647604
OS -2.52818138 -38.59479708
OS -2.52818138 -38.59572164
OS -2.5300305 -38.5966462
OS -2.53187962 -38.59941988
OS -2.53372874 -38.60311812
OS -2.53650242 -38.60866548
OS -2.54020066 -38.61421284
OS -2.5438989 -38.62160932
OS -2.54667258 -38.6290058
OS -2.55037082 -38.6382514
OS -2.55406906 -38.64842156
OS -2.55684274 -38.65951628
OS -2.56054098 -38.67153556
OS -2.5623901 -38.68540396
OS -2.56423922 -38.69927236
OS -2.56608834 -38.71406532
OS -2.56608834 -38.7307074
OS -2.56608834 -38.73163196
OS -2.56608834 -38.73440564
OS -2.56608834 -38.73902844
OS -2.56516378 -38.74550036
OS -2.56516378 -38.75289684
OS -2.56423922 -38.76121788
OS -2.56146554 -38.78063364
OS -2.55684274 -38.80282308
OS -2.55129538 -38.82408796
OS -2.54204978 -38.84535284
OS -2.53650242 -38.85459844
OS -2.5300305 -38.86291948
OS -2.52818138 -38.8647686
OS -2.52355858 -38.8693914
OS -2.5161621 -38.87678788
OS -2.50599194 -38.88418436
OS -2.4930481 -38.89158084
OS -2.47825514 -38.89897732
OS -2.46161306 -38.90360012
OS -2.45236746 -38.90452468
OS -2.44312186 -38.90544924
OS -2.4375745 -38.90544924
OS -2.43387626 -38.90452468
OS -2.42463066 -38.90267556
OS -2.41168682 -38.89990188
OS -2.39781842 -38.89435452
OS -2.38302546 -38.88695804
OS -2.3682325 -38.87586332
OS -2.36083602 -38.8693914
OS -2.35343954 -38.86199492
OS -2.35343954 -38.86107036
OS -2.35159042 -38.8601458
OS -2.3497413 -38.85737212
OS -2.34789218 -38.85367388
OS -2.34419394 -38.84905108
OS -2.34142026 -38.84257916
OS -2.33772202 -38.83610724
OS -2.33402378 -38.8277862
OS -2.3312501 -38.81946516
OS -2.32755186 -38.80837044
OS -2.32385362 -38.79727572
OS -2.32107994 -38.78525644
OS -2.31923082 -38.77138804
OS -2.3173817 -38.75659508
OS -2.31553258 -38.74087756
OS -2.31553258 -38.72423548
OS -2.31553258 -38.72331092
OS -2.31553258 -38.72053724
OS -2.31553258 -38.71591444
OS -2.31645714 -38.70944252
OS -2.31645714 -38.70204604
OS -2.3173817 -38.693725
OS -2.32015538 -38.67430924
OS -2.32477818 -38.65304436
OS -2.3312501 -38.63177948
OS -2.3404957 -38.6105146
OS -2.34604306 -38.60034444
OS -2.35251498 -38.5920234
OS -2.35251498 -38.59109884
OS -2.3543641 -38.59017428
OS -2.3589869 -38.58462692
OS -2.36638338 -38.578155
OS -2.37655354 -38.56983396
OS -2.38949738 -38.56151292
OS -2.40429034 -38.55411644
OS -2.42093242 -38.54949364
OS -2.43017802 -38.54856908
OS -2.43942362 -38.54764452
OE
OB -1.84308242 -38.72700916 H
OS -1.84400698 -38.72700916
OS -1.84493154 -38.72793372
OS -1.84770522 -38.72885828
OS -1.85140346 -38.72978284
OS -1.85602626 -38.73163196
OS -1.86157362 -38.73348108
OS -1.86804554 -38.7353302
OS -1.87544202 -38.73717932
OS -1.88376306 -38.739953
OS -1.89393322 -38.74180212
OS -1.90410338 -38.7445758
OS -1.91612266 -38.74734948
OS -1.9290665 -38.75012316
OS -1.94201034 -38.75289684
OS -1.9568033 -38.75474596
OS -1.97252082 -38.75751964
OS -1.97436994 -38.75751964
OS -1.9799173 -38.7584442
OS -1.9891629 -38.76029332
OS -1.99933306 -38.76214244
OS -2.01042778 -38.76399156
OS -2.0215225 -38.76676524
OS -2.03169266 -38.76953892
OS -2.04093826 -38.77323716
OS -2.04186282 -38.77323716
OS -2.0446365 -38.77508628
OS -2.04833474 -38.7769354
OS -2.05203298 -38.77970908
OS -2.0631277 -38.78710556
OS -2.0723733 -38.79820028
OS -2.0723733 -38.79912484
OS -2.07422242 -38.80097396
OS -2.07514698 -38.8046722
OS -2.0769961 -38.809295
OS -2.07884522 -38.81484236
OS -2.08069434 -38.82038972
OS -2.0816189 -38.8277862
OS -2.08254346 -38.83518268
OS -2.08254346 -38.83610724
OS -2.08254346 -38.84073004
OS -2.0816189 -38.8462774
OS -2.07976978 -38.85367388
OS -2.0769961 -38.86199492
OS -2.0723733 -38.87031596
OS -2.06682594 -38.87956156
OS -2.05942946 -38.8878826
OS -2.0585049 -38.88880716
OS -2.05480666 -38.89065628
OS -2.0492593 -38.89435452
OS -2.04186282 -38.89805276
OS -2.03169266 -38.901751
OS -2.01967338 -38.90544924
OS -2.00580498 -38.90729836
OS -1.9891629 -38.90822292
OS -1.98176642 -38.90822292
OS -1.97252082 -38.90729836
OS -1.96235066 -38.90544924
OS -1.94940682 -38.90360012
OS -1.93646298 -38.89990188
OS -1.92259458 -38.89527908
OS -1.90872618 -38.88880716
OS -1.90687706 -38.8878826
OS -1.90317882 -38.88510892
OS -1.8967069 -38.88048612
OS -1.88931042 -38.8740142
OS -1.88098938 -38.86661772
OS -1.87174378 -38.85737212
OS -1.8643473 -38.8462774
OS -1.85695082 -38.83425812
OS -1.85602626 -38.83333356
OS -1.8551017 -38.82963532
OS -1.85325258 -38.8231634
OS -1.8504789 -38.81484236
OS -1.84770522 -38.80374764
OS -1.8458561 -38.7908038
OS -1.84493154 -38.77508628
OS -1.84400698 -38.75659508
OS -1.84308242 -38.72700916
OE
OB -5.18444226 -38.5504182 H
OS -5.18998962 -38.5504182
OS -5.19461242 -38.55134276
OS -5.20478258 -38.55226732
OS -5.21865098 -38.55596556
OS -5.2343685 -38.56151292
OS -5.25101058 -38.5689094
OS -5.2667281 -38.58000412
OS -5.27504914 -38.5874006
OS -5.28244562 -38.59479708
OS -5.28244562 -38.59572164
OS -5.28429474 -38.5966462
OS -5.28614386 -38.59941988
OS -5.28891754 -38.60311812
OS -5.29169122 -38.60774092
OS -5.2944649 -38.61328828
OS -5.29816314 -38.62068476
OS -5.30186138 -38.62808124
OS -5.30555962 -38.63732684
OS -5.30925786 -38.64657244
OS -5.31203154 -38.65766716
OS -5.31480522 -38.66968644
OS -5.3175789 -38.68263028
OS -5.31942802 -38.69649868
OS -5.32035258 -38.7122162
OS -5.32127714 -38.72793372
OS -5.32127714 -38.72885828
OS -5.32127714 -38.73163196
OS -5.32127714 -38.73625476
OS -5.32035258 -38.74272668
OS -5.32035258 -38.75012316
OS -5.31942802 -38.7584442
OS -5.31665434 -38.77785996
OS -5.31203154 -38.8000494
OS -5.30463506 -38.82223884
OS -5.29538946 -38.84350372
OS -5.28891754 -38.85274932
OS -5.28244562 -38.86199492
OS -5.28152106 -38.86199492
OS -5.2805965 -38.86384404
OS -5.27504914 -38.86846684
OS -5.2667281 -38.87586332
OS -5.25563338 -38.8832598
OS -5.24176498 -38.89158084
OS -5.2251229 -38.89897732
OS -5.20570714 -38.90360012
OS -5.19553698 -38.90452468
OS -5.18444226 -38.90544924
OS -5.1788949 -38.90544924
OS -5.1742721 -38.90452468
OS -5.16410194 -38.90267556
OS -5.15023354 -38.89990188
OS -5.13544058 -38.89435452
OS -5.1187985 -38.88695804
OS -5.10308098 -38.87586332
OS -5.09475994 -38.86846684
OS -5.08736346 -38.86107036
OS -5.0864389 -38.8601458
OS -5.08551434 -38.85922124
OS -5.08366522 -38.85644756
OS -5.08089154 -38.85274932
OS -5.07811786 -38.84812652
OS -5.07441962 -38.84257916
OS -5.07072138 -38.83518268
OS -5.06702314 -38.8277862
OS -5.0633249 -38.8185406
OS -5.06055122 -38.80837044
OS -5.05685298 -38.79727572
OS -5.0540793 -38.78525644
OS -5.05130562 -38.77138804
OS -5.0494565 -38.75751964
OS -5.04760738 -38.74180212
OS -5.04760738 -38.72516004
OS -5.04760738 -38.72423548
OS -5.04760738 -38.7214618
OS -5.04760738 -38.716839
OS -5.04853194 -38.71129164
OS -5.04853194 -38.70389516
OS -5.0494565 -38.69557412
OS -5.05223018 -38.67615836
OS -5.05685298 -38.65581804
OS -5.06424946 -38.6336286
OS -5.07441962 -38.61328828
OS -5.07996698 -38.60311812
OS -5.08736346 -38.59479708
OS -5.08736346 -38.59387252
OS -5.08921258 -38.59294796
OS -5.09475994 -38.5874006
OS -5.10308098 -38.58092868
OS -5.1141757 -38.57260764
OS -5.1280441 -38.5642866
OS -5.14468618 -38.55689012
OS -5.16317738 -38.55226732
OS -5.17334754 -38.55134276
OS -5.18444226 -38.5504182
OE
SE
S P 0
OB -4.66714078 -36.5016923 I
OS -4.65465922 -36.5016923
OS -4.62553558 -36.50307914
OS -4.5950251 -36.50723966
OS -4.56174094 -36.51140018
OS -4.53123046 -36.51833438
OS -4.51597522 -36.5224949
OS -4.50349366 -36.52665542
OS -4.50210682 -36.52665542
OS -4.50071998 -36.52804226
OS -4.49239894 -36.53220278
OS -4.47991738 -36.53775014
OS -4.46466214 -36.54745802
OS -4.44802006 -36.55993958
OS -4.42999114 -36.57658166
OS -4.41334906 -36.59599742
OS -4.39670698 -36.61818686
OS -4.39670698 -36.6195737
OS -4.39532014 -36.62096054
OS -4.38977278 -36.62928158
OS -4.38422542 -36.64314998
OS -4.37590438 -36.6611789
OS -4.36897018 -36.6819815
OS -4.36203598 -36.70694462
OS -4.35787546 -36.73329458
OS -4.35648862 -36.76241822
OS -4.35648862 -36.76380506
OS -4.35648862 -36.76657874
OS -4.35648862 -36.7721261
OS -4.35787546 -36.7790603
OS -4.35787546 -36.78876818
OS -4.3592623 -36.79847606
OS -4.36480966 -36.82205234
OS -4.3731307 -36.84978914
OS -4.38422542 -36.87891278
OS -4.4008675 -36.90803642
OS -4.41196222 -36.92190482
OS -4.42305694 -36.93577322
OS -4.42444378 -36.93716006
OS -4.42583062 -36.9385469
OS -4.42999114 -36.94270742
OS -4.4355385 -36.94686794
OS -4.4424727 -36.9524153
OS -4.45079374 -36.95796266
OS -4.46188846 -36.96489686
OS -4.47298318 -36.9732179
OS -4.48685158 -36.9801521
OS -4.50210682 -36.9870863
OS -4.5187489 -36.99540734
OS -4.53677782 -37.00234154
OS -4.55758042 -37.0078889
OS -4.57838302 -37.0148231
OS -4.6019593 -37.01898362
OS -4.62692242 -37.02314414
OS -4.62414874 -37.02453098
OS -4.61860138 -37.02730466
OS -4.61028034 -37.03285202
OS -4.59918562 -37.03839938
OS -4.5742225 -37.05365462
OS -4.56174094 -37.0633625
OS -4.55064622 -37.07168354
OS -4.54787254 -37.07445722
OS -4.54093834 -37.08139142
OS -4.52984362 -37.09248614
OS -4.51597522 -37.10635454
OS -4.50071998 -37.1257703
OS -4.48269106 -37.1465729
OS -4.46466214 -37.17153602
OS -4.44524638 -37.19927282
OS -4.28021242 -37.45999874
OS -4.43831218 -37.45999874
OS -4.56451462 -37.26029378
OS -4.56451462 -37.25890694
OS -4.5672883 -37.25613326
OS -4.57006198 -37.25197274
OS -4.5742225 -37.24642538
OS -4.58393038 -37.23117014
OS -4.59641194 -37.21175438
OS -4.61166718 -37.19095178
OS -4.62692242 -37.16876234
OS -4.64217766 -37.14795974
OS -4.65604606 -37.12854398
OS -4.6574329 -37.12715714
OS -4.66159342 -37.12160978
OS -4.66852762 -37.11328874
OS -4.6782355 -37.10358086
OS -4.6990381 -37.08277826
OS -4.71013282 -37.07307038
OS -4.72122754 -37.06474934
OS -4.72261438 -37.0633625
OS -4.72538806 -37.06197566
OS -4.73093542 -37.05920198
OS -4.73925646 -37.05504146
OS -4.7475775 -37.05088094
OS -4.75728538 -37.04672042
OS -4.77947482 -37.03978622
OS -4.78086166 -37.03978622
OS -4.78363534 -37.03839938
OS -4.7891827 -37.03839938
OS -4.7961169 -37.03701254
OS -4.80582478 -37.0356257
OS -4.8169195 -37.0356257
OS -4.83217474 -37.03423886
OS -4.99582186 -37.03423886
OS -4.99582186 -37.45999874
OS -5.12341114 -37.45999874
OS -5.12341114 -36.50030546
OS -4.6782355 -36.50030546
OS -4.66714078 -36.5016923
OE
OB -1.0100437 -37.45999874 I
OS -1.13208562 -37.45999874
OS -1.13208562 -36.65701838
OS -1.4122273 -37.45999874
OS -1.52594818 -37.45999874
OS -1.80331618 -36.64314998
OS -1.80331618 -37.45999874
OS -1.9253581 -37.45999874
OS -1.9253581 -36.50030546
OS -1.73536102 -36.50030546
OS -1.50791926 -37.1812439
OS -1.50791926 -37.18263074
OS -1.50653242 -37.18540442
OS -1.50514558 -37.18956494
OS -1.5023719 -37.19649914
OS -1.49682454 -37.21314122
OS -1.48989034 -37.23394382
OS -1.48295614 -37.2575201
OS -1.4746351 -37.28109638
OS -1.4677009 -37.30328582
OS -1.46215354 -37.32270158
OS -1.4607667 -37.3199279
OS -1.45937986 -37.3129937
OS -1.45521934 -37.30051214
OS -1.44967198 -37.28387006
OS -1.44273778 -37.26168062
OS -1.4330299 -37.23533066
OS -1.42332202 -37.20482018
OS -1.41084046 -37.16876234
OS -1.18062502 -36.50030546
OS -1.0100437 -36.50030546
OS -1.0100437 -37.45999874
OE
OB -2.02382374 -37.45999874 I
OS -2.1680551 -37.45999874
OS -2.28038914 -37.16876234
OS -2.68257274 -37.16876234
OS -2.78658574 -37.45999874
OS -2.92110922 -37.45999874
OS -2.55498346 -36.50030546
OS -2.41629946 -36.50030546
OS -2.02382374 -37.45999874
OE
OB -3.02928274 -37.45999874 I
OS -3.16103254 -37.45999874
OS -3.66306862 -36.70694462
OS -3.66306862 -37.45999874
OS -3.78511054 -37.45999874
OS -3.78511054 -36.50030546
OS -3.65474758 -36.50030546
OS -3.15132466 -37.25474642
OS -3.15132466 -36.50030546
OS -3.02928274 -36.50030546
OS -3.02928274 -37.45999874
OE
OB -5.3231161 -36.61402634 I
OS -5.89033366 -36.61402634
OS -5.89033366 -36.90664958
OS -5.35917394 -36.90664958
OS -5.35917394 -37.02037046
OS -5.89033366 -37.02037046
OS -5.89033366 -37.34627786
OS -5.30092666 -37.34627786
OS -5.30092666 -37.45999874
OS -6.01792294 -37.45999874
OS -6.01792294 -36.50030546
OS -5.3231161 -36.50030546
OS -5.3231161 -36.61402634
OE
OB -0.10721086 -36.61402634 I
OS -0.67442842 -36.61402634
OS -0.67442842 -36.90664958
OS -0.1432687 -36.90664958
OS -0.1432687 -37.02037046
OS -0.67442842 -37.02037046
OS -0.67442842 -37.34627786
OS -0.08502142 -37.34627786
OS -0.08502142 -37.45999874
OS -0.8020177 -37.45999874
OS -0.8020177 -36.50030546
OS -0.10721086 -36.50030546
OS -0.10721086 -36.61402634
OE
OB -8.43241138 -37.34627786 I
OS -7.95949894 -37.34627786
OS -7.95949894 -37.45999874
OS -8.56000066 -37.45999874
OS -8.56000066 -36.50030546
OS -8.43241138 -36.50030546
OS -8.43241138 -37.34627786
OE
OB -6.51718534 -37.05365462 I
OS -6.51718534 -37.45999874
OS -6.64477462 -37.45999874
OS -6.64477462 -37.05365462
OS -7.0150609 -36.50030546
OS -6.86112166 -36.50030546
OS -6.67251142 -36.79154186
OS -6.67251142 -36.7929287
OS -6.66973774 -36.79570238
OS -6.66696406 -36.7998629
OS -6.66419038 -36.80541026
OS -6.65864302 -36.81234446
OS -6.65309566 -36.8206655
OS -6.6406141 -36.8414681
OS -6.62535886 -36.86643122
OS -6.60871678 -36.89416802
OS -6.59068786 -36.92329166
OS -6.57404578 -36.95380214
OS -6.57404578 -36.9524153
OS -6.57265894 -36.94964162
OS -6.56988526 -36.9454811
OS -6.56572474 -36.93993374
OS -6.56156422 -36.93299954
OS -6.55601686 -36.9246785
OS -6.5435353 -36.9038759
OS -6.52828006 -36.87891278
OS -6.51025114 -36.84978914
OS -6.48944854 -36.81789182
OS -6.4672591 -36.78322082
OS -6.28280938 -36.50030546
OS -6.1344175 -36.50030546
OS -6.51718534 -37.05365462
OE
OB -7.01644774 -37.45999874 I
OS -7.1606791 -37.45999874
OS -7.27301314 -37.16876234
OS -7.67519674 -37.16876234
OS -7.77920974 -37.45999874
OS -7.91373322 -37.45999874
OS -7.54760746 -36.50030546
OS -7.40892346 -36.50030546
OS -7.01644774 -37.45999874
OE
OB -7.48103914 -36.60015794 H
OS -7.48103914 -36.60154478
OS -7.48242598 -36.60431846
OS -7.48242598 -36.60986582
OS -7.48519966 -36.61541318
OS -7.4865865 -36.62512106
OS -7.48936018 -36.63482894
OS -7.49490754 -36.65840522
OS -7.50184174 -36.68614202
OS -7.51154962 -36.7166525
OS -7.5212575 -36.74993666
OS -7.53373906 -36.78460766
OS -7.63775206 -37.06474934
OS -7.3132315 -37.06474934
OS -7.41308398 -36.80124974
OS -7.41308398 -36.7998629
OS -7.41447082 -36.79570238
OS -7.4172445 -36.78876818
OS -7.42001818 -36.78044714
OS -7.4241787 -36.77073926
OS -7.42833922 -36.7582577
OS -7.43249974 -36.7443893
OS -7.4380471 -36.7305209
OS -7.44914182 -36.69862358
OS -7.46023654 -36.66533942
OS -7.47133126 -36.63205526
OS -7.48103914 -36.60015794
OE
OB -4.69349074 -36.60709214 H
OS -4.99582186 -36.60709214
OS -4.99582186 -36.9246785
OS -4.71013282 -36.9246785
OS -4.69349074 -36.92329166
OS -4.67407498 -36.92190482
OS -4.65188554 -36.92051798
OS -4.6296961 -36.9177443
OS -4.60750666 -36.91358378
OS -4.5880909 -36.90803642
OS -4.58531722 -36.90664958
OS -4.57976986 -36.9038759
OS -4.57144882 -36.89971538
OS -4.5603541 -36.89416802
OS -4.54787254 -36.88584698
OS -4.53539098 -36.8761391
OS -4.52290942 -36.86365754
OS -4.51320154 -36.84978914
OS -4.5118147 -36.8484023
OS -4.50904102 -36.84285494
OS -4.5048805 -36.8345339
OS -4.49933314 -36.82343918
OS -4.49517262 -36.81095762
OS -4.4910121 -36.79708922
OS -4.48823842 -36.78044714
OS -4.48685158 -36.76380506
OS -4.48685158 -36.76241822
OS -4.48685158 -36.76103138
OS -4.48823842 -36.75271034
OS -4.48962526 -36.74022878
OS -4.49239894 -36.7235867
OS -4.49933314 -36.70694462
OS -4.50765418 -36.68752886
OS -4.52013574 -36.66949994
OS -4.53677782 -36.65147102
OS -4.5395515 -36.65008418
OS -4.5464857 -36.64453682
OS -4.55758042 -36.63760262
OS -4.57560934 -36.62928158
OS -4.59641194 -36.62096054
OS -4.62414874 -36.61402634
OS -4.65604606 -36.60847898
OS -4.69349074 -36.60709214
OE
OB -2.48841514 -36.60015794 H
OS -2.48841514 -36.60154478
OS -2.48980198 -36.60431846
OS -2.48980198 -36.60986582
OS -2.49257566 -36.61541318
OS -2.4939625 -36.62512106
OS -2.49673618 -36.63482894
OS -2.50228354 -36.65840522
OS -2.50921774 -36.68614202
OS -2.51892562 -36.7166525
OS -2.5286335 -36.74993666
OS -2.54111506 -36.78460766
OS -2.64512806 -37.06474934
OS -2.3206075 -37.06474934
OS -2.42045998 -36.80124974
OS -2.42045998 -36.7998629
OS -2.42184682 -36.79570238
OS -2.4246205 -36.78876818
OS -2.42739418 -36.78044714
OS -2.4315547 -36.77073926
OS -2.43571522 -36.7582577
OS -2.43987574 -36.7443893
OS -2.4454231 -36.7305209
OS -2.45651782 -36.69862358
OS -2.46761254 -36.66533942
OS -2.47870726 -36.63205526
OS -2.48841514 -36.60015794
OE
SE
S P 0
OB 35.73690338 -37.45999874 I
OS 35.61486146 -37.45999874
OS 35.61486146 -36.65701838
OS 35.33471978 -37.45999874
OS 35.2209989 -37.45999874
OS 34.9436309 -36.64314998
OS 34.9436309 -37.45999874
OS 34.82158898 -37.45999874
OS 34.82158898 -36.50030546
OS 35.01158606 -36.50030546
OS 35.23902782 -37.1812439
OS 35.23902782 -37.18263074
OS 35.24041466 -37.18540442
OS 35.2418015 -37.18956494
OS 35.24457518 -37.19649914
OS 35.25012254 -37.21314122
OS 35.25705674 -37.23394382
OS 35.26399094 -37.2575201
OS 35.27231198 -37.28109638
OS 35.27924618 -37.30328582
OS 35.28479354 -37.32270158
OS 35.28618038 -37.3199279
OS 35.28756722 -37.3129937
OS 35.29172774 -37.30051214
OS 35.2972751 -37.28387006
OS 35.3042093 -37.26168062
OS 35.31391718 -37.23533066
OS 35.32362506 -37.20482018
OS 35.33610662 -37.16876234
OS 35.56632206 -36.50030546
OS 35.73690338 -36.50030546
OS 35.73690338 -37.45999874
OE
OB 34.61356298 -37.05504146 I
OS 34.61356298 -37.0564283
OS 34.61356298 -37.06197566
OS 34.61356298 -37.06890986
OS 34.61356298 -37.07861774
OS 34.61217614 -37.0910993
OS 34.61217614 -37.1049677
OS 34.6107893 -37.12160978
OS 34.60940246 -37.13825186
OS 34.60524194 -37.17569654
OS 34.59969458 -37.21452806
OS 34.59137354 -37.25197274
OS 34.58582618 -37.27000166
OS 34.58027882 -37.28664374
OS 34.58027882 -37.28803058
OS 34.57889198 -37.29080426
OS 34.5761183 -37.29496478
OS 34.57334462 -37.30051214
OS 34.56502358 -37.31576738
OS 34.55254202 -37.33518314
OS 34.53589994 -37.35737258
OS 34.51648418 -37.37956202
OS 34.49152106 -37.4031383
OS 34.46101058 -37.4239409
OS 34.45962374 -37.4239409
OS 34.45685006 -37.42671458
OS 34.45268954 -37.42810142
OS 34.44575534 -37.43226194
OS 34.4374343 -37.43642246
OS 34.42633958 -37.44058298
OS 34.41524486 -37.4447435
OS 34.40137646 -37.45029086
OS 34.38612122 -37.45583822
OS 34.36947914 -37.45999874
OS 34.35145022 -37.46415926
OS 34.33064762 -37.46831978
OS 34.30984502 -37.47109346
OS 34.28765558 -37.47386714
OS 34.23772934 -37.47664082
OS 34.22524778 -37.47664082
OS 34.2155399 -37.47525398
OS 34.20444518 -37.47525398
OS 34.19057678 -37.47386714
OS 34.17532154 -37.4724803
OS 34.1600663 -37.47109346
OS 34.1253953 -37.4655461
OS 34.08795062 -37.45722506
OS 34.05189278 -37.44613034
OS 34.01722178 -37.4308751
OS 34.01583494 -37.4308751
OS 34.01306126 -37.42810142
OS 34.00890074 -37.42532774
OS 34.00335338 -37.42255406
OS 33.98809814 -37.41145934
OS 33.97006922 -37.3962041
OS 33.94926662 -37.37678834
OS 33.92985086 -37.3545989
OS 33.9104351 -37.3268621
OS 33.89517986 -37.29635162
OS 33.89517986 -37.29496478
OS 33.89379302 -37.2921911
OS 33.89240618 -37.28664374
OS 33.8896325 -37.27970954
OS 33.88685882 -37.2713885
OS 33.88408514 -37.26029378
OS 33.87992462 -37.24781222
OS 33.87715094 -37.23255698
OS 33.87437726 -37.2159149
OS 33.87021674 -37.19788598
OS 33.86744306 -37.17847022
OS 33.86466938 -37.15766762
OS 33.8618957 -37.13409134
OS 33.86050886 -37.10912822
OS 33.85912202 -37.08277826
OS 33.85912202 -37.05504146
OS 33.85912202 -36.50030546
OS 33.9867113 -36.50030546
OS 33.9867113 -37.05504146
OS 33.9867113 -37.0564283
OS 33.9867113 -37.06058882
OS 33.9867113 -37.06752302
OS 33.9867113 -37.07584406
OS 33.98809814 -37.08555194
OS 33.98809814 -37.0980335
OS 33.98948498 -37.12438346
OS 33.99225866 -37.15489394
OS 33.99641918 -37.18540442
OS 34.00196654 -37.21452806
OS 34.00474022 -37.22700962
OS 34.00890074 -37.23949118
OS 34.01028758 -37.24226486
OS 34.01306126 -37.24919906
OS 34.01999546 -37.25890694
OS 34.0283165 -37.27277534
OS 34.03802438 -37.28664374
OS 34.05189278 -37.30189898
OS 34.06853486 -37.31715422
OS 34.08795062 -37.32963578
OS 34.0907243 -37.33102262
OS 34.0976585 -37.33518314
OS 34.11014006 -37.33934366
OS 34.12678214 -37.34489102
OS 34.1461979 -37.35182522
OS 34.17116102 -37.35598574
OS 34.19751098 -37.36014626
OS 34.22663462 -37.3615331
OS 34.24050302 -37.3615331
OS 34.24882406 -37.36014626
OS 34.26130562 -37.36014626
OS 34.27378718 -37.35875942
OS 34.30429766 -37.35321206
OS 34.33758182 -37.34627786
OS 34.36947914 -37.33518314
OS 34.39998962 -37.3199279
OS 34.41385802 -37.31022002
OS 34.42633958 -37.2991253
OS 34.42772642 -37.29773846
OS 34.42911326 -37.29635162
OS 34.43188694 -37.2921911
OS 34.43604746 -37.28664374
OS 34.44020798 -37.2783227
OS 34.44575534 -37.27000166
OS 34.4513027 -37.2575201
OS 34.45685006 -37.24503854
OS 34.46239742 -37.2297833
OS 34.46655794 -37.21175438
OS 34.4721053 -37.19095178
OS 34.47626582 -37.16876234
OS 34.48042634 -37.14379922
OS 34.48320002 -37.11744926
OS 34.4859737 -37.08693878
OS 34.4859737 -37.05504146
OS 34.4859737 -36.50030546
OS 34.61356298 -36.50030546
OS 34.61356298 -37.05504146
OE
OB 33.64416182 -37.45999874 I
OS 33.51241202 -37.45999874
OS 33.01037594 -36.70694462
OS 33.01037594 -37.45999874
OS 32.88833402 -37.45999874
OS 32.88833402 -36.50030546
OS 33.01869698 -36.50030546
OS 33.5221199 -37.25474642
OS 33.5221199 -36.50030546
OS 33.64416182 -36.50030546
OS 33.64416182 -37.45999874
OE
OB 38.19022334 -36.5016923 I
OS 38.2027049 -36.5016923
OS 38.23182854 -36.50307914
OS 38.26233902 -36.50723966
OS 38.29562318 -36.51140018
OS 38.32613366 -36.51833438
OS 38.3413889 -36.5224949
OS 38.35387046 -36.52665542
OS 38.3552573 -36.52665542
OS 38.35664414 -36.52804226
OS 38.36496518 -36.53220278
OS 38.37744674 -36.53775014
OS 38.39270198 -36.54745802
OS 38.40934406 -36.55993958
OS 38.42737298 -36.57658166
OS 38.44401506 -36.59599742
OS 38.46065714 -36.61818686
OS 38.46065714 -36.6195737
OS 38.46204398 -36.62096054
OS 38.46759134 -36.62928158
OS 38.4731387 -36.64314998
OS 38.48145974 -36.6611789
OS 38.48839394 -36.6819815
OS 38.49532814 -36.70694462
OS 38.49948866 -36.73329458
OS 38.5008755 -36.76241822
OS 38.5008755 -36.76380506
OS 38.5008755 -36.76657874
OS 38.5008755 -36.7721261
OS 38.49948866 -36.7790603
OS 38.49948866 -36.78876818
OS 38.49810182 -36.79847606
OS 38.49255446 -36.82205234
OS 38.48423342 -36.84978914
OS 38.4731387 -36.87891278
OS 38.45649662 -36.90803642
OS 38.4454019 -36.92190482
OS 38.43430718 -36.93577322
OS 38.43292034 -36.93716006
OS 38.4315335 -36.9385469
OS 38.42737298 -36.94270742
OS 38.42182562 -36.94686794
OS 38.41489142 -36.9524153
OS 38.40657038 -36.95796266
OS 38.39547566 -36.96489686
OS 38.38438094 -36.9732179
OS 38.37051254 -36.9801521
OS 38.3552573 -36.9870863
OS 38.33861522 -36.99540734
OS 38.3205863 -37.00234154
OS 38.2997837 -37.0078889
OS 38.2789811 -37.0148231
OS 38.25540482 -37.01898362
OS 38.2304417 -37.02314414
OS 38.23321538 -37.02453098
OS 38.23876274 -37.02730466
OS 38.24708378 -37.03285202
OS 38.2581785 -37.03839938
OS 38.28314162 -37.05365462
OS 38.29562318 -37.0633625
OS 38.3067179 -37.07168354
OS 38.30949158 -37.07445722
OS 38.31642578 -37.08139142
OS 38.3275205 -37.09248614
OS 38.3413889 -37.10635454
OS 38.35664414 -37.1257703
OS 38.37467306 -37.1465729
OS 38.39270198 -37.17153602
OS 38.41211774 -37.19927282
OS 38.5771517 -37.45999874
OS 38.41905194 -37.45999874
OS 38.2928495 -37.26029378
OS 38.2928495 -37.25890694
OS 38.29007582 -37.25613326
OS 38.28730214 -37.25197274
OS 38.28314162 -37.24642538
OS 38.27343374 -37.23117014
OS 38.26095218 -37.21175438
OS 38.24569694 -37.19095178
OS 38.2304417 -37.16876234
OS 38.21518646 -37.14795974
OS 38.20131806 -37.12854398
OS 38.19993122 -37.12715714
OS 38.1957707 -37.12160978
OS 38.1888365 -37.11328874
OS 38.17912862 -37.10358086
OS 38.15832602 -37.08277826
OS 38.1472313 -37.07307038
OS 38.13613658 -37.06474934
OS 38.13474974 -37.0633625
OS 38.13197606 -37.06197566
OS 38.1264287 -37.05920198
OS 38.11810766 -37.05504146
OS 38.10978662 -37.05088094
OS 38.10007874 -37.04672042
OS 38.0778893 -37.03978622
OS 38.07650246 -37.03978622
OS 38.07372878 -37.03839938
OS 38.06818142 -37.03839938
OS 38.06124722 -37.03701254
OS 38.05153934 -37.0356257
OS 38.04044462 -37.0356257
OS 38.02518938 -37.03423886
OS 37.86154226 -37.03423886
OS 37.86154226 -37.45999874
OS 37.73395298 -37.45999874
OS 37.73395298 -36.50030546
OS 38.17912862 -36.50030546
OS 38.19022334 -36.5016923
OE
OB 37.53424802 -36.61402634 I
OS 36.96703046 -36.61402634
OS 36.96703046 -36.90664958
OS 37.49819018 -36.90664958
OS 37.49819018 -37.02037046
OS 36.96703046 -37.02037046
OS 36.96703046 -37.34627786
OS 37.55643746 -37.34627786
OS 37.55643746 -37.45999874
OS 36.83944118 -37.45999874
OS 36.83944118 -36.50030546
OS 37.53424802 -36.50030546
OS 37.53424802 -36.61402634
OE
OB 36.32492354 -36.5016923 I
OS 36.33601826 -36.5016923
OS 36.36098138 -36.50446598
OS 36.38871818 -36.50723966
OS 36.41784182 -36.51278702
OS 36.44696546 -36.51972122
OS 36.47331542 -36.5294291
OS 36.47470226 -36.5294291
OS 36.4760891 -36.53081594
OS 36.48441014 -36.53497646
OS 36.4968917 -36.54191066
OS 36.5107601 -36.55161854
OS 36.52740218 -36.5641001
OS 36.5454311 -36.57935534
OS 36.56207318 -36.5987711
OS 36.57732842 -36.6195737
OS 36.57871526 -36.62234738
OS 36.58287578 -36.63066842
OS 36.58980998 -36.64176314
OS 36.59674418 -36.65840522
OS 36.60367838 -36.67782098
OS 36.61061258 -36.69862358
OS 36.6147731 -36.72219986
OS 36.61615994 -36.74577614
OS 36.61615994 -36.74854982
OS 36.61615994 -36.75548402
OS 36.6147731 -36.76796558
OS 36.61199942 -36.78322082
OS 36.6078389 -36.80124974
OS 36.6009047 -36.8206655
OS 36.59258366 -36.84008126
OS 36.58148894 -36.86088386
OS 36.5801021 -36.86365754
OS 36.57594158 -36.8692049
OS 36.56762054 -36.88029962
OS 36.55652582 -36.89139434
OS 36.54265742 -36.90526274
OS 36.52601534 -36.92051798
OS 36.50521274 -36.93438638
OS 36.48163646 -36.94825478
OS 36.4830233 -36.94825478
OS 36.48579698 -36.94964162
OS 36.4899575 -36.95102846
OS 36.49550486 -36.95380214
OS 36.51214694 -36.9593495
OS 36.5315627 -36.96905738
OS 36.5523653 -36.98153894
OS 36.57594158 -36.99679418
OS 36.59674418 -37.0148231
OS 36.61615994 -37.03701254
OS 36.61754678 -37.03978622
OS 36.62309414 -37.04810726
OS 36.63141518 -37.06058882
OS 36.63973622 -37.0772309
OS 36.64805726 -37.09942034
OS 36.6563783 -37.12299662
OS 36.66192566 -37.15073342
OS 36.6633125 -37.1812439
OS 36.6633125 -37.18263074
OS 36.6633125 -37.18401758
OS 36.6633125 -37.19233862
OS 36.66192566 -37.20620702
OS 36.65915198 -37.2228491
OS 36.6563783 -37.24226486
OS 36.65083094 -37.26306746
OS 36.64389674 -37.2852569
OS 36.63418886 -37.30744634
OS 36.63280202 -37.31022002
OS 36.6286415 -37.31715422
OS 36.62309414 -37.3268621
OS 36.6147731 -37.3407305
OS 36.60367838 -37.3545989
OS 36.59258366 -37.36985414
OS 36.57871526 -37.38510938
OS 36.56346002 -37.39759094
OS 36.56207318 -37.39897778
OS 36.55652582 -37.4031383
OS 36.54681794 -37.40868566
OS 36.53433638 -37.41423302
OS 36.51908114 -37.42255406
OS 36.50105222 -37.4308751
OS 36.48163646 -37.4378093
OS 36.45806018 -37.4447435
OS 36.4552865 -37.4447435
OS 36.44696546 -37.44751718
OS 36.43309706 -37.44890402
OS 36.41506814 -37.4516777
OS 36.3928787 -37.45445138
OS 36.36652874 -37.45722506
OS 36.3374051 -37.4586119
OS 36.30412094 -37.45999874
OS 35.93799518 -37.45999874
OS 35.93799518 -36.50030546
OS 36.31521566 -36.50030546
OS 36.32492354 -36.5016923
OE
OB 32.3849111 -36.61402634 I
OS 32.06871158 -36.61402634
OS 32.06871158 -37.45999874
OS 31.9411223 -37.45999874
OS 31.9411223 -36.61402634
OS 31.62492278 -36.61402634
OS 31.62492278 -36.50030546
OS 32.3849111 -36.50030546
OS 32.3849111 -36.61402634
OE
OB 30.62639798 -37.45999874 I
OS 30.48216662 -37.45999874
OS 30.36983258 -37.16876234
OS 29.96764898 -37.16876234
OS 29.86363598 -37.45999874
OS 29.7291125 -37.45999874
OS 30.09523826 -36.50030546
OS 30.23392226 -36.50030546
OS 30.62639798 -37.45999874
OE
OB 29.3546657 -36.5016923 I
OS 29.37824198 -36.50307914
OS 29.4032051 -36.50446598
OS 29.42678138 -36.50723966
OS 29.44758398 -36.51001334
OS 29.45035766 -36.51001334
OS 29.46006554 -36.51278702
OS 29.4725471 -36.5155607
OS 29.48918918 -36.51972122
OS 29.5072181 -36.52665542
OS 29.52663386 -36.53497646
OS 29.54743646 -36.54468434
OS 29.56546538 -36.55577906
OS 29.56823906 -36.5571659
OS 29.57378642 -36.56132642
OS 29.58210746 -36.56964746
OS 29.59320218 -36.57935534
OS 29.60568374 -36.5918369
OS 29.6181653 -36.60847898
OS 29.6320337 -36.6265079
OS 29.64312842 -36.6473105
OS 29.64451526 -36.65008418
OS 29.64728894 -36.65701838
OS 29.6528363 -36.66949994
OS 29.65838366 -36.68614202
OS 29.66254418 -36.70555778
OS 29.66809154 -36.72774722
OS 29.67086522 -36.75271034
OS 29.67225206 -36.7790603
OS 29.67225206 -36.78044714
OS 29.67225206 -36.78460766
OS 29.67225206 -36.79015502
OS 29.67086522 -36.7998629
OS 29.66947838 -36.80957078
OS 29.66809154 -36.82205234
OS 29.66531786 -36.83592074
OS 29.66254418 -36.85117598
OS 29.6528363 -36.8830733
OS 29.64728894 -36.89971538
OS 29.6389679 -36.9177443
OS 29.62926002 -36.93577322
OS 29.61955214 -36.9524153
OS 29.60707058 -36.96905738
OS 29.59320218 -36.98569946
OS 29.59181534 -36.9870863
OS 29.58904166 -36.98985998
OS 29.58488114 -36.9940205
OS 29.57794694 -36.99818102
OS 29.5696259 -37.00511522
OS 29.55853118 -37.01204942
OS 29.54466278 -37.02037046
OS 29.52940754 -37.02730466
OS 29.51137862 -37.0356257
OS 29.49057602 -37.04394674
OS 29.46838658 -37.05088094
OS 29.44203662 -37.0564283
OS 29.41429982 -37.06197566
OS 29.38378934 -37.06613618
OS 29.34911834 -37.06890986
OS 29.3130605 -37.0702967
OS 29.06758982 -37.0702967
OS 29.06758982 -37.45999874
OS 28.94000054 -37.45999874
OS 28.94000054 -36.50030546
OS 29.3338631 -36.50030546
OS 29.3546657 -36.5016923
OE
OB 31.18668134 -36.5016923 I
OS 31.1991629 -36.5016923
OS 31.22828654 -36.50307914
OS 31.25879702 -36.50723966
OS 31.29208118 -36.51140018
OS 31.32259166 -36.51833438
OS 31.3378469 -36.5224949
OS 31.35032846 -36.52665542
OS 31.3517153 -36.52665542
OS 31.35310214 -36.52804226
OS 31.36142318 -36.53220278
OS 31.37390474 -36.53775014
OS 31.38915998 -36.54745802
OS 31.40580206 -36.55993958
OS 31.42383098 -36.57658166
OS 31.44047306 -36.59599742
OS 31.45711514 -36.61818686
OS 31.45711514 -36.6195737
OS 31.45850198 -36.62096054
OS 31.46404934 -36.62928158
OS 31.4695967 -36.64314998
OS 31.47791774 -36.6611789
OS 31.48485194 -36.6819815
OS 31.49178614 -36.70694462
OS 31.49594666 -36.73329458
OS 31.4973335 -36.76241822
OS 31.4973335 -36.76380506
OS 31.4973335 -36.76657874
OS 31.4973335 -36.7721261
OS 31.49594666 -36.7790603
OS 31.49594666 -36.78876818
OS 31.49455982 -36.79847606
OS 31.48901246 -36.82205234
OS 31.48069142 -36.84978914
OS 31.4695967 -36.87891278
OS 31.45295462 -36.90803642
OS 31.4418599 -36.92190482
OS 31.43076518 -36.93577322
OS 31.42937834 -36.93716006
OS 31.4279915 -36.9385469
OS 31.42383098 -36.94270742
OS 31.41828362 -36.94686794
OS 31.41134942 -36.9524153
OS 31.40302838 -36.95796266
OS 31.39193366 -36.96489686
OS 31.38083894 -36.9732179
OS 31.36697054 -36.9801521
OS 31.3517153 -36.9870863
OS 31.33507322 -36.99540734
OS 31.3170443 -37.00234154
OS 31.2962417 -37.0078889
OS 31.2754391 -37.0148231
OS 31.25186282 -37.01898362
OS 31.2268997 -37.02314414
OS 31.22967338 -37.02453098
OS 31.23522074 -37.02730466
OS 31.24354178 -37.03285202
OS 31.2546365 -37.03839938
OS 31.27959962 -37.05365462
OS 31.29208118 -37.0633625
OS 31.3031759 -37.07168354
OS 31.30594958 -37.07445722
OS 31.31288378 -37.08139142
OS 31.3239785 -37.09248614
OS 31.3378469 -37.10635454
OS 31.35310214 -37.1257703
OS 31.37113106 -37.1465729
OS 31.38915998 -37.17153602
OS 31.40857574 -37.19927282
OS 31.5736097 -37.45999874
OS 31.41550994 -37.45999874
OS 31.2893075 -37.26029378
OS 31.2893075 -37.25890694
OS 31.28653382 -37.25613326
OS 31.28376014 -37.25197274
OS 31.27959962 -37.24642538
OS 31.26989174 -37.23117014
OS 31.25741018 -37.21175438
OS 31.24215494 -37.19095178
OS 31.2268997 -37.16876234
OS 31.21164446 -37.14795974
OS 31.19777606 -37.12854398
OS 31.19638922 -37.12715714
OS 31.1922287 -37.12160978
OS 31.1852945 -37.11328874
OS 31.17558662 -37.10358086
OS 31.15478402 -37.08277826
OS 31.1436893 -37.07307038
OS 31.13259458 -37.06474934
OS 31.13120774 -37.0633625
OS 31.12843406 -37.06197566
OS 31.1228867 -37.05920198
OS 31.11456566 -37.05504146
OS 31.10624462 -37.05088094
OS 31.09653674 -37.04672042
OS 31.0743473 -37.03978622
OS 31.07296046 -37.03978622
OS 31.07018678 -37.03839938
OS 31.06463942 -37.03839938
OS 31.05770522 -37.03701254
OS 31.04799734 -37.0356257
OS 31.03690262 -37.0356257
OS 31.02164738 -37.03423886
OS 30.85800026 -37.03423886
OS 30.85800026 -37.45999874
OS 30.73041098 -37.45999874
OS 30.73041098 -36.50030546
OS 31.17558662 -36.50030546
OS 31.18668134 -36.5016923
OE
OB 38.16387338 -36.60709214 H
OS 37.86154226 -36.60709214
OS 37.86154226 -36.9246785
OS 38.1472313 -36.9246785
OS 38.16387338 -36.92329166
OS 38.18328914 -36.92190482
OS 38.20547858 -36.92051798
OS 38.22766802 -36.9177443
OS 38.24985746 -36.91358378
OS 38.26927322 -36.90803642
OS 38.2720469 -36.90664958
OS 38.27759426 -36.9038759
OS 38.2859153 -36.89971538
OS 38.29701002 -36.89416802
OS 38.30949158 -36.88584698
OS 38.32197314 -36.8761391
OS 38.3344547 -36.86365754
OS 38.34416258 -36.84978914
OS 38.34554942 -36.8484023
OS 38.3483231 -36.84285494
OS 38.35248362 -36.8345339
OS 38.35803098 -36.82343918
OS 38.3621915 -36.81095762
OS 38.36635202 -36.79708922
OS 38.3691257 -36.78044714
OS 38.37051254 -36.76380506
OS 38.37051254 -36.76241822
OS 38.37051254 -36.76103138
OS 38.3691257 -36.75271034
OS 38.36773886 -36.74022878
OS 38.36496518 -36.7235867
OS 38.35803098 -36.70694462
OS 38.34970994 -36.68752886
OS 38.33722838 -36.66949994
OS 38.3205863 -36.65147102
OS 38.31781262 -36.65008418
OS 38.31087842 -36.64453682
OS 38.2997837 -36.63760262
OS 38.28175478 -36.62928158
OS 38.26095218 -36.62096054
OS 38.23321538 -36.61402634
OS 38.20131806 -36.60847898
OS 38.16387338 -36.60709214
OE
OB 29.34218414 -36.61402634 H
OS 29.06758982 -36.61402634
OS 29.06758982 -36.95657582
OS 29.32554206 -36.95657582
OS 29.33524994 -36.95518898
OS 29.34495782 -36.95518898
OS 29.35605254 -36.95380214
OS 29.3824025 -36.95102846
OS 29.41152614 -36.9454811
OS 29.44064978 -36.93716006
OS 29.46699974 -36.92606534
OS 29.4794813 -36.91913114
OS 29.48918918 -36.9108101
OS 29.49196286 -36.90803642
OS 29.49751022 -36.90248906
OS 29.50583126 -36.89139434
OS 29.51553914 -36.87752594
OS 29.52524702 -36.85949702
OS 29.53356806 -36.83730758
OS 29.53911542 -36.81234446
OS 29.5418891 -36.78322082
OS 29.5418891 -36.78183398
OS 29.5418891 -36.78044714
OS 29.5418891 -36.77351294
OS 29.54050226 -36.76103138
OS 29.53772858 -36.74716298
OS 29.5349549 -36.73190774
OS 29.52940754 -36.71387882
OS 29.5210865 -36.69723674
OS 29.51137862 -36.68059466
OS 29.50999178 -36.67920782
OS 29.50583126 -36.67366046
OS 29.49889706 -36.66672626
OS 29.49057602 -36.65701838
OS 29.47809446 -36.6473105
OS 29.46422606 -36.63898946
OS 29.44897082 -36.63066842
OS 29.4309419 -36.62373422
OS 29.42955506 -36.62373422
OS 29.4240077 -36.62234738
OS 29.41568666 -36.62096054
OS 29.40459194 -36.61818686
OS 29.38794986 -36.61680002
OS 29.36714726 -36.61541318
OS 29.34218414 -36.61402634
OE
OB 30.16180658 -36.60015794 H
OS 30.16180658 -36.60154478
OS 30.16041974 -36.60431846
OS 30.16041974 -36.60986582
OS 30.15764606 -36.61541318
OS 30.15625922 -36.62512106
OS 30.15348554 -36.63482894
OS 30.14793818 -36.65840522
OS 30.14100398 -36.68614202
OS 30.1312961 -36.7166525
OS 30.12158822 -36.74993666
OS 30.10910666 -36.78460766
OS 30.00509366 -37.06474934
OS 30.32961422 -37.06474934
OS 30.22976174 -36.80124974
OS 30.22976174 -36.7998629
OS 30.2283749 -36.79570238
OS 30.22560122 -36.78876818
OS 30.22282754 -36.78044714
OS 30.21866702 -36.77073926
OS 30.2145065 -36.7582577
OS 30.21034598 -36.7443893
OS 30.20479862 -36.7305209
OS 30.1937039 -36.69862358
OS 30.18260918 -36.66533942
OS 30.17151446 -36.63205526
OS 30.16180658 -36.60015794
OE
OB 31.16033138 -36.60709214 H
OS 30.85800026 -36.60709214
OS 30.85800026 -36.9246785
OS 31.1436893 -36.9246785
OS 31.16033138 -36.92329166
OS 31.17974714 -36.92190482
OS 31.20193658 -36.92051798
OS 31.22412602 -36.9177443
OS 31.24631546 -36.91358378
OS 31.26573122 -36.90803642
OS 31.2685049 -36.90664958
OS 31.27405226 -36.9038759
OS 31.2823733 -36.89971538
OS 31.29346802 -36.89416802
OS 31.30594958 -36.88584698
OS 31.31843114 -36.8761391
OS 31.3309127 -36.86365754
OS 31.34062058 -36.84978914
OS 31.34200742 -36.8484023
OS 31.3447811 -36.84285494
OS 31.34894162 -36.8345339
OS 31.35448898 -36.82343918
OS 31.3586495 -36.81095762
OS 31.36281002 -36.79708922
OS 31.3655837 -36.78044714
OS 31.36697054 -36.76380506
OS 31.36697054 -36.76241822
OS 31.36697054 -36.76103138
OS 31.3655837 -36.75271034
OS 31.36419686 -36.74022878
OS 31.36142318 -36.7235867
OS 31.35448898 -36.70694462
OS 31.34616794 -36.68752886
OS 31.33368638 -36.66949994
OS 31.3170443 -36.65147102
OS 31.31427062 -36.65008418
OS 31.30733642 -36.64453682
OS 31.2962417 -36.63760262
OS 31.27821278 -36.62928158
OS 31.25741018 -36.62096054
OS 31.22967338 -36.61402634
OS 31.19777606 -36.60847898
OS 31.16033138 -36.60709214
OE
OB 36.29302622 -36.61402634 H
OS 36.06558446 -36.61402634
OS 36.06558446 -36.90248906
OS 36.30134726 -36.90248906
OS 36.31937618 -36.90110222
OS 36.33879194 -36.89971538
OS 36.3582077 -36.89832854
OS 36.37762346 -36.89555486
OS 36.3928787 -36.89278118
OS 36.39565238 -36.89139434
OS 36.40119974 -36.8900075
OS 36.40952078 -36.88584698
OS 36.4206155 -36.88029962
OS 36.43171022 -36.87475226
OS 36.44419178 -36.86643122
OS 36.45667334 -36.8553365
OS 36.46638122 -36.84424178
OS 36.46776806 -36.84285494
OS 36.47054174 -36.83869442
OS 36.47470226 -36.83037338
OS 36.47886278 -36.8206655
OS 36.4830233 -36.80957078
OS 36.48718382 -36.79570238
OS 36.4899575 -36.7790603
OS 36.49134434 -36.76103138
OS 36.49134434 -36.7582577
OS 36.49134434 -36.75271034
OS 36.4899575 -36.7443893
OS 36.48857066 -36.73329458
OS 36.48579698 -36.71942618
OS 36.48163646 -36.70555778
OS 36.4760891 -36.69168938
OS 36.46776806 -36.67782098
OS 36.46638122 -36.67643414
OS 36.46360754 -36.67227362
OS 36.45806018 -36.66533942
OS 36.45112598 -36.65840522
OS 36.4414181 -36.65008418
OS 36.43032338 -36.64176314
OS 36.41645498 -36.6334421
OS 36.40119974 -36.62789474
OS 36.3998129 -36.62789474
OS 36.3928787 -36.62512106
OS 36.38317082 -36.62373422
OS 36.36791558 -36.62096054
OS 36.34711298 -36.61818686
OS 36.3235367 -36.61680002
OS 36.29302622 -36.61402634
OE
OB 36.31798934 -37.01620994 H
OS 36.06558446 -37.01620994
OS 36.06558446 -37.34627786
OS 36.33879194 -37.34627786
OS 36.36791558 -37.34489102
OS 36.38039714 -37.34350418
OS 36.39149186 -37.34211734
OS 36.3928787 -37.34211734
OS 36.39842606 -37.3407305
OS 36.4067471 -37.33934366
OS 36.41645498 -37.33656998
OS 36.44003126 -37.32824894
OS 36.46360754 -37.31715422
OS 36.46499438 -37.31576738
OS 36.4691549 -37.3129937
OS 36.47470226 -37.30883318
OS 36.48163646 -37.30328582
OS 36.48857066 -37.29496478
OS 36.49827854 -37.28664374
OS 36.50521274 -37.27554902
OS 36.51353378 -37.26306746
OS 36.51492062 -37.26168062
OS 36.51630746 -37.2575201
OS 36.51908114 -37.24919906
OS 36.52324166 -37.23949118
OS 36.52740218 -37.22839646
OS 36.53017586 -37.21452806
OS 36.5315627 -37.19788598
OS 36.53294954 -37.1812439
OS 36.53294954 -37.17847022
OS 36.53294954 -37.17292286
OS 36.5315627 -37.16182814
OS 36.52878902 -37.14934658
OS 36.52601534 -37.13547818
OS 36.52046798 -37.12022294
OS 36.51353378 -37.1049677
OS 36.5038259 -37.08971246
OS 36.50243906 -37.08832562
OS 36.49827854 -37.08277826
OS 36.49273118 -37.07584406
OS 36.48441014 -37.06752302
OS 36.47331542 -37.05781514
OS 36.45944702 -37.04810726
OS 36.44419178 -37.03978622
OS 36.42616286 -37.03285202
OS 36.42338918 -37.03146518
OS 36.41784182 -37.03007834
OS 36.40536026 -37.02730466
OS 36.39010502 -37.02453098
OS 36.37068926 -37.0217573
OS 36.34711298 -37.01898362
OS 36.31798934 -37.01620994
OE
SE
S P 0
OB 40.9056459 -38.32112732 I
OS 40.92136342 -38.32205188
OS 40.9380055 -38.32297644
OS 40.95372302 -38.32482556
OS 40.96759142 -38.32667468
OS 40.96944054 -38.32667468
OS 40.97591246 -38.3285238
OS 40.9842335 -38.33037292
OS 40.99532822 -38.3331466
OS 41.0073475 -38.3377694
OS 41.02029134 -38.34331676
OS 41.03415974 -38.34978868
OS 41.04617902 -38.35718516
OS 41.04802814 -38.35810972
OS 41.05172638 -38.3608834
OS 41.05727374 -38.36643076
OS 41.06467022 -38.37290268
OS 41.07299126 -38.38122372
OS 41.0813123 -38.39231844
OS 41.0905579 -38.40433772
OS 41.09795438 -38.41820612
OS 41.09887894 -38.42005524
OS 41.10072806 -38.42467804
OS 41.1044263 -38.43299908
OS 41.10812454 -38.4440938
OS 41.11089822 -38.45703764
OS 41.11459646 -38.4718306
OS 41.11644558 -38.48847268
OS 41.11737014 -38.50603932
OS 41.11737014 -38.50696388
OS 41.11737014 -38.50973756
OS 41.11737014 -38.5134358
OS 41.11644558 -38.51990772
OS 41.11552102 -38.52637964
OS 41.11459646 -38.53470068
OS 41.11274734 -38.54394628
OS 41.11089822 -38.55411644
OS 41.1044263 -38.57538132
OS 41.10072806 -38.58647604
OS 41.0951807 -38.59849532
OS 41.08870878 -38.6105146
OS 41.08223686 -38.62160932
OS 41.07391582 -38.63270404
OS 41.06467022 -38.64379876
OS 41.06374566 -38.64472332
OS 41.06189654 -38.64657244
OS 41.05912286 -38.64934612
OS 41.05450006 -38.6521198
OS 41.0489527 -38.6567426
OS 41.04155622 -38.6613654
OS 41.03231062 -38.66691276
OS 41.02214046 -38.67153556
OS 41.01012118 -38.67708292
OS 40.99625278 -38.68263028
OS 40.98145982 -38.68725308
OS 40.96389318 -38.69095132
OS 40.94540198 -38.69464956
OS 40.92506166 -38.69742324
OS 40.90194766 -38.69927236
OS 40.8779091 -38.70019692
OS 40.71426198 -38.70019692
OS 40.71426198 -38.95999828
OS 40.62920246 -38.95999828
OS 40.62920246 -38.32020276
OS 40.8917775 -38.32020276
OS 40.9056459 -38.32112732
OE
OB 40.49791494 -38.98403684 I
OS 40.49791494 -38.9849614
OS 40.49791494 -38.98773508
OS 40.49791494 -38.99235788
OS 40.49791494 -38.99790524
OS 40.49699038 -39.00530172
OS 40.49699038 -39.0126982
OS 40.49514126 -39.0311894
OS 40.49236758 -39.05060516
OS 40.48866934 -39.07094548
OS 40.48312198 -39.08851212
OS 40.47942374 -39.09683316
OS 40.4757255 -39.10330508
OS 40.4757255 -39.10422964
OS 40.47480094 -39.1051542
OS 40.47017814 -39.109777
OS 40.46278166 -39.11717348
OS 40.45353606 -39.12549452
OS 40.44059222 -39.13381556
OS 40.42395014 -39.14028748
OS 40.40453438 -39.14583484
OS 40.39343966 -39.1467594
OS 40.38142038 -39.14768396
OS 40.37587302 -39.14768396
OS 40.37032566 -39.1467594
OS 40.36200462 -39.1467594
OS 40.35275902 -39.14583484
OS 40.34258886 -39.14398572
OS 40.32039942 -39.13843836
OS 40.33519238 -39.07187004
OS 40.33611694 -39.07187004
OS 40.33889062 -39.0727946
OS 40.34351342 -39.07371916
OS 40.34813622 -39.07464372
OS 40.3601555 -39.0774174
OS 40.36570286 -39.07834196
OS 40.37494846 -39.07834196
OS 40.37957126 -39.0774174
OS 40.38511862 -39.07649284
OS 40.39066598 -39.07464372
OS 40.39621334 -39.07094548
OS 40.40268526 -39.06724724
OS 40.40730806 -39.06169988
OS 40.40823262 -39.06077532
OS 40.40915718 -39.05800164
OS 40.4110063 -39.05337884
OS 40.41377998 -39.04598236
OS 40.4156291 -39.0358122
OS 40.41655366 -39.02841572
OS 40.41747822 -39.0219438
OS 40.41840278 -39.01362276
OS 40.41840278 -39.0034526
OS 40.41932734 -38.99328244
OS 40.41932734 -38.98218772
OS 40.41932734 -38.49586916
OS 40.49791494 -38.49586916
OS 40.49791494 -38.98403684
OE
OB 41.51770462 -38.3100326 I
OS 41.52602566 -38.31095716
OS 41.53619582 -38.31188172
OS 41.54636598 -38.31280628
OS 41.55838526 -38.31557996
OS 41.58334838 -38.32112732
OS 41.61108518 -38.32944836
OS 41.62495358 -38.33499572
OS 41.63789742 -38.34146764
OS 41.65084126 -38.34978868
OS 41.6637851 -38.35810972
OS 41.66470966 -38.35903428
OS 41.66655878 -38.35995884
OS 41.67025702 -38.36273252
OS 41.67487982 -38.36735532
OS 41.67950262 -38.37197812
OS 41.68597454 -38.37845004
OS 41.69244646 -38.38584652
OS 41.69984294 -38.393243
OS 41.70723942 -38.4024886
OS 41.7146359 -38.41358332
OS 41.72295694 -38.42467804
OS 41.73035342 -38.43669732
OS 41.73682534 -38.45056572
OS 41.74422182 -38.46443412
OS 41.74976918 -38.47922708
OS 41.75531654 -38.49586916
OS 41.67210614 -38.51528492
OS 41.67210614 -38.51436036
OS 41.67118158 -38.51251124
OS 41.66933246 -38.508813
OS 41.66748334 -38.5041902
OS 41.66563422 -38.49864284
OS 41.66286054 -38.49124636
OS 41.65546406 -38.4764534
OS 41.64621846 -38.45981132
OS 41.63512374 -38.44316924
OS 41.62125534 -38.42745172
OS 41.60646238 -38.41358332
OS 41.60461326 -38.4117342
OS 41.5990659 -38.40803596
OS 41.5898203 -38.40341316
OS 41.57780102 -38.39694124
OS 41.5620835 -38.39139388
OS 41.54451686 -38.38584652
OS 41.52325198 -38.38214828
OS 41.50013798 -38.38122372
OS 41.4927415 -38.38122372
OS 41.4881187 -38.38214828
OS 41.48164678 -38.38214828
OS 41.4742503 -38.38307284
OS 41.45668366 -38.38584652
OS 41.4372679 -38.38954476
OS 41.41692758 -38.39601668
OS 41.3956627 -38.40526228
OS 41.37624694 -38.41728156
OS 41.37532238 -38.41728156
OS 41.37439782 -38.41913068
OS 41.3679259 -38.42375348
OS 41.35960486 -38.43114996
OS 41.3494347 -38.44224468
OS 41.33741542 -38.45611308
OS 41.3263207 -38.4718306
OS 41.31615054 -38.49124636
OS 41.30690494 -38.51251124
OS 41.30690494 -38.5134358
OS 41.30598038 -38.51528492
OS 41.30505582 -38.5180586
OS 41.30413126 -38.5226814
OS 41.30228214 -38.52822876
OS 41.30043302 -38.53470068
OS 41.29765934 -38.5504182
OS 41.2939611 -38.5689094
OS 41.29026286 -38.58924972
OS 41.28841374 -38.61143916
OS 41.28748918 -38.63547772
OS 41.28748918 -38.63640228
OS 41.28748918 -38.63917596
OS 41.28748918 -38.64379876
OS 41.28748918 -38.64934612
OS 41.28841374 -38.65581804
OS 41.28841374 -38.66413908
OS 41.2893383 -38.67338468
OS 41.29026286 -38.68355484
OS 41.29303654 -38.70574428
OS 41.29765934 -38.72978284
OS 41.3032067 -38.7538214
OS 41.31060318 -38.77785996
OS 41.31060318 -38.77878452
OS 41.31152774 -38.78063364
OS 41.31337686 -38.78340732
OS 41.31522598 -38.78803012
OS 41.32077334 -38.79912484
OS 41.32909438 -38.81206868
OS 41.33926454 -38.82686164
OS 41.35220838 -38.84257916
OS 41.36700134 -38.85644756
OS 41.38456798 -38.8693914
OS 41.38549254 -38.8693914
OS 41.38734166 -38.87031596
OS 41.39011534 -38.87216508
OS 41.39381358 -38.8740142
OS 41.39843638 -38.87586332
OS 41.40398374 -38.878637
OS 41.41692758 -38.88418436
OS 41.43356966 -38.88973172
OS 41.45206086 -38.89435452
OS 41.47240118 -38.89805276
OS 41.49366606 -38.89897732
OS 41.50013798 -38.89897732
OS 41.50568534 -38.89805276
OS 41.51215726 -38.89805276
OS 41.51862918 -38.8971282
OS 41.53527126 -38.89342996
OS 41.55468702 -38.88880716
OS 41.57410278 -38.88141068
OS 41.5944431 -38.87124052
OS 41.60461326 -38.86569316
OS 41.61385886 -38.85829668
OS 41.61478342 -38.85737212
OS 41.61570798 -38.85644756
OS 41.61848166 -38.85367388
OS 41.6221799 -38.8509002
OS 41.62587814 -38.8462774
OS 41.63050094 -38.84073004
OS 41.6360483 -38.83518268
OS 41.6406711 -38.8277862
OS 41.64621846 -38.81946516
OS 41.65269038 -38.81021956
OS 41.65823774 -38.80097396
OS 41.6637851 -38.78987924
OS 41.6684079 -38.77785996
OS 41.6730307 -38.76491612
OS 41.6776535 -38.75104772
OS 41.68135174 -38.73625476
OS 41.76641126 -38.75751964
OS 41.76641126 -38.7584442
OS 41.7654867 -38.76214244
OS 41.76363758 -38.7676898
OS 41.7608639 -38.77508628
OS 41.75809022 -38.78340732
OS 41.75439198 -38.79357748
OS 41.74976918 -38.8046722
OS 41.74422182 -38.81669148
OS 41.73127798 -38.84257916
OS 41.7146359 -38.86846684
OS 41.70446574 -38.88141068
OS 41.69429558 -38.89435452
OS 41.68320086 -38.90544924
OS 41.67025702 -38.91654396
OS 41.66933246 -38.91746852
OS 41.66748334 -38.91931764
OS 41.66286054 -38.92116676
OS 41.65823774 -38.924865
OS 41.65084126 -38.9294878
OS 41.64344478 -38.9341106
OS 41.63327462 -38.9387334
OS 41.62310446 -38.9433562
OS 41.61108518 -38.94890356
OS 41.59814134 -38.95352636
OS 41.58427294 -38.95814916
OS 41.56947998 -38.96277196
OS 41.55376246 -38.9664702
OS 41.53712038 -38.96831932
OS 41.51955374 -38.97016844
OS 41.50106254 -38.971093
OS 41.49089238 -38.971093
OS 41.4834959 -38.97016844
OS 41.47517486 -38.97016844
OS 41.4650047 -38.96924388
OS 41.45390998 -38.96739476
OS 41.44096614 -38.96554564
OS 41.4141539 -38.96092284
OS 41.3864171 -38.95352636
OS 41.3586803 -38.9433562
OS 41.34573646 -38.93688428
OS 41.33279262 -38.9294878
OS 41.33186806 -38.92856324
OS 41.33001894 -38.92763868
OS 41.3263207 -38.924865
OS 41.32262246 -38.92116676
OS 41.3170751 -38.91746852
OS 41.31060318 -38.91192116
OS 41.3032067 -38.90544924
OS 41.29581022 -38.89805276
OS 41.28841374 -38.88973172
OS 41.2800927 -38.88141068
OS 41.26345062 -38.8601458
OS 41.2477331 -38.83518268
OS 41.2338647 -38.80744588
OS 41.2338647 -38.80652132
OS 41.23201558 -38.80374764
OS 41.23109102 -38.79912484
OS 41.22831734 -38.79357748
OS 41.22646822 -38.786181
OS 41.22369454 -38.7769354
OS 41.2199963 -38.76676524
OS 41.21722262 -38.75567052
OS 41.21444894 -38.74365124
OS 41.2107507 -38.72978284
OS 41.2061279 -38.70112148
OS 41.20242966 -38.66876188
OS 41.20058054 -38.63547772
OS 41.20058054 -38.63455316
OS 41.20058054 -38.63085492
OS 41.20058054 -38.62530756
OS 41.2015051 -38.61883564
OS 41.2015051 -38.60959004
OS 41.20242966 -38.60034444
OS 41.20335422 -38.58832516
OS 41.20520334 -38.57630588
OS 41.20982614 -38.54949364
OS 41.21629806 -38.51990772
OS 41.22554366 -38.4903218
OS 41.2384875 -38.46166044
OS 41.23941206 -38.46073588
OS 41.24033662 -38.4579622
OS 41.24218574 -38.45426396
OS 41.24588398 -38.44964116
OS 41.24958222 -38.44316924
OS 41.25420502 -38.43577276
OS 41.2662243 -38.41913068
OS 41.28194182 -38.40063948
OS 41.30043302 -38.38214828
OS 41.3216979 -38.36365708
OS 41.34666102 -38.34793956
OS 41.34758558 -38.347015
OS 41.35035926 -38.34609044
OS 41.3540575 -38.34424132
OS 41.3586803 -38.34146764
OS 41.36607678 -38.33869396
OS 41.37347326 -38.33592028
OS 41.38271886 -38.33222204
OS 41.39288902 -38.3285238
OS 41.40398374 -38.32482556
OS 41.41600302 -38.32112732
OS 41.4418907 -38.31557996
OS 41.47147662 -38.31095716
OS 41.5019871 -38.30910804
OS 41.5112327 -38.30910804
OS 41.51770462 -38.3100326
OE
OB 42.90454462 -39.1375138 I
OS 42.38401734 -39.1375138
OS 42.38401734 -39.08111564
OS 42.90454462 -39.08111564
OS 42.90454462 -39.1375138
OE
OB 42.12514054 -38.32112732 I
OS 42.13253702 -38.32112732
OS 42.1491791 -38.32297644
OS 42.1676703 -38.32482556
OS 42.18708606 -38.3285238
OS 42.20650182 -38.3331466
OS 42.22406846 -38.33961852
OS 42.22499302 -38.33961852
OS 42.22591758 -38.34054308
OS 42.23146494 -38.34331676
OS 42.23978598 -38.34793956
OS 42.24903158 -38.35441148
OS 42.2601263 -38.36273252
OS 42.27214558 -38.37290268
OS 42.2832403 -38.38584652
OS 42.29341046 -38.39971492
OS 42.29433502 -38.40156404
OS 42.2971087 -38.4071114
OS 42.3017315 -38.41450788
OS 42.3063543 -38.4256026
OS 42.3109771 -38.43854644
OS 42.3155999 -38.45241484
OS 42.31837358 -38.46813236
OS 42.31929814 -38.48384988
OS 42.31929814 -38.485699
OS 42.31929814 -38.4903218
OS 42.31837358 -38.49864284
OS 42.31652446 -38.508813
OS 42.31375078 -38.52083228
OS 42.30912798 -38.53377612
OS 42.30358062 -38.54671996
OS 42.29618414 -38.56058836
OS 42.29525958 -38.56243748
OS 42.2924859 -38.56613572
OS 42.28693854 -38.5735322
OS 42.27954206 -38.58092868
OS 42.27029646 -38.59017428
OS 42.25920174 -38.60034444
OS 42.24533334 -38.60959004
OS 42.22961582 -38.61883564
OS 42.23054038 -38.61883564
OS 42.2323895 -38.6197602
OS 42.23516318 -38.62068476
OS 42.23886142 -38.62253388
OS 42.24995614 -38.62623212
OS 42.26289998 -38.63270404
OS 42.27676838 -38.64102508
OS 42.2924859 -38.65119524
OS 42.3063543 -38.66321452
OS 42.31929814 -38.67800748
OS 42.3202227 -38.6798566
OS 42.32392094 -38.68540396
OS 42.3294683 -38.693725
OS 42.33501566 -38.70481972
OS 42.34056302 -38.71961268
OS 42.34611038 -38.7353302
OS 42.34980862 -38.7538214
OS 42.35073318 -38.77416172
OS 42.35073318 -38.77508628
OS 42.35073318 -38.77601084
OS 42.35073318 -38.7815582
OS 42.34980862 -38.7908038
OS 42.3479595 -38.80189852
OS 42.34611038 -38.81484236
OS 42.34241214 -38.82871076
OS 42.33778934 -38.84350372
OS 42.33131742 -38.85829668
OS 42.33039286 -38.8601458
OS 42.32761918 -38.8647686
OS 42.32392094 -38.87124052
OS 42.31837358 -38.88048612
OS 42.3109771 -38.88973172
OS 42.30358062 -38.89990188
OS 42.29433502 -38.91007204
OS 42.28416486 -38.91839308
OS 42.2832403 -38.91931764
OS 42.27954206 -38.92209132
OS 42.27307014 -38.92578956
OS 42.2647491 -38.9294878
OS 42.25457894 -38.93503516
OS 42.24255966 -38.94058252
OS 42.22961582 -38.94520532
OS 42.2138983 -38.94982812
OS 42.21204918 -38.94982812
OS 42.20650182 -38.95167724
OS 42.19725622 -38.9526018
OS 42.18523694 -38.95445092
OS 42.17044398 -38.95630004
OS 42.15287734 -38.95814916
OS 42.13346158 -38.95907372
OS 42.11127214 -38.95999828
OS 41.8671883 -38.95999828
OS 41.8671883 -38.32020276
OS 42.11866862 -38.32020276
OS 42.12514054 -38.32112732
OE
OB 40.30745558 -38.48662356 I
OS 40.31762574 -38.48847268
OS 40.32964502 -38.49217092
OS 40.34258886 -38.49679372
OS 40.35738182 -38.50326564
OS 40.37309934 -38.51158668
OS 40.34443798 -38.58370236
OS 40.34351342 -38.5827778
OS 40.33981518 -38.58092868
OS 40.33426782 -38.578155
OS 40.32687134 -38.57538132
OS 40.3185503 -38.57260764
OS 40.30838014 -38.56983396
OS 40.29820998 -38.56798484
OS 40.28803982 -38.56706028
OS 40.28341702 -38.56706028
OS 40.27879422 -38.56798484
OS 40.2723223 -38.5689094
OS 40.26585038 -38.57075852
OS 40.25752934 -38.5735322
OS 40.2492083 -38.57723044
OS 40.24181182 -38.5827778
OS 40.24088726 -38.58370236
OS 40.23811358 -38.58555148
OS 40.2353399 -38.58924972
OS 40.2307171 -38.59387252
OS 40.2260943 -38.60034444
OS 40.2214715 -38.60774092
OS 40.2168487 -38.61606196
OS 40.21315046 -38.62623212
OS 40.2122259 -38.62808124
OS 40.21130134 -38.6336286
OS 40.20945222 -38.64194964
OS 40.20667854 -38.65304436
OS 40.20390486 -38.66691276
OS 40.20205574 -38.68263028
OS 40.20113118 -38.69927236
OS 40.20020662 -38.71776356
OS 40.20020662 -38.95999828
OS 40.12161902 -38.95999828
OS 40.12161902 -38.49586916
OS 40.19281014 -38.49586916
OS 40.19281014 -38.56613572
OS 40.1937347 -38.56521116
OS 40.19743294 -38.55873924
OS 40.20205574 -38.5504182
OS 40.20945222 -38.54024804
OS 40.2168487 -38.53007788
OS 40.22516974 -38.51898316
OS 40.23349078 -38.50973756
OS 40.24181182 -38.50234108
OS 40.24273638 -38.50141652
OS 40.24551006 -38.4995674
OS 40.25105742 -38.49679372
OS 40.25660478 -38.49402004
OS 40.26400126 -38.49124636
OS 40.27324686 -38.48847268
OS 40.28249246 -38.48662356
OS 40.29266262 -38.485699
OS 40.29913454 -38.485699
OS 40.30745558 -38.48662356
OE
OB 39.48829542 -38.95999828 I
OS 39.3986131 -38.95999828
OS 39.3986131 -38.87031596
OS 39.48829542 -38.87031596
OS 39.48829542 -38.95999828
OE
OB 38.6404739 -38.95999828 I
OS 38.55171614 -38.95999828
OS 38.30393406 -38.32020276
OS 38.39639006 -38.32020276
OS 38.56281086 -38.78525644
OS 38.56281086 -38.786181
OS 38.56373542 -38.78803012
OS 38.56465998 -38.7908038
OS 38.5665091 -38.79450204
OS 38.56743366 -38.8000494
OS 38.56928278 -38.80559676
OS 38.57390558 -38.81946516
OS 38.57945294 -38.83518268
OS 38.5850003 -38.85274932
OS 38.59609502 -38.88973172
OS 38.59609502 -38.88880716
OS 38.59701958 -38.88695804
OS 38.59794414 -38.88418436
OS 38.5988687 -38.88048612
OS 38.60164238 -38.87031596
OS 38.60626518 -38.85644756
OS 38.61088798 -38.84073004
OS 38.61643534 -38.8231634
OS 38.62290726 -38.8046722
OS 38.63030374 -38.78525644
OS 38.80412102 -38.32020276
OS 38.8901051 -38.32020276
OS 38.6404739 -38.95999828
OE
OB 39.27564662 -38.42745172 I
OS 39.25438174 -38.54671996
OS 39.20538006 -38.54671996
OS 39.1859643 -38.42745172
OS 39.1859643 -38.32020276
OS 39.27564662 -38.32020276
OS 39.27564662 -38.42745172
OE
OB 40.49791494 -38.4117342 I
OS 40.41932734 -38.4117342
OS 40.41932734 -38.32020276
OS 40.49791494 -38.32020276
OS 40.49791494 -38.4117342
OE
OB 39.84517558 -38.48662356 I
OS 39.8516475 -38.48754812
OS 39.8655159 -38.48939724
OS 39.88215798 -38.49309548
OS 39.89972462 -38.49864284
OS 39.91729126 -38.50696388
OS 39.9348579 -38.51713404
OS 39.93578246 -38.51713404
OS 39.93670702 -38.51898316
OS 39.94225438 -38.5226814
OS 39.95057542 -38.53007788
OS 39.96074558 -38.53932348
OS 39.9718403 -38.55134276
OS 39.98293502 -38.56613572
OS 39.99402974 -38.58370236
OS 40.00327534 -38.60311812
OS 40.00327534 -38.60404268
OS 40.0041999 -38.6058918
OS 40.00512446 -38.60866548
OS 40.00697358 -38.61236372
OS 40.0088227 -38.61791108
OS 40.01067182 -38.624383
OS 40.01529462 -38.63917596
OS 40.01991742 -38.65766716
OS 40.02361566 -38.67800748
OS 40.02638934 -38.70112148
OS 40.0273139 -38.72516004
OS 40.0273139 -38.7260846
OS 40.0273139 -38.72793372
OS 40.0273139 -38.73163196
OS 40.0273139 -38.73717932
OS 40.02638934 -38.74365124
OS 40.02638934 -38.75104772
OS 40.02454022 -38.7676898
OS 40.02084198 -38.78803012
OS 40.01621918 -38.809295
OS 40.00974726 -38.83148444
OS 40.00142622 -38.85367388
OS 40.00142622 -38.85459844
OS 40.00050166 -38.85644756
OS 39.99865254 -38.85922124
OS 39.99680342 -38.86291948
OS 39.9903315 -38.87308964
OS 39.98201046 -38.88603348
OS 39.9718403 -38.89990188
OS 39.95889646 -38.91377028
OS 39.9441035 -38.92763868
OS 39.92653686 -38.94058252
OS 39.9256123 -38.94058252
OS 39.92468774 -38.94150708
OS 39.92191406 -38.9433562
OS 39.91821582 -38.94520532
OS 39.90897022 -38.94982812
OS 39.89602638 -38.95537548
OS 39.88030886 -38.96092284
OS 39.86366678 -38.96554564
OS 39.84425102 -38.96924388
OS 39.82483526 -38.97016844
OS 39.81836334 -38.97016844
OS 39.81096686 -38.96924388
OS 39.80172126 -38.96831932
OS 39.79062654 -38.9664702
OS 39.77860726 -38.96369652
OS 39.76658798 -38.95999828
OS 39.7545687 -38.95445092
OS 39.75364414 -38.95352636
OS 39.74902134 -38.95167724
OS 39.74347398 -38.947979
OS 39.7360775 -38.94243164
OS 39.72868102 -38.93688428
OS 39.71943542 -38.9294878
OS 39.71111438 -38.92116676
OS 39.7037179 -38.91192116
OS 39.7037179 -39.1375138
OS 39.6251303 -39.1375138
OS 39.6251303 -38.49586916
OS 39.69632142 -38.49586916
OS 39.69632142 -38.55689012
OS 39.69724598 -38.555041
OS 39.70094422 -38.55134276
OS 39.70556702 -38.54487084
OS 39.7129635 -38.53747436
OS 39.72128454 -38.52822876
OS 39.73053014 -38.51990772
OS 39.74162486 -38.51158668
OS 39.75271958 -38.5041902
OS 39.7545687 -38.50326564
OS 39.75826694 -38.50141652
OS 39.76566342 -38.49864284
OS 39.77490902 -38.4949446
OS 39.78600374 -38.49124636
OS 39.79894758 -38.48847268
OS 39.81374054 -38.48662356
OS 39.83038262 -38.485699
OS 39.84055278 -38.485699
OS 39.84517558 -38.48662356
OE
OB 44.92193454 -38.40988508 I
OS 44.84334694 -38.40988508
OS 44.84334694 -38.32020276
OS 44.92193454 -38.32020276
OS 44.92193454 -38.40988508
OE
OB 45.24553054 -38.48662356 I
OS 45.25385158 -38.48754812
OS 45.26309718 -38.48939724
OS 45.27326734 -38.49124636
OS 45.28528662 -38.49309548
OS 45.31024974 -38.50141652
OS 45.32319358 -38.50603932
OS 45.33613742 -38.51251124
OS 45.34908126 -38.51898316
OS 45.3620251 -38.52822876
OS 45.37404438 -38.53747436
OS 45.38606366 -38.54856908
OS 45.38698822 -38.54949364
OS 45.38883734 -38.55134276
OS 45.39161102 -38.555041
OS 45.39530926 -38.5596638
OS 45.39993206 -38.56613572
OS 45.40547942 -38.57445676
OS 45.41102678 -38.58370236
OS 45.41657414 -38.59387252
OS 45.4221215 -38.60496724
OS 45.42766886 -38.61883564
OS 45.43321622 -38.63270404
OS 45.43783902 -38.64842156
OS 45.44153726 -38.66506364
OS 45.44431094 -38.68263028
OS 45.44616006 -38.70112148
OS 45.44708462 -38.7214618
OS 45.44708462 -38.72238636
OS 45.44708462 -38.72516004
OS 45.44708462 -38.72978284
OS 45.44708462 -38.73625476
OS 45.44616006 -38.74365124
OS 45.4452355 -38.75289684
OS 45.4452355 -38.76214244
OS 45.44338638 -38.7723126
OS 45.4406127 -38.7954266
OS 45.43506534 -38.8185406
OS 45.42859342 -38.8416546
OS 45.41934782 -38.86291948
OS 45.41934782 -38.86384404
OS 45.41842326 -38.8647686
OS 45.41657414 -38.86754228
OS 45.41472502 -38.87124052
OS 45.4082531 -38.88048612
OS 45.39993206 -38.89158084
OS 45.38883734 -38.90452468
OS 45.37496894 -38.91746852
OS 45.35925142 -38.93041236
OS 45.34076022 -38.94243164
OS 45.33983566 -38.94243164
OS 45.3389111 -38.9433562
OS 45.33613742 -38.94520532
OS 45.33151462 -38.94705444
OS 45.32689182 -38.94890356
OS 45.32134446 -38.95075268
OS 45.30747606 -38.95630004
OS 45.29175854 -38.96092284
OS 45.27234278 -38.96554564
OS 45.25200246 -38.96924388
OS 45.22981302 -38.97016844
OS 45.22056742 -38.97016844
OS 45.21317094 -38.96924388
OS 45.2048499 -38.96831932
OS 45.1956043 -38.9664702
OS 45.18450958 -38.96462108
OS 45.17341486 -38.96277196
OS 45.14845174 -38.95537548
OS 45.13458334 -38.94982812
OS 45.1216395 -38.94428076
OS 45.10869566 -38.93688428
OS 45.09575182 -38.92856324
OS 45.08373254 -38.91931764
OS 45.07171326 -38.90822292
OS 45.0707887 -38.90729836
OS 45.06893958 -38.90544924
OS 45.0661659 -38.901751
OS 45.06246766 -38.89620364
OS 45.05784486 -38.88973172
OS 45.05322206 -38.88233524
OS 45.0476747 -38.87308964
OS 45.04212734 -38.86199492
OS 45.03657998 -38.84997564
OS 45.03103262 -38.83610724
OS 45.02640982 -38.82131428
OS 45.02178702 -38.80559676
OS 45.01808878 -38.78803012
OS 45.0153151 -38.76953892
OS 45.01346598 -38.7491986
OS 45.01254142 -38.72793372
OS 45.01254142 -38.7260846
OS 45.01254142 -38.72238636
OS 45.01346598 -38.71591444
OS 45.01346598 -38.70666884
OS 45.01439054 -38.69649868
OS 45.01623966 -38.68355484
OS 45.01808878 -38.670611
OS 45.02178702 -38.65581804
OS 45.02548526 -38.64102508
OS 45.03010806 -38.62530756
OS 45.03565542 -38.60866548
OS 45.0430519 -38.59294796
OS 45.05044838 -38.578155
OS 45.06061854 -38.56336204
OS 45.0707887 -38.54949364
OS 45.08373254 -38.53747436
OS 45.0846571 -38.5365498
OS 45.08650622 -38.53562524
OS 45.09020446 -38.53285156
OS 45.09482726 -38.52915332
OS 45.10037462 -38.52545508
OS 45.1077711 -38.52083228
OS 45.11516758 -38.51620948
OS 45.12441318 -38.51158668
OS 45.13458334 -38.50696388
OS 45.14567806 -38.50234108
OS 45.17064118 -38.49402004
OS 45.19930254 -38.48754812
OS 45.2140955 -38.48662356
OS 45.22981302 -38.485699
OS 45.23905862 -38.485699
OS 45.24553054 -38.48662356
OE
OB 44.92193454 -38.95999828 I
OS 44.84334694 -38.95999828
OS 44.84334694 -38.49586916
OS 44.92193454 -38.49586916
OS 44.92193454 -38.95999828
OE
OB 46.10722046 -38.42745172 I
OS 46.08595558 -38.54671996
OS 46.0369539 -38.54671996
OS 46.01753814 -38.42745172
OS 46.01753814 -38.32020276
OS 46.10722046 -38.32020276
OS 46.10722046 -38.42745172
OE
OB 45.77160518 -38.48662356 I
OS 45.78177534 -38.48754812
OS 45.79379462 -38.48939724
OS 45.80673846 -38.49217092
OS 45.82060686 -38.49586916
OS 45.8335507 -38.50141652
OS 45.83539982 -38.50234108
OS 45.83909806 -38.5041902
OS 45.84556998 -38.50696388
OS 45.85296646 -38.51158668
OS 45.86221206 -38.51713404
OS 45.8705331 -38.52453052
OS 45.87885414 -38.531927
OS 45.88625062 -38.5411726
OS 45.88717518 -38.54209716
OS 45.8890243 -38.5457954
OS 45.89179798 -38.5504182
OS 45.89642078 -38.55689012
OS 45.90011902 -38.56613572
OS 45.90381726 -38.57538132
OS 45.90844006 -38.58647604
OS 45.91121374 -38.59849532
OS 45.91121374 -38.59941988
OS 45.9121383 -38.60311812
OS 45.91306286 -38.60866548
OS 45.91398742 -38.61606196
OS 45.91398742 -38.62715668
OS 45.91491198 -38.64010052
OS 45.91583654 -38.65581804
OS 45.91583654 -38.6752338
OS 45.91583654 -38.95999828
OS 45.83724894 -38.95999828
OS 45.83724894 -38.67893204
OS 45.83724894 -38.67800748
OS 45.83724894 -38.67708292
OS 45.83724894 -38.670611
OS 45.83724894 -38.66228996
OS 45.83632438 -38.6521198
OS 45.83539982 -38.64010052
OS 45.8335507 -38.62808124
OS 45.83077702 -38.61698652
OS 45.82800334 -38.60681636
OS 45.82800334 -38.6058918
OS 45.82615422 -38.60311812
OS 45.82338054 -38.59849532
OS 45.82060686 -38.59294796
OS 45.81598406 -38.5874006
OS 45.8104367 -38.58092868
OS 45.80304022 -38.57445676
OS 45.79471918 -38.5689094
OS 45.79379462 -38.56798484
OS 45.79102094 -38.56613572
OS 45.78547358 -38.5642866
OS 45.77900166 -38.56151292
OS 45.77160518 -38.55873924
OS 45.76235958 -38.55596556
OS 45.75126486 -38.555041
OS 45.74017014 -38.55411644
OS 45.73554734 -38.55411644
OS 45.7318491 -38.555041
OS 45.7226035 -38.55596556
OS 45.71058422 -38.55781468
OS 45.69764038 -38.56243748
OS 45.68284742 -38.56798484
OS 45.66805446 -38.57538132
OS 45.65418606 -38.58647604
OS 45.65233694 -38.58832516
OS 45.6486387 -38.59294796
OS 45.64586502 -38.5966462
OS 45.64309134 -38.601269
OS 45.6393931 -38.60681636
OS 45.63661942 -38.61328828
OS 45.63292118 -38.62068476
OS 45.62922294 -38.62993036
OS 45.62644926 -38.64010052
OS 45.62367558 -38.65119524
OS 45.62182646 -38.66321452
OS 45.61997734 -38.67615836
OS 45.61812822 -38.69187588
OS 45.61812822 -38.7075934
OS 45.61812822 -38.95999828
OS 45.53954062 -38.95999828
OS 45.53954062 -38.49586916
OS 45.60980718 -38.49586916
OS 45.60980718 -38.56243748
OS 45.61073174 -38.56151292
OS 45.61258086 -38.55873924
OS 45.61535454 -38.555041
OS 45.61905278 -38.5504182
OS 45.62460014 -38.54487084
OS 45.63107206 -38.53839892
OS 45.63846854 -38.53100244
OS 45.64771414 -38.52360596
OS 45.65695974 -38.51713404
OS 45.66805446 -38.50973756
OS 45.68007374 -38.50326564
OS 45.69301758 -38.49771828
OS 45.70781054 -38.49309548
OS 45.7226035 -38.48939724
OS 45.73924558 -38.48662356
OS 45.75681222 -38.485699
OS 45.7642087 -38.485699
OS 45.77160518 -38.48662356
OE
OB 44.2756671 -38.95999828 I
OS 44.1970795 -38.95999828
OS 44.1970795 -38.49586916
OS 44.2756671 -38.49586916
OS 44.2756671 -38.95999828
OE
OB 43.4574315 -38.48662356 I
OS 43.46482798 -38.48754812
OS 43.47407358 -38.48939724
OS 43.48424374 -38.49124636
OS 43.49626302 -38.49402004
OS 43.50735774 -38.49679372
OS 43.52030158 -38.50141652
OS 43.53232086 -38.50603932
OS 43.5452647 -38.51251124
OS 43.55820854 -38.51990772
OS 43.57115238 -38.52822876
OS 43.58317166 -38.53839892
OS 43.59426638 -38.54949364
OS 43.59519094 -38.5504182
OS 43.59704006 -38.55226732
OS 43.59981374 -38.55596556
OS 43.60351198 -38.56151292
OS 43.60813478 -38.56798484
OS 43.61275758 -38.57538132
OS 43.61830494 -38.58462692
OS 43.6238523 -38.59572164
OS 43.62939966 -38.60774092
OS 43.63494702 -38.62068476
OS 43.63956982 -38.63547772
OS 43.64419262 -38.65119524
OS 43.64789086 -38.66876188
OS 43.65066454 -38.68725308
OS 43.65251366 -38.70666884
OS 43.65343822 -38.72793372
OS 43.65343822 -38.72885828
OS 43.65343822 -38.73255652
OS 43.65343822 -38.73902844
OS 43.65251366 -38.74827404
OS 43.30580366 -38.74827404
OS 43.30580366 -38.7491986
OS 43.30580366 -38.75197228
OS 43.30672822 -38.75567052
OS 43.30672822 -38.76121788
OS 43.30765278 -38.7676898
OS 43.3095019 -38.77508628
OS 43.31227558 -38.79172836
OS 43.31782294 -38.81021956
OS 43.32521942 -38.83055988
OS 43.33538958 -38.84905108
OS 43.34833342 -38.86569316
OS 43.34925798 -38.86569316
OS 43.35018254 -38.86754228
OS 43.3557299 -38.87216508
OS 43.36405094 -38.878637
OS 43.37514566 -38.88510892
OS 43.38993862 -38.8925054
OS 43.4065807 -38.89897732
OS 43.4250719 -38.90360012
OS 43.43524206 -38.90452468
OS 43.44633678 -38.90544924
OS 43.45373326 -38.90544924
OS 43.4620543 -38.90452468
OS 43.47222446 -38.90267556
OS 43.48331918 -38.89990188
OS 43.49626302 -38.89620364
OS 43.5082823 -38.89065628
OS 43.52030158 -38.8832598
OS 43.52122614 -38.88233524
OS 43.52584894 -38.878637
OS 43.5313963 -38.87308964
OS 43.53786822 -38.86569316
OS 43.5452647 -38.855523
OS 43.55358574 -38.84257916
OS 43.56190678 -38.8277862
OS 43.56930326 -38.81021956
OS 43.65066454 -38.82038972
OS 43.65066454 -38.82131428
OS 43.64973998 -38.8231634
OS 43.64881542 -38.82686164
OS 43.6469663 -38.832409
OS 43.64419262 -38.83795636
OS 43.64141894 -38.84535284
OS 43.63402246 -38.86107036
OS 43.62477686 -38.878637
OS 43.61183302 -38.8971282
OS 43.59704006 -38.91469484
OS 43.57854886 -38.93133692
OS 43.5776243 -38.93133692
OS 43.57577518 -38.93318604
OS 43.5730015 -38.93503516
OS 43.56930326 -38.93780884
OS 43.5637559 -38.94058252
OS 43.55820854 -38.9433562
OS 43.55081206 -38.94705444
OS 43.54249102 -38.95075268
OS 43.53324542 -38.95445092
OS 43.52399982 -38.95814916
OS 43.50088582 -38.96369652
OS 43.47499814 -38.96831932
OS 43.44633678 -38.97016844
OS 43.43616662 -38.97016844
OS 43.4296947 -38.96924388
OS 43.42137366 -38.96831932
OS 43.4112035 -38.9664702
OS 43.40010878 -38.96462108
OS 43.3880895 -38.96277196
OS 43.36220182 -38.95537548
OS 43.34833342 -38.94982812
OS 43.33538958 -38.94428076
OS 43.32152118 -38.93688428
OS 43.30857734 -38.92856324
OS 43.29655806 -38.91931764
OS 43.28453878 -38.90822292
OS 43.28361422 -38.90729836
OS 43.2817651 -38.90544924
OS 43.27899142 -38.901751
OS 43.27529318 -38.89620364
OS 43.27067038 -38.88973172
OS 43.26604758 -38.88233524
OS 43.26050022 -38.87308964
OS 43.25495286 -38.86291948
OS 43.2494055 -38.8509002
OS 43.24385814 -38.83795636
OS 43.23923534 -38.8231634
OS 43.23461254 -38.80744588
OS 43.2309143 -38.7908038
OS 43.22814062 -38.7723126
OS 43.2262915 -38.75289684
OS 43.22536694 -38.73255652
OS 43.22536694 -38.73163196
OS 43.22536694 -38.72700916
OS 43.22536694 -38.7214618
OS 43.2262915 -38.71314076
OS 43.22721606 -38.7029706
OS 43.22814062 -38.69187588
OS 43.22998974 -38.67893204
OS 43.23276342 -38.6659882
OS 43.2401599 -38.63640228
OS 43.2447827 -38.62160932
OS 43.25033006 -38.6058918
OS 43.25772654 -38.59109884
OS 43.26604758 -38.57723044
OS 43.27529318 -38.56336204
OS 43.28546334 -38.5504182
OS 43.2863879 -38.54949364
OS 43.28823702 -38.54764452
OS 43.29193526 -38.54487084
OS 43.29655806 -38.54024804
OS 43.30210542 -38.53562524
OS 43.3095019 -38.53007788
OS 43.31782294 -38.52360596
OS 43.3279931 -38.5180586
OS 43.33816326 -38.51158668
OS 43.35018254 -38.50603932
OS 43.36312638 -38.50049196
OS 43.37699478 -38.49586916
OS 43.39178774 -38.49124636
OS 43.40750526 -38.48847268
OS 43.42414734 -38.48662356
OS 43.44171398 -38.485699
OS 43.45095958 -38.485699
OS 43.4574315 -38.48662356
OE
OB 43.13938286 -38.48662356 I
OS 43.14955302 -38.48847268
OS 43.1615723 -38.49217092
OS 43.17451614 -38.49679372
OS 43.1893091 -38.50326564
OS 43.20502662 -38.51158668
OS 43.17636526 -38.58370236
OS 43.1754407 -38.5827778
OS 43.17174246 -38.58092868
OS 43.1661951 -38.578155
OS 43.15879862 -38.57538132
OS 43.15047758 -38.57260764
OS 43.14030742 -38.56983396
OS 43.13013726 -38.56798484
OS 43.1199671 -38.56706028
OS 43.1153443 -38.56706028
OS 43.1107215 -38.56798484
OS 43.10424958 -38.5689094
OS 43.09777766 -38.57075852
OS 43.08945662 -38.5735322
OS 43.08113558 -38.57723044
OS 43.0737391 -38.5827778
OS 43.07281454 -38.58370236
OS 43.07004086 -38.58555148
OS 43.06726718 -38.58924972
OS 43.06264438 -38.59387252
OS 43.05802158 -38.60034444
OS 43.05339878 -38.60774092
OS 43.04877598 -38.61606196
OS 43.04507774 -38.62623212
OS 43.04415318 -38.62808124
OS 43.04322862 -38.6336286
OS 43.0413795 -38.64194964
OS 43.03860582 -38.65304436
OS 43.03583214 -38.66691276
OS 43.03398302 -38.68263028
OS 43.03305846 -38.69927236
OS 43.0321339 -38.71776356
OS 43.0321339 -38.95999828
OS 42.9535463 -38.95999828
OS 42.9535463 -38.49586916
OS 43.02473742 -38.49586916
OS 43.02473742 -38.56613572
OS 43.02566198 -38.56521116
OS 43.02936022 -38.55873924
OS 43.03398302 -38.5504182
OS 43.0413795 -38.54024804
OS 43.04877598 -38.53007788
OS 43.05709702 -38.51898316
OS 43.06541806 -38.50973756
OS 43.0737391 -38.50234108
OS 43.07466366 -38.50141652
OS 43.07743734 -38.4995674
OS 43.0829847 -38.49679372
OS 43.08853206 -38.49402004
OS 43.09592854 -38.49124636
OS 43.10517414 -38.48847268
OS 43.11441974 -38.48662356
OS 43.1245899 -38.485699
OS 43.13106182 -38.485699
OS 43.13938286 -38.48662356
OE
OB 43.95022198 -38.95999828 I
OS 43.87533262 -38.95999828
OS 43.70059078 -38.49586916
OS 43.78380118 -38.49586916
OS 43.88365366 -38.77416172
OS 43.88365366 -38.77508628
OS 43.88457822 -38.77601084
OS 43.88550278 -38.77878452
OS 43.88642734 -38.7815582
OS 43.88920102 -38.7908038
OS 43.89289926 -38.80282308
OS 43.89752206 -38.81669148
OS 43.90306942 -38.832409
OS 43.90769222 -38.84997564
OS 43.91323958 -38.86754228
OS 43.91416414 -38.86569316
OS 43.9150887 -38.86107036
OS 43.91786238 -38.85367388
OS 43.92063606 -38.84257916
OS 43.92525886 -38.83055988
OS 43.92988166 -38.81484236
OS 43.93635358 -38.79820028
OS 43.9428255 -38.77970908
OS 44.04545166 -38.49586916
OS 44.12681294 -38.49586916
OS 43.95022198 -38.95999828
OE
OB 44.2756671 -38.40988508 I
OS 44.1970795 -38.40988508
OS 44.1970795 -38.32020276
OS 44.2756671 -38.32020276
OS 44.2756671 -38.40988508
OE
OB 44.5669035 -38.48662356 I
OS 44.5807719 -38.48754812
OS 44.59556486 -38.48939724
OS 44.61128238 -38.49309548
OS 44.62792446 -38.49679372
OS 44.64364198 -38.50234108
OS 44.64456654 -38.50234108
OS 44.6454911 -38.50326564
OS 44.6501139 -38.50511476
OS 44.65751038 -38.508813
OS 44.66675598 -38.5134358
OS 44.67692614 -38.51990772
OS 44.6870963 -38.5273042
OS 44.6963419 -38.53562524
OS 44.70466294 -38.54487084
OS 44.7055875 -38.5457954
OS 44.70743662 -38.54949364
OS 44.71113486 -38.55596556
OS 44.71575766 -38.56336204
OS 44.72038046 -38.57445676
OS 44.72500326 -38.58647604
OS 44.7287015 -38.60034444
OS 44.73239974 -38.61606196
OS 44.65566126 -38.62623212
OS 44.65566126 -38.624383
OS 44.6547367 -38.62068476
OS 44.65288758 -38.61421284
OS 44.6501139 -38.6058918
OS 44.6454911 -38.59757076
OS 44.63994374 -38.58832516
OS 44.63347182 -38.57907956
OS 44.62422622 -38.57075852
OS 44.62330166 -38.56983396
OS 44.61960342 -38.56798484
OS 44.61405606 -38.5642866
OS 44.60573502 -38.56058836
OS 44.59648942 -38.55689012
OS 44.58447014 -38.55319188
OS 44.56967718 -38.55134276
OS 44.55395966 -38.5504182
OS 44.54471406 -38.5504182
OS 44.53546846 -38.55134276
OS 44.52344918 -38.55226732
OS 44.5114299 -38.555041
OS 44.49848606 -38.55781468
OS 44.48646678 -38.56243748
OS 44.47629662 -38.5689094
OS 44.47537206 -38.56983396
OS 44.47259838 -38.57168308
OS 44.46890014 -38.57538132
OS 44.4652019 -38.58092868
OS 44.4605791 -38.58647604
OS 44.45688086 -38.59387252
OS 44.45410718 -38.60219356
OS 44.45318262 -38.6105146
OS 44.45318262 -38.61143916
OS 44.45318262 -38.61328828
OS 44.45410718 -38.61606196
OS 44.45410718 -38.6197602
OS 44.45688086 -38.6290058
OS 44.46242822 -38.6382514
OS 44.46335278 -38.63917596
OS 44.46427734 -38.64010052
OS 44.46612646 -38.6428742
OS 44.4698247 -38.64564788
OS 44.47352294 -38.64842156
OS 44.4790703 -38.6521198
OS 44.48554222 -38.65489348
OS 44.4929387 -38.65859172
OS 44.49386326 -38.65859172
OS 44.49571238 -38.65951628
OS 44.49941062 -38.66044084
OS 44.50588254 -38.66321452
OS 44.51512814 -38.6659882
OS 44.52714742 -38.66876188
OS 44.5345439 -38.67153556
OS 44.54286494 -38.67338468
OS 44.55211054 -38.67615836
OS 44.5622807 -38.67893204
OS 44.56320526 -38.67893204
OS 44.56597894 -38.6798566
OS 44.57060174 -38.68078116
OS 44.5761491 -38.68263028
OS 44.58262102 -38.6844794
OS 44.59094206 -38.68632852
OS 44.6085087 -38.69187588
OS 44.62792446 -38.69742324
OS 44.64734022 -38.70389516
OS 44.66490686 -38.71036708
OS 44.67230334 -38.71314076
OS 44.67877526 -38.71591444
OS 44.68062438 -38.716839
OS 44.68432262 -38.71868812
OS 44.68986998 -38.7214618
OS 44.69819102 -38.7260846
OS 44.70651206 -38.73163196
OS 44.7148331 -38.73902844
OS 44.72315414 -38.74734948
OS 44.73055062 -38.75659508
OS 44.73147518 -38.75751964
OS 44.7333243 -38.76121788
OS 44.73702254 -38.76676524
OS 44.74072078 -38.77508628
OS 44.74349446 -38.78525644
OS 44.7471927 -38.79635116
OS 44.74904182 -38.809295
OS 44.74996638 -38.82408796
OS 44.74996638 -38.82593708
OS 44.74996638 -38.83055988
OS 44.74904182 -38.83795636
OS 44.7471927 -38.84812652
OS 44.74441902 -38.85922124
OS 44.73979622 -38.87124052
OS 44.73424886 -38.88510892
OS 44.72685238 -38.89805276
OS 44.72592782 -38.89990188
OS 44.72222958 -38.90360012
OS 44.71760678 -38.91007204
OS 44.7102103 -38.91746852
OS 44.70004014 -38.92578956
OS 44.68894542 -38.93503516
OS 44.67600158 -38.9433562
OS 44.66028406 -38.95167724
OS 44.6593595 -38.95167724
OS 44.65843494 -38.9526018
OS 44.65288758 -38.95445092
OS 44.64364198 -38.9572246
OS 44.6316227 -38.96092284
OS 44.61682974 -38.96462108
OS 44.60018766 -38.96739476
OS 44.58262102 -38.96924388
OS 44.5622807 -38.97016844
OS 44.55395966 -38.97016844
OS 44.54748774 -38.96924388
OS 44.54009126 -38.96924388
OS 44.53084566 -38.96831932
OS 44.52160006 -38.96739476
OS 44.5114299 -38.96554564
OS 44.48924046 -38.96092284
OS 44.46612646 -38.95445092
OS 44.44393702 -38.94520532
OS 44.43376686 -38.93965796
OS 44.42452126 -38.93318604
OS 44.4235967 -38.93226148
OS 44.42267214 -38.93133692
OS 44.41712478 -38.92578956
OS 44.40880374 -38.91746852
OS 44.39955814 -38.90452468
OS 44.38938798 -38.88880716
OS 44.37921782 -38.87031596
OS 44.37089678 -38.84720196
OS 44.36442486 -38.82131428
OS 44.4420879 -38.809295
OS 44.4420879 -38.81021956
OS 44.4420879 -38.81114412
OS 44.44393702 -38.81669148
OS 44.44578614 -38.82593708
OS 44.44948438 -38.83610724
OS 44.45410718 -38.84720196
OS 44.45965454 -38.85922124
OS 44.46797558 -38.87124052
OS 44.47814574 -38.88141068
OS 44.47999486 -38.88233524
OS 44.4836931 -38.88510892
OS 44.49108958 -38.88880716
OS 44.50033518 -38.89342996
OS 44.51235446 -38.89805276
OS 44.52622286 -38.901751
OS 44.54286494 -38.90452468
OS 44.5622807 -38.90544924
OS 44.5715263 -38.90544924
OS 44.5807719 -38.90452468
OS 44.59279118 -38.90267556
OS 44.60573502 -38.89990188
OS 44.61960342 -38.89620364
OS 44.6316227 -38.89158084
OS 44.64271742 -38.88418436
OS 44.64364198 -38.8832598
OS 44.64734022 -38.88048612
OS 44.65103846 -38.87586332
OS 44.65658582 -38.8693914
OS 44.66120862 -38.86199492
OS 44.66583142 -38.85274932
OS 44.6686051 -38.84350372
OS 44.66952966 -38.832409
OS 44.66952966 -38.83148444
OS 44.66952966 -38.8277862
OS 44.6686051 -38.8231634
OS 44.66675598 -38.81669148
OS 44.6639823 -38.81021956
OS 44.6593595 -38.80374764
OS 44.65381214 -38.79635116
OS 44.6454911 -38.7908038
OS 44.64456654 -38.78987924
OS 44.64179286 -38.78895468
OS 44.63717006 -38.786181
OS 44.62977358 -38.78340732
OS 44.61867886 -38.77970908
OS 44.61220694 -38.7769354
OS 44.60481046 -38.77508628
OS 44.59648942 -38.7723126
OS 44.58724382 -38.76953892
OS 44.57707366 -38.76676524
OS 44.56505438 -38.76399156
OS 44.56412982 -38.76399156
OS 44.56135614 -38.763067
OS 44.55673334 -38.76214244
OS 44.55118598 -38.76029332
OS 44.5437895 -38.7584442
OS 44.53546846 -38.75567052
OS 44.51790182 -38.75104772
OS 44.4975615 -38.7445758
OS 44.47814574 -38.73902844
OS 44.45965454 -38.73255652
OS 44.4513335 -38.72885828
OS 44.44486158 -38.7260846
OS 44.44301246 -38.72516004
OS 44.43931422 -38.72331092
OS 44.43376686 -38.71961268
OS 44.42637038 -38.71498988
OS 44.41804934 -38.70851796
OS 44.4097283 -38.70112148
OS 44.40140726 -38.69280044
OS 44.39401078 -38.68263028
OS 44.39308622 -38.68170572
OS 44.3912371 -38.67800748
OS 44.38846342 -38.67153556
OS 44.38568974 -38.66413908
OS 44.38291606 -38.65489348
OS 44.38014238 -38.64379876
OS 44.37829326 -38.63270404
OS 44.3773687 -38.6197602
OS 44.3773687 -38.61791108
OS 44.3773687 -38.61421284
OS 44.37829326 -38.60866548
OS 44.37921782 -38.60034444
OS 44.38106694 -38.5920234
OS 44.38291606 -38.58185324
OS 44.3866143 -38.57260764
OS 44.3912371 -38.56243748
OS 44.39216166 -38.56151292
OS 44.39401078 -38.55781468
OS 44.39678446 -38.55319188
OS 44.40140726 -38.54671996
OS 44.40695462 -38.54024804
OS 44.41342654 -38.531927
OS 44.42082302 -38.52453052
OS 44.43006862 -38.5180586
OS 44.43099318 -38.51713404
OS 44.43376686 -38.51620948
OS 44.4374651 -38.5134358
OS 44.44301246 -38.51066212
OS 44.45040894 -38.50696388
OS 44.45872998 -38.50326564
OS 44.46890014 -38.4995674
OS 44.47999486 -38.49586916
OS 44.48184398 -38.4949446
OS 44.48554222 -38.49402004
OS 44.49201414 -38.49217092
OS 44.50033518 -38.4903218
OS 44.51050534 -38.48847268
OS 44.52160006 -38.48754812
OS 44.5345439 -38.485699
OS 44.55673334 -38.485699
OS 44.5669035 -38.48662356
OE
OB 33.15968222 -38.32112732 I
OS 33.17539974 -38.32205188
OS 33.19204182 -38.32297644
OS 33.20775934 -38.32482556
OS 33.22162774 -38.32667468
OS 33.22347686 -38.32667468
OS 33.22994878 -38.3285238
OS 33.23826982 -38.33037292
OS 33.24936454 -38.3331466
OS 33.26138382 -38.3377694
OS 33.27432766 -38.34331676
OS 33.28819606 -38.34978868
OS 33.30021534 -38.35718516
OS 33.30206446 -38.35810972
OS 33.3057627 -38.3608834
OS 33.31131006 -38.36643076
OS 33.31870654 -38.37290268
OS 33.32702758 -38.38122372
OS 33.33534862 -38.39231844
OS 33.34459422 -38.40433772
OS 33.3519907 -38.41820612
OS 33.35291526 -38.42005524
OS 33.35476438 -38.42467804
OS 33.35846262 -38.43299908
OS 33.36216086 -38.4440938
OS 33.36493454 -38.45703764
OS 33.36863278 -38.4718306
OS 33.3704819 -38.48847268
OS 33.37140646 -38.50603932
OS 33.37140646 -38.50696388
OS 33.37140646 -38.50973756
OS 33.37140646 -38.5134358
OS 33.3704819 -38.51990772
OS 33.36955734 -38.52637964
OS 33.36863278 -38.53470068
OS 33.36678366 -38.54394628
OS 33.36493454 -38.55411644
OS 33.35846262 -38.57538132
OS 33.35476438 -38.58647604
OS 33.34921702 -38.59849532
OS 33.3427451 -38.6105146
OS 33.33627318 -38.62160932
OS 33.32795214 -38.63270404
OS 33.31870654 -38.64379876
OS 33.31778198 -38.64472332
OS 33.31593286 -38.64657244
OS 33.31315918 -38.64934612
OS 33.30853638 -38.6521198
OS 33.30298902 -38.6567426
OS 33.29559254 -38.6613654
OS 33.28634694 -38.66691276
OS 33.27617678 -38.67153556
OS 33.2641575 -38.67708292
OS 33.2502891 -38.68263028
OS 33.23549614 -38.68725308
OS 33.2179295 -38.69095132
OS 33.1994383 -38.69464956
OS 33.17909798 -38.69742324
OS 33.15598398 -38.69927236
OS 33.13194542 -38.70019692
OS 32.9682983 -38.70019692
OS 32.9682983 -38.95999828
OS 32.88323878 -38.95999828
OS 32.88323878 -38.32020276
OS 33.14581382 -38.32020276
OS 33.15968222 -38.32112732
OE
OB 32.75195126 -38.98403684 I
OS 32.75195126 -38.9849614
OS 32.75195126 -38.98773508
OS 32.75195126 -38.99235788
OS 32.75195126 -38.99790524
OS 32.7510267 -39.00530172
OS 32.7510267 -39.0126982
OS 32.74917758 -39.0311894
OS 32.7464039 -39.05060516
OS 32.74270566 -39.07094548
OS 32.7371583 -39.08851212
OS 32.73346006 -39.09683316
OS 32.72976182 -39.10330508
OS 32.72976182 -39.10422964
OS 32.72883726 -39.1051542
OS 32.72421446 -39.109777
OS 32.71681798 -39.11717348
OS 32.70757238 -39.12549452
OS 32.69462854 -39.13381556
OS 32.67798646 -39.14028748
OS 32.6585707 -39.14583484
OS 32.64747598 -39.1467594
OS 32.6354567 -39.14768396
OS 32.62990934 -39.14768396
OS 32.62436198 -39.1467594
OS 32.61604094 -39.1467594
OS 32.60679534 -39.14583484
OS 32.59662518 -39.14398572
OS 32.57443574 -39.13843836
OS 32.5892287 -39.07187004
OS 32.59015326 -39.07187004
OS 32.59292694 -39.0727946
OS 32.59754974 -39.07371916
OS 32.60217254 -39.07464372
OS 32.61419182 -39.0774174
OS 32.61973918 -39.07834196
OS 32.62898478 -39.07834196
OS 32.63360758 -39.0774174
OS 32.63915494 -39.07649284
OS 32.6447023 -39.07464372
OS 32.65024966 -39.07094548
OS 32.65672158 -39.06724724
OS 32.66134438 -39.06169988
OS 32.66226894 -39.06077532
OS 32.6631935 -39.05800164
OS 32.66504262 -39.05337884
OS 32.6678163 -39.04598236
OS 32.66966542 -39.0358122
OS 32.67058998 -39.02841572
OS 32.67151454 -39.0219438
OS 32.6724391 -39.01362276
OS 32.6724391 -39.0034526
OS 32.67336366 -38.99328244
OS 32.67336366 -38.98218772
OS 32.67336366 -38.49586916
OS 32.75195126 -38.49586916
OS 32.75195126 -38.98403684
OE
OB 33.77174094 -38.3100326 I
OS 33.78006198 -38.31095716
OS 33.79023214 -38.31188172
OS 33.8004023 -38.31280628
OS 33.81242158 -38.31557996
OS 33.8373847 -38.32112732
OS 33.8651215 -38.32944836
OS 33.8789899 -38.33499572
OS 33.89193374 -38.34146764
OS 33.90487758 -38.34978868
OS 33.91782142 -38.35810972
OS 33.91874598 -38.35903428
OS 33.9205951 -38.35995884
OS 33.92429334 -38.36273252
OS 33.92891614 -38.36735532
OS 33.93353894 -38.37197812
OS 33.94001086 -38.37845004
OS 33.94648278 -38.38584652
OS 33.95387926 -38.393243
OS 33.96127574 -38.4024886
OS 33.96867222 -38.41358332
OS 33.97699326 -38.42467804
OS 33.98438974 -38.43669732
OS 33.99086166 -38.45056572
OS 33.99825814 -38.46443412
OS 34.0038055 -38.47922708
OS 34.00935286 -38.49586916
OS 33.92614246 -38.51528492
OS 33.92614246 -38.51436036
OS 33.9252179 -38.51251124
OS 33.92336878 -38.508813
OS 33.92151966 -38.5041902
OS 33.91967054 -38.49864284
OS 33.91689686 -38.49124636
OS 33.90950038 -38.4764534
OS 33.90025478 -38.45981132
OS 33.88916006 -38.44316924
OS 33.87529166 -38.42745172
OS 33.8604987 -38.41358332
OS 33.85864958 -38.4117342
OS 33.85310222 -38.40803596
OS 33.84385662 -38.40341316
OS 33.83183734 -38.39694124
OS 33.81611982 -38.39139388
OS 33.79855318 -38.38584652
OS 33.7772883 -38.38214828
OS 33.7541743 -38.38122372
OS 33.74677782 -38.38122372
OS 33.74215502 -38.38214828
OS 33.7356831 -38.38214828
OS 33.72828662 -38.38307284
OS 33.71071998 -38.38584652
OS 33.69130422 -38.38954476
OS 33.6709639 -38.39601668
OS 33.64969902 -38.40526228
OS 33.63028326 -38.41728156
OS 33.6293587 -38.41728156
OS 33.62843414 -38.41913068
OS 33.62196222 -38.42375348
OS 33.61364118 -38.43114996
OS 33.60347102 -38.44224468
OS 33.59145174 -38.45611308
OS 33.58035702 -38.4718306
OS 33.57018686 -38.49124636
OS 33.56094126 -38.51251124
OS 33.56094126 -38.5134358
OS 33.5600167 -38.51528492
OS 33.55909214 -38.5180586
OS 33.55816758 -38.5226814
OS 33.55631846 -38.52822876
OS 33.55446934 -38.53470068
OS 33.55169566 -38.5504182
OS 33.54799742 -38.5689094
OS 33.54429918 -38.58924972
OS 33.54245006 -38.61143916
OS 33.5415255 -38.63547772
OS 33.5415255 -38.63640228
OS 33.5415255 -38.63917596
OS 33.5415255 -38.64379876
OS 33.5415255 -38.64934612
OS 33.54245006 -38.65581804
OS 33.54245006 -38.66413908
OS 33.54337462 -38.67338468
OS 33.54429918 -38.68355484
OS 33.54707286 -38.70574428
OS 33.55169566 -38.72978284
OS 33.55724302 -38.7538214
OS 33.5646395 -38.77785996
OS 33.5646395 -38.77878452
OS 33.56556406 -38.78063364
OS 33.56741318 -38.78340732
OS 33.5692623 -38.78803012
OS 33.57480966 -38.79912484
OS 33.5831307 -38.81206868
OS 33.59330086 -38.82686164
OS 33.6062447 -38.84257916
OS 33.62103766 -38.85644756
OS 33.6386043 -38.8693914
OS 33.63952886 -38.8693914
OS 33.64137798 -38.87031596
OS 33.64415166 -38.87216508
OS 33.6478499 -38.8740142
OS 33.6524727 -38.87586332
OS 33.65802006 -38.878637
OS 33.6709639 -38.88418436
OS 33.68760598 -38.88973172
OS 33.70609718 -38.89435452
OS 33.7264375 -38.89805276
OS 33.74770238 -38.89897732
OS 33.7541743 -38.89897732
OS 33.75972166 -38.89805276
OS 33.76619358 -38.89805276
OS 33.7726655 -38.8971282
OS 33.78930758 -38.89342996
OS 33.80872334 -38.88880716
OS 33.8281391 -38.88141068
OS 33.84847942 -38.87124052
OS 33.85864958 -38.86569316
OS 33.86789518 -38.85829668
OS 33.86881974 -38.85737212
OS 33.8697443 -38.85644756
OS 33.87251798 -38.85367388
OS 33.87621622 -38.8509002
OS 33.87991446 -38.8462774
OS 33.88453726 -38.84073004
OS 33.89008462 -38.83518268
OS 33.89470742 -38.8277862
OS 33.90025478 -38.81946516
OS 33.9067267 -38.81021956
OS 33.91227406 -38.80097396
OS 33.91782142 -38.78987924
OS 33.92244422 -38.77785996
OS 33.92706702 -38.76491612
OS 33.93168982 -38.75104772
OS 33.93538806 -38.73625476
OS 34.02044758 -38.75751964
OS 34.02044758 -38.7584442
OS 34.01952302 -38.76214244
OS 34.0176739 -38.7676898
OS 34.01490022 -38.77508628
OS 34.01212654 -38.78340732
OS 34.0084283 -38.79357748
OS 34.0038055 -38.8046722
OS 33.99825814 -38.81669148
OS 33.9853143 -38.84257916
OS 33.96867222 -38.86846684
OS 33.95850206 -38.88141068
OS 33.9483319 -38.89435452
OS 33.93723718 -38.90544924
OS 33.92429334 -38.91654396
OS 33.92336878 -38.91746852
OS 33.92151966 -38.91931764
OS 33.91689686 -38.92116676
OS 33.91227406 -38.924865
OS 33.90487758 -38.9294878
OS 33.8974811 -38.9341106
OS 33.88731094 -38.9387334
OS 33.87714078 -38.9433562
OS 33.8651215 -38.94890356
OS 33.85217766 -38.95352636
OS 33.83830926 -38.95814916
OS 33.8235163 -38.96277196
OS 33.80779878 -38.9664702
OS 33.7911567 -38.96831932
OS 33.77359006 -38.97016844
OS 33.75509886 -38.971093
OS 33.7449287 -38.971093
OS 33.73753222 -38.97016844
OS 33.72921118 -38.97016844
OS 33.71904102 -38.96924388
OS 33.7079463 -38.96739476
OS 33.69500246 -38.96554564
OS 33.66819022 -38.96092284
OS 33.64045342 -38.95352636
OS 33.61271662 -38.9433562
OS 33.59977278 -38.93688428
OS 33.58682894 -38.9294878
OS 33.58590438 -38.92856324
OS 33.58405526 -38.92763868
OS 33.58035702 -38.924865
OS 33.57665878 -38.92116676
OS 33.57111142 -38.91746852
OS 33.5646395 -38.91192116
OS 33.55724302 -38.90544924
OS 33.54984654 -38.89805276
OS 33.54245006 -38.88973172
OS 33.53412902 -38.88141068
OS 33.51748694 -38.8601458
OS 33.50176942 -38.83518268
OS 33.48790102 -38.80744588
OS 33.48790102 -38.80652132
OS 33.4860519 -38.80374764
OS 33.48512734 -38.79912484
OS 33.48235366 -38.79357748
OS 33.48050454 -38.786181
OS 33.47773086 -38.7769354
OS 33.47403262 -38.76676524
OS 33.47125894 -38.75567052
OS 33.46848526 -38.74365124
OS 33.46478702 -38.72978284
OS 33.46016422 -38.70112148
OS 33.45646598 -38.66876188
OS 33.45461686 -38.63547772
OS 33.45461686 -38.63455316
OS 33.45461686 -38.63085492
OS 33.45461686 -38.62530756
OS 33.45554142 -38.61883564
OS 33.45554142 -38.60959004
OS 33.45646598 -38.60034444
OS 33.45739054 -38.58832516
OS 33.45923966 -38.57630588
OS 33.46386246 -38.54949364
OS 33.47033438 -38.51990772
OS 33.47957998 -38.4903218
OS 33.49252382 -38.46166044
OS 33.49344838 -38.46073588
OS 33.49437294 -38.4579622
OS 33.49622206 -38.45426396
OS 33.4999203 -38.44964116
OS 33.50361854 -38.44316924
OS 33.50824134 -38.43577276
OS 33.52026062 -38.41913068
OS 33.53597814 -38.40063948
OS 33.55446934 -38.38214828
OS 33.57573422 -38.36365708
OS 33.60069734 -38.34793956
OS 33.6016219 -38.347015
OS 33.60439558 -38.34609044
OS 33.60809382 -38.34424132
OS 33.61271662 -38.34146764
OS 33.6201131 -38.33869396
OS 33.62750958 -38.33592028
OS 33.63675518 -38.33222204
OS 33.64692534 -38.3285238
OS 33.65802006 -38.32482556
OS 33.67003934 -38.32112732
OS 33.69592702 -38.31557996
OS 33.72551294 -38.31095716
OS 33.75602342 -38.30910804
OS 33.76526902 -38.30910804
OS 33.77174094 -38.3100326
OE
OB 35.15858094 -39.1375138 I
OS 34.63805366 -39.1375138
OS 34.63805366 -39.08111564
OS 35.15858094 -39.08111564
OS 35.15858094 -39.1375138
OE
OB 34.37917686 -38.32112732 I
OS 34.38657334 -38.32112732
OS 34.40321542 -38.32297644
OS 34.42170662 -38.32482556
OS 34.44112238 -38.3285238
OS 34.46053814 -38.3331466
OS 34.47810478 -38.33961852
OS 34.47902934 -38.33961852
OS 34.4799539 -38.34054308
OS 34.48550126 -38.34331676
OS 34.4938223 -38.34793956
OS 34.5030679 -38.35441148
OS 34.51416262 -38.36273252
OS 34.5261819 -38.37290268
OS 34.53727662 -38.38584652
OS 34.54744678 -38.39971492
OS 34.54837134 -38.40156404
OS 34.55114502 -38.4071114
OS 34.55576782 -38.41450788
OS 34.56039062 -38.4256026
OS 34.56501342 -38.43854644
OS 34.56963622 -38.45241484
OS 34.5724099 -38.46813236
OS 34.57333446 -38.48384988
OS 34.57333446 -38.485699
OS 34.57333446 -38.4903218
OS 34.5724099 -38.49864284
OS 34.57056078 -38.508813
OS 34.5677871 -38.52083228
OS 34.5631643 -38.53377612
OS 34.55761694 -38.54671996
OS 34.55022046 -38.56058836
OS 34.5492959 -38.56243748
OS 34.54652222 -38.56613572
OS 34.54097486 -38.5735322
OS 34.53357838 -38.58092868
OS 34.52433278 -38.59017428
OS 34.51323806 -38.60034444
OS 34.49936966 -38.60959004
OS 34.48365214 -38.61883564
OS 34.4845767 -38.61883564
OS 34.48642582 -38.6197602
OS 34.4891995 -38.62068476
OS 34.49289774 -38.62253388
OS 34.50399246 -38.62623212
OS 34.5169363 -38.63270404
OS 34.5308047 -38.64102508
OS 34.54652222 -38.65119524
OS 34.56039062 -38.66321452
OS 34.57333446 -38.67800748
OS 34.57425902 -38.6798566
OS 34.57795726 -38.68540396
OS 34.58350462 -38.693725
OS 34.58905198 -38.70481972
OS 34.59459934 -38.71961268
OS 34.6001467 -38.7353302
OS 34.60384494 -38.7538214
OS 34.6047695 -38.77416172
OS 34.6047695 -38.77508628
OS 34.6047695 -38.77601084
OS 34.6047695 -38.7815582
OS 34.60384494 -38.7908038
OS 34.60199582 -38.80189852
OS 34.6001467 -38.81484236
OS 34.59644846 -38.82871076
OS 34.59182566 -38.84350372
OS 34.58535374 -38.85829668
OS 34.58442918 -38.8601458
OS 34.5816555 -38.8647686
OS 34.57795726 -38.87124052
OS 34.5724099 -38.88048612
OS 34.56501342 -38.88973172
OS 34.55761694 -38.89990188
OS 34.54837134 -38.91007204
OS 34.53820118 -38.91839308
OS 34.53727662 -38.91931764
OS 34.53357838 -38.92209132
OS 34.52710646 -38.92578956
OS 34.51878542 -38.9294878
OS 34.50861526 -38.93503516
OS 34.49659598 -38.94058252
OS 34.48365214 -38.94520532
OS 34.46793462 -38.94982812
OS 34.4660855 -38.94982812
OS 34.46053814 -38.95167724
OS 34.45129254 -38.9526018
OS 34.43927326 -38.95445092
OS 34.4244803 -38.95630004
OS 34.40691366 -38.95814916
OS 34.3874979 -38.95907372
OS 34.36530846 -38.95999828
OS 34.12122462 -38.95999828
OS 34.12122462 -38.32020276
OS 34.37270494 -38.32020276
OS 34.37917686 -38.32112732
OE
OB 31.74233174 -38.95999828 I
OS 31.65264942 -38.95999828
OS 31.65264942 -38.87031596
OS 31.74233174 -38.87031596
OS 31.74233174 -38.95999828
OE
OB 31.52968294 -38.42745172 I
OS 31.50841806 -38.54671996
OS 31.45941638 -38.54671996
OS 31.44000062 -38.42745172
OS 31.44000062 -38.32020276
OS 31.52968294 -38.32020276
OS 31.52968294 -38.42745172
OE
OB 32.0992119 -38.48662356 I
OS 32.10568382 -38.48754812
OS 32.11955222 -38.48939724
OS 32.1361943 -38.49309548
OS 32.15376094 -38.49864284
OS 32.17132758 -38.50696388
OS 32.18889422 -38.51713404
OS 32.18981878 -38.51713404
OS 32.19074334 -38.51898316
OS 32.1962907 -38.5226814
OS 32.20461174 -38.53007788
OS 32.2147819 -38.53932348
OS 32.22587662 -38.55134276
OS 32.23697134 -38.56613572
OS 32.24806606 -38.58370236
OS 32.25731166 -38.60311812
OS 32.25731166 -38.60404268
OS 32.25823622 -38.6058918
OS 32.25916078 -38.60866548
OS 32.2610099 -38.61236372
OS 32.26285902 -38.61791108
OS 32.26470814 -38.624383
OS 32.26933094 -38.63917596
OS 32.27395374 -38.65766716
OS 32.27765198 -38.67800748
OS 32.28042566 -38.70112148
OS 32.28135022 -38.72516004
OS 32.28135022 -38.7260846
OS 32.28135022 -38.72793372
OS 32.28135022 -38.73163196
OS 32.28135022 -38.73717932
OS 32.28042566 -38.74365124
OS 32.28042566 -38.75104772
OS 32.27857654 -38.7676898
OS 32.2748783 -38.78803012
OS 32.2702555 -38.809295
OS 32.26378358 -38.83148444
OS 32.25546254 -38.85367388
OS 32.25546254 -38.85459844
OS 32.25453798 -38.85644756
OS 32.25268886 -38.85922124
OS 32.25083974 -38.86291948
OS 32.24436782 -38.87308964
OS 32.23604678 -38.88603348
OS 32.22587662 -38.89990188
OS 32.21293278 -38.91377028
OS 32.19813982 -38.92763868
OS 32.18057318 -38.94058252
OS 32.17964862 -38.94058252
OS 32.17872406 -38.94150708
OS 32.17595038 -38.9433562
OS 32.17225214 -38.94520532
OS 32.16300654 -38.94982812
OS 32.1500627 -38.95537548
OS 32.13434518 -38.96092284
OS 32.1177031 -38.96554564
OS 32.09828734 -38.96924388
OS 32.07887158 -38.97016844
OS 32.07239966 -38.97016844
OS 32.06500318 -38.96924388
OS 32.05575758 -38.96831932
OS 32.04466286 -38.9664702
OS 32.03264358 -38.96369652
OS 32.0206243 -38.95999828
OS 32.00860502 -38.95445092
OS 32.00768046 -38.95352636
OS 32.00305766 -38.95167724
OS 31.9975103 -38.947979
OS 31.99011382 -38.94243164
OS 31.98271734 -38.93688428
OS 31.97347174 -38.9294878
OS 31.9651507 -38.92116676
OS 31.95775422 -38.91192116
OS 31.95775422 -39.1375138
OS 31.87916662 -39.1375138
OS 31.87916662 -38.49586916
OS 31.95035774 -38.49586916
OS 31.95035774 -38.55689012
OS 31.9512823 -38.555041
OS 31.95498054 -38.55134276
OS 31.95960334 -38.54487084
OS 31.96699982 -38.53747436
OS 31.97532086 -38.52822876
OS 31.98456646 -38.51990772
OS 31.99566118 -38.51158668
OS 32.0067559 -38.5041902
OS 32.00860502 -38.50326564
OS 32.01230326 -38.50141652
OS 32.01969974 -38.49864284
OS 32.02894534 -38.4949446
OS 32.04004006 -38.49124636
OS 32.0529839 -38.48847268
OS 32.06777686 -38.48662356
OS 32.08441894 -38.485699
OS 32.0945891 -38.485699
OS 32.0992119 -38.48662356
OE
OB 32.5614919 -38.48662356 I
OS 32.57166206 -38.48847268
OS 32.58368134 -38.49217092
OS 32.59662518 -38.49679372
OS 32.61141814 -38.50326564
OS 32.62713566 -38.51158668
OS 32.5984743 -38.58370236
OS 32.59754974 -38.5827778
OS 32.5938515 -38.58092868
OS 32.58830414 -38.578155
OS 32.58090766 -38.57538132
OS 32.57258662 -38.57260764
OS 32.56241646 -38.56983396
OS 32.5522463 -38.56798484
OS 32.54207614 -38.56706028
OS 32.53745334 -38.56706028
OS 32.53283054 -38.56798484
OS 32.52635862 -38.5689094
OS 32.5198867 -38.57075852
OS 32.51156566 -38.5735322
OS 32.50324462 -38.57723044
OS 32.49584814 -38.5827778
OS 32.49492358 -38.58370236
OS 32.4921499 -38.58555148
OS 32.48937622 -38.58924972
OS 32.48475342 -38.59387252
OS 32.48013062 -38.60034444
OS 32.47550782 -38.60774092
OS 32.47088502 -38.61606196
OS 32.46718678 -38.62623212
OS 32.46626222 -38.62808124
OS 32.46533766 -38.6336286
OS 32.46348854 -38.64194964
OS 32.46071486 -38.65304436
OS 32.45794118 -38.66691276
OS 32.45609206 -38.68263028
OS 32.4551675 -38.69927236
OS 32.45424294 -38.71776356
OS 32.45424294 -38.95999828
OS 32.37565534 -38.95999828
OS 32.37565534 -38.49586916
OS 32.44684646 -38.49586916
OS 32.44684646 -38.56613572
OS 32.44777102 -38.56521116
OS 32.45146926 -38.55873924
OS 32.45609206 -38.5504182
OS 32.46348854 -38.54024804
OS 32.47088502 -38.53007788
OS 32.47920606 -38.51898316
OS 32.4875271 -38.50973756
OS 32.49584814 -38.50234108
OS 32.4967727 -38.50141652
OS 32.49954638 -38.4995674
OS 32.50509374 -38.49679372
OS 32.5106411 -38.49402004
OS 32.51803758 -38.49124636
OS 32.52728318 -38.48847268
OS 32.53652878 -38.48662356
OS 32.54669894 -38.485699
OS 32.55317086 -38.485699
OS 32.5614919 -38.48662356
OE
OB 32.75195126 -38.4117342 I
OS 32.67336366 -38.4117342
OS 32.67336366 -38.32020276
OS 32.75195126 -38.32020276
OS 32.75195126 -38.4117342
OE
OB 36.56668582 -38.95999828 I
OS 36.47885262 -38.95999828
OS 36.1441619 -38.4579622
OS 36.1441619 -38.95999828
OS 36.06280062 -38.95999828
OS 36.06280062 -38.32020276
OS 36.14970926 -38.32020276
OS 36.48532454 -38.8231634
OS 36.48532454 -38.32020276
OS 36.56668582 -38.32020276
OS 36.56668582 -38.95999828
OE
OB 35.74382742 -38.32112732 I
OS 35.75954494 -38.32205188
OS 35.77618702 -38.32297644
OS 35.79190454 -38.32482556
OS 35.80577294 -38.32667468
OS 35.80762206 -38.32667468
OS 35.81409398 -38.3285238
OS 35.82241502 -38.33037292
OS 35.83350974 -38.3331466
OS 35.84552902 -38.3377694
OS 35.85847286 -38.34331676
OS 35.87234126 -38.34978868
OS 35.88436054 -38.35718516
OS 35.88620966 -38.35810972
OS 35.8899079 -38.3608834
OS 35.89545526 -38.36643076
OS 35.90285174 -38.37290268
OS 35.91117278 -38.38122372
OS 35.91949382 -38.39231844
OS 35.92873942 -38.40433772
OS 35.9361359 -38.41820612
OS 35.93706046 -38.42005524
OS 35.93890958 -38.42467804
OS 35.94260782 -38.43299908
OS 35.94630606 -38.4440938
OS 35.94907974 -38.45703764
OS 35.95277798 -38.4718306
OS 35.9546271 -38.48847268
OS 35.95555166 -38.50603932
OS 35.95555166 -38.50696388
OS 35.95555166 -38.50973756
OS 35.95555166 -38.5134358
OS 35.9546271 -38.51990772
OS 35.95370254 -38.52637964
OS 35.95277798 -38.53470068
OS 35.95092886 -38.54394628
OS 35.94907974 -38.55411644
OS 35.94260782 -38.57538132
OS 35.93890958 -38.58647604
OS 35.93336222 -38.59849532
OS 35.9268903 -38.6105146
OS 35.92041838 -38.62160932
OS 35.91209734 -38.63270404
OS 35.90285174 -38.64379876
OS 35.90192718 -38.64472332
OS 35.90007806 -38.64657244
OS 35.89730438 -38.64934612
OS 35.89268158 -38.6521198
OS 35.88713422 -38.6567426
OS 35.87973774 -38.6613654
OS 35.87049214 -38.66691276
OS 35.86032198 -38.67153556
OS 35.8483027 -38.67708292
OS 35.8344343 -38.68263028
OS 35.81964134 -38.68725308
OS 35.8020747 -38.69095132
OS 35.7835835 -38.69464956
OS 35.76324318 -38.69742324
OS 35.74012918 -38.69927236
OS 35.71609062 -38.70019692
OS 35.5524435 -38.70019692
OS 35.5524435 -38.95999828
OS 35.46738398 -38.95999828
OS 35.46738398 -38.32020276
OS 35.72995902 -38.32020276
OS 35.74382742 -38.32112732
OE
OB 36.76916446 -38.42745172 I
OS 36.74789958 -38.54671996
OS 36.6988979 -38.54671996
OS 36.67948214 -38.42745172
OS 36.67948214 -38.32020276
OS 36.76916446 -38.32020276
OS 36.76916446 -38.42745172
OE
OB 38.2382903 -38.39601668 I
OS 37.86014526 -38.39601668
OS 37.86014526 -38.59109884
OS 38.21425174 -38.59109884
OS 38.21425174 -38.66691276
OS 37.86014526 -38.66691276
OS 37.86014526 -38.88418436
OS 38.25308326 -38.88418436
OS 38.25308326 -38.95999828
OS 37.77508574 -38.95999828
OS 37.77508574 -38.32020276
OS 38.2382903 -38.32020276
OS 38.2382903 -38.39601668
OE
OB 37.4339231 -38.32112732 I
OS 37.44224414 -38.32112732
OS 37.4616599 -38.32205188
OS 37.48200022 -38.32482556
OS 37.50418966 -38.32759924
OS 37.52452998 -38.33222204
OS 37.53470014 -38.33499572
OS 37.54302118 -38.3377694
OS 37.54394574 -38.3377694
OS 37.5448703 -38.33869396
OS 37.55041766 -38.34146764
OS 37.5587387 -38.34516588
OS 37.56890886 -38.3516378
OS 37.58000358 -38.35995884
OS 37.59202286 -38.37105356
OS 37.60311758 -38.3839974
OS 37.6142123 -38.39879036
OS 37.6142123 -38.39971492
OS 37.61513686 -38.40063948
OS 37.6188351 -38.40618684
OS 37.62253334 -38.41543244
OS 37.6280807 -38.42745172
OS 37.6327035 -38.44132012
OS 37.6373263 -38.4579622
OS 37.64009998 -38.47552884
OS 37.64102454 -38.4949446
OS 37.64102454 -38.49586916
OS 37.64102454 -38.49771828
OS 37.64102454 -38.50141652
OS 37.64009998 -38.50603932
OS 37.64009998 -38.51251124
OS 37.63917542 -38.51898316
OS 37.63547718 -38.53470068
OS 37.62992982 -38.55319188
OS 37.62253334 -38.57260764
OS 37.61143862 -38.5920234
OS 37.60404214 -38.601269
OS 37.59664566 -38.6105146
OS 37.5957211 -38.61143916
OS 37.59479654 -38.61236372
OS 37.59202286 -38.6151374
OS 37.58832462 -38.61791108
OS 37.58370182 -38.62160932
OS 37.57815446 -38.62530756
OS 37.57075798 -38.62993036
OS 37.5633615 -38.63547772
OS 37.5541159 -38.64010052
OS 37.54394574 -38.64472332
OS 37.53285102 -38.65027068
OS 37.52083174 -38.65489348
OS 37.50696334 -38.65859172
OS 37.49309494 -38.66321452
OS 37.47737742 -38.6659882
OS 37.46073534 -38.66876188
OS 37.46258446 -38.66968644
OS 37.4662827 -38.67153556
OS 37.47183006 -38.6752338
OS 37.47922654 -38.67893204
OS 37.49586862 -38.6891022
OS 37.50418966 -38.69557412
OS 37.51158614 -38.70112148
OS 37.51343526 -38.7029706
OS 37.51805806 -38.7075934
OS 37.52545454 -38.71498988
OS 37.53470014 -38.72423548
OS 37.5448703 -38.73717932
OS 37.55688958 -38.75104772
OS 37.56890886 -38.7676898
OS 37.5818527 -38.786181
OS 37.69187534 -38.95999828
OS 37.5864755 -38.95999828
OS 37.50234054 -38.82686164
OS 37.50234054 -38.82593708
OS 37.50049142 -38.82408796
OS 37.4986423 -38.82131428
OS 37.49586862 -38.81761604
OS 37.4893967 -38.80744588
OS 37.48107566 -38.79450204
OS 37.4709055 -38.78063364
OS 37.46073534 -38.76584068
OS 37.45056518 -38.75197228
OS 37.44131958 -38.73902844
OS 37.44039502 -38.73810388
OS 37.43762134 -38.73440564
OS 37.43299854 -38.72885828
OS 37.42652662 -38.72238636
OS 37.41265822 -38.70851796
OS 37.40526174 -38.70204604
OS 37.39786526 -38.69649868
OS 37.3969407 -38.69557412
OS 37.39509158 -38.69464956
OS 37.39139334 -38.69280044
OS 37.38584598 -38.69002676
OS 37.38029862 -38.68725308
OS 37.3738267 -38.6844794
OS 37.35903374 -38.6798566
OS 37.35810918 -38.6798566
OS 37.35626006 -38.67893204
OS 37.35256182 -38.67893204
OS 37.34793902 -38.67800748
OS 37.3414671 -38.67708292
OS 37.33407062 -38.67708292
OS 37.32390046 -38.67615836
OS 37.21480238 -38.67615836
OS 37.21480238 -38.95999828
OS 37.12974286 -38.95999828
OS 37.12974286 -38.32020276
OS 37.42652662 -38.32020276
OS 37.4339231 -38.32112732
OE
OB 35.31760526 -38.95999828 I
OS 35.23254574 -38.95999828
OS 35.23254574 -38.32020276
OS 35.31760526 -38.32020276
OS 35.31760526 -38.95999828
OE
OB 42.12051774 -38.66413908 H
OS 41.95224782 -38.66413908
OS 41.95224782 -38.88418436
OS 42.13438614 -38.88418436
OS 42.1538019 -38.8832598
OS 42.16212294 -38.88233524
OS 42.16951942 -38.88141068
OS 42.17044398 -38.88141068
OS 42.17414222 -38.88048612
OS 42.17968958 -38.87956156
OS 42.1861615 -38.87771244
OS 42.20187902 -38.87216508
OS 42.21759654 -38.8647686
OS 42.2185211 -38.86384404
OS 42.22129478 -38.86199492
OS 42.22499302 -38.85922124
OS 42.22961582 -38.855523
OS 42.23423862 -38.84997564
OS 42.24071054 -38.84442828
OS 42.24533334 -38.8370318
OS 42.2508807 -38.82871076
OS 42.25180526 -38.8277862
OS 42.25272982 -38.82501252
OS 42.25457894 -38.81946516
OS 42.25735262 -38.81299324
OS 42.2601263 -38.80559676
OS 42.26197542 -38.79635116
OS 42.26289998 -38.78525644
OS 42.26382454 -38.77416172
OS 42.26382454 -38.7723126
OS 42.26382454 -38.76861436
OS 42.26289998 -38.76121788
OS 42.26105086 -38.75289684
OS 42.25920174 -38.74365124
OS 42.2555035 -38.73348108
OS 42.2508807 -38.72331092
OS 42.24440878 -38.71314076
OS 42.24348422 -38.7122162
OS 42.24071054 -38.70851796
OS 42.2370123 -38.70389516
OS 42.23146494 -38.6983478
OS 42.22406846 -38.69187588
OS 42.21482286 -38.68540396
OS 42.2046527 -38.6798566
OS 42.19263342 -38.6752338
OS 42.1907843 -38.67430924
OS 42.18708606 -38.67338468
OS 42.17876502 -38.67153556
OS 42.16859486 -38.66968644
OS 42.15565102 -38.66783732
OS 42.1399335 -38.6659882
OS 42.12051774 -38.66413908
OE
OB 45.22981302 -38.5504182 H
OS 45.22426566 -38.5504182
OS 45.21964286 -38.55134276
OS 45.2094727 -38.55226732
OS 45.1956043 -38.55596556
OS 45.17988678 -38.56151292
OS 45.1632447 -38.5689094
OS 45.14752718 -38.58000412
OS 45.13920614 -38.5874006
OS 45.13180966 -38.59479708
OS 45.13180966 -38.59572164
OS 45.12996054 -38.5966462
OS 45.12811142 -38.59941988
OS 45.12533774 -38.60311812
OS 45.12256406 -38.60774092
OS 45.11979038 -38.61328828
OS 45.11609214 -38.62068476
OS 45.1123939 -38.62808124
OS 45.10869566 -38.63732684
OS 45.10499742 -38.64657244
OS 45.10222374 -38.65766716
OS 45.09945006 -38.66968644
OS 45.09667638 -38.68263028
OS 45.09482726 -38.69649868
OS 45.0939027 -38.7122162
OS 45.09297814 -38.72793372
OS 45.09297814 -38.72885828
OS 45.09297814 -38.73163196
OS 45.09297814 -38.73625476
OS 45.0939027 -38.74272668
OS 45.0939027 -38.75012316
OS 45.09482726 -38.7584442
OS 45.09760094 -38.77785996
OS 45.10222374 -38.8000494
OS 45.10962022 -38.82223884
OS 45.11886582 -38.84350372
OS 45.12533774 -38.85274932
OS 45.13180966 -38.86199492
OS 45.13273422 -38.86199492
OS 45.13365878 -38.86384404
OS 45.13920614 -38.86846684
OS 45.14752718 -38.87586332
OS 45.1586219 -38.8832598
OS 45.1724903 -38.89158084
OS 45.18913238 -38.89897732
OS 45.20854814 -38.90360012
OS 45.2187183 -38.90452468
OS 45.22981302 -38.90544924
OS 45.23536038 -38.90544924
OS 45.23998318 -38.90452468
OS 45.25015334 -38.90267556
OS 45.26402174 -38.89990188
OS 45.2788147 -38.89435452
OS 45.29545678 -38.88695804
OS 45.3111743 -38.87586332
OS 45.31949534 -38.86846684
OS 45.32689182 -38.86107036
OS 45.32781638 -38.8601458
OS 45.32874094 -38.85922124
OS 45.33059006 -38.85644756
OS 45.33336374 -38.85274932
OS 45.33613742 -38.84812652
OS 45.33983566 -38.84257916
OS 45.3435339 -38.83518268
OS 45.34723214 -38.8277862
OS 45.35093038 -38.8185406
OS 45.35370406 -38.80837044
OS 45.3574023 -38.79727572
OS 45.36017598 -38.78525644
OS 45.36294966 -38.77138804
OS 45.36479878 -38.75751964
OS 45.3666479 -38.74180212
OS 45.3666479 -38.72516004
OS 45.3666479 -38.72423548
OS 45.3666479 -38.7214618
OS 45.3666479 -38.716839
OS 45.36572334 -38.71129164
OS 45.36572334 -38.70389516
OS 45.36479878 -38.69557412
OS 45.3620251 -38.67615836
OS 45.3574023 -38.65581804
OS 45.35000582 -38.6336286
OS 45.33983566 -38.61328828
OS 45.3342883 -38.60311812
OS 45.32689182 -38.59479708
OS 45.32689182 -38.59387252
OS 45.3250427 -38.59294796
OS 45.31949534 -38.5874006
OS 45.3111743 -38.58092868
OS 45.30007958 -38.57260764
OS 45.28621118 -38.5642866
OS 45.2695691 -38.55689012
OS 45.2510779 -38.55226732
OS 45.24090774 -38.55134276
OS 45.22981302 -38.5504182
OE
OB 32.07702246 -38.54764452 H
OS 32.07239966 -38.54764452
OS 32.06870142 -38.54856908
OS 32.05945582 -38.5504182
OS 32.04743654 -38.55319188
OS 32.03356814 -38.55873924
OS 32.01877518 -38.56706028
OS 32.01045414 -38.57260764
OS 32.00305766 -38.57907956
OS 31.99566118 -38.58647604
OS 31.9882647 -38.59479708
OS 31.9882647 -38.59572164
OS 31.98641558 -38.5966462
OS 31.98456646 -38.59941988
OS 31.98271734 -38.60311812
OS 31.97994366 -38.60866548
OS 31.97624542 -38.61421284
OS 31.97254718 -38.62160932
OS 31.9697735 -38.6290058
OS 31.96607526 -38.6382514
OS 31.96237702 -38.64842156
OS 31.95960334 -38.65951628
OS 31.9559051 -38.67153556
OS 31.95405598 -38.68540396
OS 31.95220686 -38.69927236
OS 31.95035774 -38.71406532
OS 31.95035774 -38.7307074
OS 31.95035774 -38.73163196
OS 31.95035774 -38.73440564
OS 31.95035774 -38.73902844
OS 31.9512823 -38.74550036
OS 31.9512823 -38.75289684
OS 31.95220686 -38.76121788
OS 31.95498054 -38.78063364
OS 31.95960334 -38.80282308
OS 31.9651507 -38.82408796
OS 31.9743963 -38.84535284
OS 31.97994366 -38.85459844
OS 31.98641558 -38.86291948
OS 31.9882647 -38.8647686
OS 31.9928875 -38.8693914
OS 32.00028398 -38.87678788
OS 32.01045414 -38.88418436
OS 32.02339798 -38.89158084
OS 32.03819094 -38.89897732
OS 32.05483302 -38.90360012
OS 32.06407862 -38.90452468
OS 32.07332422 -38.90544924
OS 32.07887158 -38.90544924
OS 32.08256982 -38.90452468
OS 32.09181542 -38.90267556
OS 32.10475926 -38.89990188
OS 32.11862766 -38.89435452
OS 32.13342062 -38.88695804
OS 32.14821358 -38.87586332
OS 32.15561006 -38.8693914
OS 32.16300654 -38.86199492
OS 32.16300654 -38.86107036
OS 32.16485566 -38.8601458
OS 32.16670478 -38.85737212
OS 32.1685539 -38.85367388
OS 32.17225214 -38.84905108
OS 32.17502582 -38.84257916
OS 32.17872406 -38.83610724
OS 32.1824223 -38.8277862
OS 32.18519598 -38.81946516
OS 32.18889422 -38.80837044
OS 32.19259246 -38.79727572
OS 32.19536614 -38.78525644
OS 32.19721526 -38.77138804
OS 32.19906438 -38.75659508
OS 32.2009135 -38.74087756
OS 32.2009135 -38.72423548
OS 32.2009135 -38.72331092
OS 32.2009135 -38.72053724
OS 32.2009135 -38.71591444
OS 32.19998894 -38.70944252
OS 32.19998894 -38.70204604
OS 32.19906438 -38.693725
OS 32.1962907 -38.67430924
OS 32.1916679 -38.65304436
OS 32.18519598 -38.63177948
OS 32.17595038 -38.6105146
OS 32.17040302 -38.60034444
OS 32.1639311 -38.5920234
OS 32.1639311 -38.59109884
OS 32.16208198 -38.59017428
OS 32.15745918 -38.58462692
OS 32.1500627 -38.578155
OS 32.13989254 -38.56983396
OS 32.1269487 -38.56151292
OS 32.11215574 -38.55411644
OS 32.09551366 -38.54949364
OS 32.08626806 -38.54856908
OS 32.07702246 -38.54764452
OE
OB 42.10387566 -38.39601668 H
OS 41.95224782 -38.39601668
OS 41.95224782 -38.58832516
OS 42.10942302 -38.58832516
OS 42.1214423 -38.5874006
OS 42.13438614 -38.58647604
OS 42.14732998 -38.58555148
OS 42.16027382 -38.58370236
OS 42.17044398 -38.58185324
OS 42.1722931 -38.58092868
OS 42.17599134 -38.58000412
OS 42.1815387 -38.57723044
OS 42.18893518 -38.5735322
OS 42.19633166 -38.56983396
OS 42.2046527 -38.5642866
OS 42.21297374 -38.55689012
OS 42.21944566 -38.54949364
OS 42.22037022 -38.54856908
OS 42.22221934 -38.5457954
OS 42.22499302 -38.54024804
OS 42.2277667 -38.53377612
OS 42.23054038 -38.52637964
OS 42.23331406 -38.51713404
OS 42.23516318 -38.50603932
OS 42.23608774 -38.49402004
OS 42.23608774 -38.49217092
OS 42.23608774 -38.48847268
OS 42.23516318 -38.48292532
OS 42.23423862 -38.47552884
OS 42.2323895 -38.46628324
OS 42.22961582 -38.45703764
OS 42.22591758 -38.44779204
OS 42.22037022 -38.43854644
OS 42.21944566 -38.43762188
OS 42.21759654 -38.4348482
OS 42.2138983 -38.4302254
OS 42.2092755 -38.4256026
OS 42.20280358 -38.42005524
OS 42.1954071 -38.41450788
OS 42.1861615 -38.40896052
OS 42.17599134 -38.40526228
OS 42.17506678 -38.40526228
OS 42.17044398 -38.40341316
OS 42.16397206 -38.4024886
OS 42.1538019 -38.40063948
OS 42.1399335 -38.39879036
OS 42.12421598 -38.3978658
OS 42.10387566 -38.39601668
OE
OB 37.41635646 -38.39139388 H
OS 37.21480238 -38.39139388
OS 37.21480238 -38.60311812
OS 37.40526174 -38.60311812
OS 37.41635646 -38.60219356
OS 37.4293003 -38.601269
OS 37.44409326 -38.60034444
OS 37.45888622 -38.59849532
OS 37.47367918 -38.59572164
OS 37.48662302 -38.5920234
OS 37.48847214 -38.59109884
OS 37.49217038 -38.58924972
OS 37.49771774 -38.58647604
OS 37.50511422 -38.5827778
OS 37.51343526 -38.57723044
OS 37.5217563 -38.57075852
OS 37.53007734 -38.56243748
OS 37.53654926 -38.55319188
OS 37.53747382 -38.55226732
OS 37.53932294 -38.54856908
OS 37.54209662 -38.54302172
OS 37.54579486 -38.53562524
OS 37.54856854 -38.5273042
OS 37.55134222 -38.5180586
OS 37.55319134 -38.50696388
OS 37.5541159 -38.49586916
OS 37.5541159 -38.4949446
OS 37.5541159 -38.49402004
OS 37.55319134 -38.48847268
OS 37.55226678 -38.48015164
OS 37.55041766 -38.46905692
OS 37.54579486 -38.4579622
OS 37.5402475 -38.44501836
OS 37.53192646 -38.43299908
OS 37.52083174 -38.4209798
OS 37.51898262 -38.42005524
OS 37.51435982 -38.416357
OS 37.50696334 -38.4117342
OS 37.49494406 -38.40618684
OS 37.48107566 -38.40063948
OS 37.46258446 -38.39601668
OS 37.44131958 -38.39231844
OS 37.41635646 -38.39139388
OE
OB 39.82298614 -38.54764452 H
OS 39.81836334 -38.54764452
OS 39.8146651 -38.54856908
OS 39.8054195 -38.5504182
OS 39.79340022 -38.55319188
OS 39.77953182 -38.55873924
OS 39.76473886 -38.56706028
OS 39.75641782 -38.57260764
OS 39.74902134 -38.57907956
OS 39.74162486 -38.58647604
OS 39.73422838 -38.59479708
OS 39.73422838 -38.59572164
OS 39.73237926 -38.5966462
OS 39.73053014 -38.59941988
OS 39.72868102 -38.60311812
OS 39.72590734 -38.60866548
OS 39.7222091 -38.61421284
OS 39.71851086 -38.62160932
OS 39.71573718 -38.6290058
OS 39.71203894 -38.6382514
OS 39.7083407 -38.64842156
OS 39.70556702 -38.65951628
OS 39.70186878 -38.67153556
OS 39.70001966 -38.68540396
OS 39.69817054 -38.69927236
OS 39.69632142 -38.71406532
OS 39.69632142 -38.7307074
OS 39.69632142 -38.73163196
OS 39.69632142 -38.73440564
OS 39.69632142 -38.73902844
OS 39.69724598 -38.74550036
OS 39.69724598 -38.75289684
OS 39.69817054 -38.76121788
OS 39.70094422 -38.78063364
OS 39.70556702 -38.80282308
OS 39.71111438 -38.82408796
OS 39.72035998 -38.84535284
OS 39.72590734 -38.85459844
OS 39.73237926 -38.86291948
OS 39.73422838 -38.8647686
OS 39.73885118 -38.8693914
OS 39.74624766 -38.87678788
OS 39.75641782 -38.88418436
OS 39.76936166 -38.89158084
OS 39.78415462 -38.89897732
OS 39.8007967 -38.90360012
OS 39.8100423 -38.90452468
OS 39.8192879 -38.90544924
OS 39.82483526 -38.90544924
OS 39.8285335 -38.90452468
OS 39.8377791 -38.90267556
OS 39.85072294 -38.89990188
OS 39.86459134 -38.89435452
OS 39.8793843 -38.88695804
OS 39.89417726 -38.87586332
OS 39.90157374 -38.8693914
OS 39.90897022 -38.86199492
OS 39.90897022 -38.86107036
OS 39.91081934 -38.8601458
OS 39.91266846 -38.85737212
OS 39.91451758 -38.85367388
OS 39.91821582 -38.84905108
OS 39.9209895 -38.84257916
OS 39.92468774 -38.83610724
OS 39.92838598 -38.8277862
OS 39.93115966 -38.81946516
OS 39.9348579 -38.80837044
OS 39.93855614 -38.79727572
OS 39.94132982 -38.78525644
OS 39.94317894 -38.77138804
OS 39.94502806 -38.75659508
OS 39.94687718 -38.74087756
OS 39.94687718 -38.72423548
OS 39.94687718 -38.72331092
OS 39.94687718 -38.72053724
OS 39.94687718 -38.71591444
OS 39.94595262 -38.70944252
OS 39.94595262 -38.70204604
OS 39.94502806 -38.693725
OS 39.94225438 -38.67430924
OS 39.93763158 -38.65304436
OS 39.93115966 -38.63177948
OS 39.92191406 -38.6105146
OS 39.9163667 -38.60034444
OS 39.90989478 -38.5920234
OS 39.90989478 -38.59109884
OS 39.90804566 -38.59017428
OS 39.90342286 -38.58462692
OS 39.89602638 -38.578155
OS 39.88585622 -38.56983396
OS 39.87291238 -38.56151292
OS 39.85811942 -38.55411644
OS 39.84147734 -38.54949364
OS 39.83223174 -38.54856908
OS 39.82298614 -38.54764452
OE
OB 35.73550638 -38.39601668 H
OS 35.5524435 -38.39601668
OS 35.5524435 -38.624383
OS 35.72441166 -38.624383
OS 35.73088358 -38.62345844
OS 35.7373555 -38.62345844
OS 35.74475198 -38.62253388
OS 35.76231862 -38.62068476
OS 35.78173438 -38.61698652
OS 35.80115014 -38.61143916
OS 35.81871678 -38.60404268
OS 35.82703782 -38.59941988
OS 35.83350974 -38.59387252
OS 35.83535886 -38.5920234
OS 35.8390571 -38.58832516
OS 35.84460446 -38.58092868
OS 35.85107638 -38.57168308
OS 35.8575483 -38.5596638
OS 35.86309566 -38.54487084
OS 35.8667939 -38.52822876
OS 35.86864302 -38.508813
OS 35.86864302 -38.50788844
OS 35.86864302 -38.50696388
OS 35.86864302 -38.50234108
OS 35.86771846 -38.49402004
OS 35.86586934 -38.48477444
OS 35.86402022 -38.47460428
OS 35.86032198 -38.462585
OS 35.85477462 -38.45149028
OS 35.8483027 -38.44039556
OS 35.84737814 -38.439471
OS 35.84460446 -38.43577276
OS 35.83998166 -38.43114996
OS 35.8344343 -38.42467804
OS 35.82611326 -38.41820612
OS 35.81686766 -38.41265876
OS 35.8066975 -38.4071114
OS 35.79467822 -38.4024886
OS 35.79375366 -38.4024886
OS 35.79005542 -38.40156404
OS 35.78450806 -38.40063948
OS 35.77711158 -38.39879036
OS 35.76601686 -38.3978658
OS 35.75214846 -38.39694124
OS 35.73550638 -38.39601668
OE
OB 43.44263854 -38.5504182 H
OS 43.43709118 -38.5504182
OS 43.43339294 -38.55134276
OS 43.42322278 -38.55226732
OS 43.4112035 -38.555041
OS 43.39641054 -38.5596638
OS 43.38069302 -38.56613572
OS 43.36590006 -38.57538132
OS 43.3511071 -38.5874006
OS 43.34925798 -38.58924972
OS 43.34555974 -38.59387252
OS 43.33908782 -38.60219356
OS 43.3326159 -38.61328828
OS 43.32521942 -38.62623212
OS 43.3187475 -38.6428742
OS 43.31320014 -38.66228996
OS 43.31042646 -38.68355484
OS 43.57022782 -38.68355484
OS 43.57022782 -38.68263028
OS 43.57022782 -38.68078116
OS 43.56930326 -38.67800748
OS 43.56930326 -38.67430924
OS 43.56745414 -38.66321452
OS 43.56468046 -38.65119524
OS 43.56005766 -38.63640228
OS 43.55543486 -38.62253388
OS 43.54803838 -38.60866548
OS 43.53971734 -38.5966462
OS 43.53971734 -38.59572164
OS 43.53786822 -38.59479708
OS 43.53324542 -38.58924972
OS 43.52492438 -38.58185324
OS 43.51382966 -38.5735322
OS 43.49996126 -38.56521116
OS 43.48331918 -38.55781468
OS 43.46390342 -38.55226732
OS 43.45373326 -38.55134276
OS 43.44263854 -38.5504182
OE
OB 34.35791198 -38.39601668 H
OS 34.20628414 -38.39601668
OS 34.20628414 -38.58832516
OS 34.36345934 -38.58832516
OS 34.37547862 -38.5874006
OS 34.38842246 -38.58647604
OS 34.4013663 -38.58555148
OS 34.41431014 -38.58370236
OS 34.4244803 -38.58185324
OS 34.42632942 -38.58092868
OS 34.43002766 -38.58000412
OS 34.43557502 -38.57723044
OS 34.4429715 -38.5735322
OS 34.45036798 -38.56983396
OS 34.45868902 -38.5642866
OS 34.46701006 -38.55689012
OS 34.47348198 -38.54949364
OS 34.47440654 -38.54856908
OS 34.47625566 -38.5457954
OS 34.47902934 -38.54024804
OS 34.48180302 -38.53377612
OS 34.4845767 -38.52637964
OS 34.48735038 -38.51713404
OS 34.4891995 -38.50603932
OS 34.49012406 -38.49402004
OS 34.49012406 -38.49217092
OS 34.49012406 -38.48847268
OS 34.4891995 -38.48292532
OS 34.48827494 -38.47552884
OS 34.48642582 -38.46628324
OS 34.48365214 -38.45703764
OS 34.4799539 -38.44779204
OS 34.47440654 -38.43854644
OS 34.47348198 -38.43762188
OS 34.47163286 -38.4348482
OS 34.46793462 -38.4302254
OS 34.46331182 -38.4256026
OS 34.4568399 -38.42005524
OS 34.44944342 -38.41450788
OS 34.44019782 -38.40896052
OS 34.43002766 -38.40526228
OS 34.4291031 -38.40526228
OS 34.4244803 -38.40341316
OS 34.41800838 -38.4024886
OS 34.40783822 -38.40063948
OS 34.39396982 -38.39879036
OS 34.3782523 -38.3978658
OS 34.35791198 -38.39601668
OE
OB 40.89732486 -38.39601668 H
OS 40.71426198 -38.39601668
OS 40.71426198 -38.624383
OS 40.88623014 -38.624383
OS 40.89270206 -38.62345844
OS 40.89917398 -38.62345844
OS 40.90657046 -38.62253388
OS 40.9241371 -38.62068476
OS 40.94355286 -38.61698652
OS 40.96296862 -38.61143916
OS 40.98053526 -38.60404268
OS 40.9888563 -38.59941988
OS 40.99532822 -38.59387252
OS 40.99717734 -38.5920234
OS 41.00087558 -38.58832516
OS 41.00642294 -38.58092868
OS 41.01289486 -38.57168308
OS 41.01936678 -38.5596638
OS 41.02491414 -38.54487084
OS 41.02861238 -38.52822876
OS 41.0304615 -38.508813
OS 41.0304615 -38.50788844
OS 41.0304615 -38.50696388
OS 41.0304615 -38.50234108
OS 41.02953694 -38.49402004
OS 41.02768782 -38.48477444
OS 41.0258387 -38.47460428
OS 41.02214046 -38.462585
OS 41.0165931 -38.45149028
OS 41.01012118 -38.44039556
OS 41.00919662 -38.439471
OS 41.00642294 -38.43577276
OS 41.00180014 -38.43114996
OS 40.99625278 -38.42467804
OS 40.98793174 -38.41820612
OS 40.97868614 -38.41265876
OS 40.96851598 -38.4071114
OS 40.9564967 -38.4024886
OS 40.95557214 -38.4024886
OS 40.9518739 -38.40156404
OS 40.94632654 -38.40063948
OS 40.93893006 -38.39879036
OS 40.92783534 -38.3978658
OS 40.91396694 -38.39694124
OS 40.89732486 -38.39601668
OE
OB 33.15136118 -38.39601668 H
OS 32.9682983 -38.39601668
OS 32.9682983 -38.624383
OS 33.14026646 -38.624383
OS 33.14673838 -38.62345844
OS 33.1532103 -38.62345844
OS 33.16060678 -38.62253388
OS 33.17817342 -38.62068476
OS 33.19758918 -38.61698652
OS 33.21700494 -38.61143916
OS 33.23457158 -38.60404268
OS 33.24289262 -38.59941988
OS 33.24936454 -38.59387252
OS 33.25121366 -38.5920234
OS 33.2549119 -38.58832516
OS 33.26045926 -38.58092868
OS 33.26693118 -38.57168308
OS 33.2734031 -38.5596638
OS 33.27895046 -38.54487084
OS 33.2826487 -38.52822876
OS 33.28449782 -38.508813
OS 33.28449782 -38.50788844
OS 33.28449782 -38.50696388
OS 33.28449782 -38.50234108
OS 33.28357326 -38.49402004
OS 33.28172414 -38.48477444
OS 33.27987502 -38.47460428
OS 33.27617678 -38.462585
OS 33.27062942 -38.45149028
OS 33.2641575 -38.44039556
OS 33.26323294 -38.439471
OS 33.26045926 -38.43577276
OS 33.25583646 -38.43114996
OS 33.2502891 -38.42467804
OS 33.24196806 -38.41820612
OS 33.23272246 -38.41265876
OS 33.2225523 -38.4071114
OS 33.21053302 -38.4024886
OS 33.20960846 -38.4024886
OS 33.20591022 -38.40156404
OS 33.20036286 -38.40063948
OS 33.19296638 -38.39879036
OS 33.18187166 -38.3978658
OS 33.16800326 -38.39694124
OS 33.15136118 -38.39601668
OE
OB 34.37455406 -38.66413908 H
OS 34.20628414 -38.66413908
OS 34.20628414 -38.88418436
OS 34.38842246 -38.88418436
OS 34.40783822 -38.8832598
OS 34.41615926 -38.88233524
OS 34.42355574 -38.88141068
OS 34.4244803 -38.88141068
OS 34.42817854 -38.88048612
OS 34.4337259 -38.87956156
OS 34.44019782 -38.87771244
OS 34.45591534 -38.87216508
OS 34.47163286 -38.8647686
OS 34.47255742 -38.86384404
OS 34.4753311 -38.86199492
OS 34.47902934 -38.85922124
OS 34.48365214 -38.855523
OS 34.48827494 -38.84997564
OS 34.49474686 -38.84442828
OS 34.49936966 -38.8370318
OS 34.50491702 -38.82871076
OS 34.50584158 -38.8277862
OS 34.50676614 -38.82501252
OS 34.50861526 -38.81946516
OS 34.51138894 -38.81299324
OS 34.51416262 -38.80559676
OS 34.51601174 -38.79635116
OS 34.5169363 -38.78525644
OS 34.51786086 -38.77416172
OS 34.51786086 -38.7723126
OS 34.51786086 -38.76861436
OS 34.5169363 -38.76121788
OS 34.51508718 -38.75289684
OS 34.51323806 -38.74365124
OS 34.50953982 -38.73348108
OS 34.50491702 -38.72331092
OS 34.4984451 -38.71314076
OS 34.49752054 -38.7122162
OS 34.49474686 -38.70851796
OS 34.49104862 -38.70389516
OS 34.48550126 -38.6983478
OS 34.47810478 -38.69187588
OS 34.46885918 -38.68540396
OS 34.45868902 -38.6798566
OS 34.44666974 -38.6752338
OS 34.44482062 -38.67430924
OS 34.44112238 -38.67338468
OS 34.43280134 -38.67153556
OS 34.42263118 -38.66968644
OS 34.40968734 -38.66783732
OS 34.39396982 -38.6659882
OS 34.37455406 -38.66413908
OE
SE
S P 0
OB 48.49040086 -36.61402634 I
OS 48.17420134 -36.61402634
OS 48.17420134 -37.45999874
OS 48.04661206 -37.45999874
OS 48.04661206 -36.61402634
OS 47.73041254 -36.61402634
OS 47.73041254 -36.50030546
OS 48.49040086 -36.50030546
OS 48.49040086 -36.61402634
OE
OB 47.69990206 -37.45999874 I
OS 47.5556707 -37.45999874
OS 47.44333666 -37.16876234
OS 47.04115306 -37.16876234
OS 46.93714006 -37.45999874
OS 46.80261658 -37.45999874
OS 47.16874234 -36.50030546
OS 47.30742634 -36.50030546
OS 47.69990206 -37.45999874
OE
OB 49.31834434 -36.61402634 I
OS 48.75112678 -36.61402634
OS 48.75112678 -36.90664958
OS 49.2822865 -36.90664958
OS 49.2822865 -37.02037046
OS 48.75112678 -37.02037046
OS 48.75112678 -37.34627786
OS 49.34053378 -37.34627786
OS 49.34053378 -37.45999874
OS 48.6235375 -37.45999874
OS 48.6235375 -36.50030546
OS 49.31834434 -36.50030546
OS 49.31834434 -36.61402634
OE
OB 46.33386466 -36.5016923 I
OS 46.36160146 -36.50307914
OS 46.38933826 -36.50585282
OS 46.41707506 -36.51001334
OS 46.44065134 -36.51417386
OS 46.44203818 -36.51417386
OS 46.44481186 -36.5155607
OS 46.44897238 -36.5155607
OS 46.45451974 -36.51833438
OS 46.46977498 -36.5224949
OS 46.48919074 -36.5294291
OS 46.51138018 -36.53913698
OS 46.53495646 -36.55161854
OS 46.55853274 -36.56548694
OS 46.58072218 -36.58351586
OS 46.58210902 -36.5849027
OS 46.58349586 -36.58628954
OS 46.58765638 -36.59045006
OS 46.59320374 -36.59461058
OS 46.60707214 -36.60847898
OS 46.62371422 -36.62789474
OS 46.64174314 -36.65147102
OS 46.6611589 -36.67920782
OS 46.67918782 -36.71110514
OS 46.69444306 -36.74716298
OS 46.69444306 -36.74854982
OS 46.6958299 -36.7513235
OS 46.69860358 -36.75687086
OS 46.69999042 -36.7651919
OS 46.70415094 -36.77489978
OS 46.70692462 -36.7859945
OS 46.7096983 -36.79847606
OS 46.71385882 -36.8137313
OS 46.71801934 -36.82898654
OS 46.72079302 -36.84701546
OS 46.72772722 -36.88584698
OS 46.73188774 -36.92883902
OS 46.73327458 -36.97599158
OS 46.73327458 -36.97737842
OS 46.73327458 -36.9801521
OS 46.73327458 -36.9870863
OS 46.73327458 -36.9940205
OS 46.73188774 -37.00372838
OS 46.73188774 -37.0148231
OS 46.7305009 -37.04117306
OS 46.72634038 -37.07168354
OS 46.72217986 -37.10358086
OS 46.71524566 -37.13686502
OS 46.70692462 -37.17014918
OS 46.70692462 -37.17153602
OS 46.70553778 -37.1743097
OS 46.70415094 -37.17847022
OS 46.7027641 -37.18401758
OS 46.69721674 -37.19927282
OS 46.6888957 -37.21868858
OS 46.68057466 -37.24087802
OS 46.66947994 -37.26306746
OS 46.65561154 -37.28664374
OS 46.64174314 -37.30883318
OS 46.6403563 -37.31160686
OS 46.63480894 -37.31854106
OS 46.6264879 -37.32824894
OS 46.61539318 -37.3407305
OS 46.60291162 -37.3545989
OS 46.58765638 -37.3684673
OS 46.57240114 -37.38372254
OS 46.55437222 -37.3962041
OS 46.55159854 -37.39759094
OS 46.54605118 -37.40175146
OS 46.5363433 -37.40729882
OS 46.5224749 -37.41423302
OS 46.50583282 -37.42255406
OS 46.48641706 -37.42948826
OS 46.46422762 -37.4378093
OS 46.4392645 -37.4447435
OS 46.43649082 -37.4447435
OS 46.4323303 -37.44613034
OS 46.42816978 -37.44751718
OS 46.41430138 -37.44890402
OS 46.39488562 -37.4516777
OS 46.37269618 -37.45445138
OS 46.34634622 -37.45722506
OS 46.31722258 -37.4586119
OS 46.28532526 -37.45999874
OS 45.9400021 -37.45999874
OS 45.9400021 -36.50030546
OS 46.30890154 -36.50030546
OS 46.33386466 -36.5016923
OE
OB 46.28948578 -36.61402634 H
OS 46.06759138 -36.61402634
OS 46.06759138 -37.34627786
OS 46.29503314 -37.34627786
OS 46.30474102 -37.34489102
OS 46.32554362 -37.34350418
OS 46.3491199 -37.34211734
OS 46.37408302 -37.33934366
OS 46.39904614 -37.33518314
OS 46.41984874 -37.32963578
OS 46.42262242 -37.32824894
OS 46.42955662 -37.3268621
OS 46.4392645 -37.32270158
OS 46.45174606 -37.31715422
OS 46.46561446 -37.30883318
OS 46.47948286 -37.30051214
OS 46.49335126 -37.29080426
OS 46.50721966 -37.27970954
OS 46.5086065 -37.27693586
OS 46.51415386 -37.2713885
OS 46.5224749 -37.26168062
OS 46.53218278 -37.24781222
OS 46.5432775 -37.2297833
OS 46.55575906 -37.2089807
OS 46.56685378 -37.18540442
OS 46.57656166 -37.15905446
OS 46.57656166 -37.15766762
OS 46.5779485 -37.15489394
OS 46.57933534 -37.15073342
OS 46.58072218 -37.14518606
OS 46.58210902 -37.13825186
OS 46.5848827 -37.12854398
OS 46.58765638 -37.1188361
OS 46.59043006 -37.10774138
OS 46.59459058 -37.08000458
OS 46.5987511 -37.04810726
OS 46.60152478 -37.01204942
OS 46.60291162 -36.9732179
OS 46.60291162 -36.97183106
OS 46.60291162 -36.9662837
OS 46.60291162 -36.9593495
OS 46.60152478 -36.94825478
OS 46.60152478 -36.93577322
OS 46.60013794 -36.92190482
OS 46.5987511 -36.90526274
OS 46.59736426 -36.88862066
OS 46.59043006 -36.85117598
OS 46.58210902 -36.81234446
OS 46.56962746 -36.77628662
OS 46.56130642 -36.7582577
OS 46.55298538 -36.74300246
OS 46.55298538 -36.74161562
OS 46.5502117 -36.73884194
OS 46.54743802 -36.73468142
OS 46.54466434 -36.72913406
OS 46.53356962 -36.71526566
OS 46.51970122 -36.69862358
OS 46.5016723 -36.68059466
OS 46.4808697 -36.66256574
OS 46.45729342 -36.6473105
OS 46.4323303 -36.63482894
OS 46.42955662 -36.6334421
OS 46.42262242 -36.63205526
OS 46.41014086 -36.62789474
OS 46.39211194 -36.62373422
OS 46.3699225 -36.62096054
OS 46.3421857 -36.61680002
OS 46.32554362 -36.61541318
OS 46.3075147 -36.61541318
OS 46.28948578 -36.61402634
OE
OB 47.23531066 -36.60015794 H
OS 47.23531066 -36.60154478
OS 47.23392382 -36.60431846
OS 47.23392382 -36.60986582
OS 47.23115014 -36.61541318
OS 47.2297633 -36.62512106
OS 47.22698962 -36.63482894
OS 47.22144226 -36.65840522
OS 47.21450806 -36.68614202
OS 47.20480018 -36.7166525
OS 47.1950923 -36.74993666
OS 47.18261074 -36.78460766
OS 47.07859774 -37.06474934
OS 47.4031183 -37.06474934
OS 47.30326582 -36.80124974
OS 47.30326582 -36.7998629
OS 47.30187898 -36.79570238
OS 47.2991053 -36.78876818
OS 47.29633162 -36.78044714
OS 47.2921711 -36.77073926
OS 47.28801058 -36.7582577
OS 47.28385006 -36.7443893
OS 47.2783027 -36.7305209
OS 47.26720798 -36.69862358
OS 47.25611326 -36.66533942
OS 47.24501854 -36.63205526
OS 47.23531066 -36.60015794
OE
SE
S P 0
OB 53.57408132 -38.30725892 I
OS 53.5861006 -38.30910804
OS 53.60089356 -38.31188172
OS 53.61753564 -38.31650452
OS 53.63417772 -38.32205188
OS 53.6508198 -38.32944836
OS 53.65174436 -38.32944836
OS 53.65266892 -38.33037292
OS 53.65821628 -38.3331466
OS 53.66653732 -38.33869396
OS 53.67578292 -38.34516588
OS 53.68687764 -38.35441148
OS 53.69797236 -38.36458164
OS 53.70906708 -38.37660092
OS 53.71831268 -38.39046932
OS 53.71923724 -38.39231844
OS 53.72201092 -38.39694124
OS 53.72570916 -38.40526228
OS 53.73033196 -38.41543244
OS 53.73495476 -38.42745172
OS 53.738653 -38.44132012
OS 53.74142668 -38.45703764
OS 53.74235124 -38.47275516
OS 53.74235124 -38.47460428
OS 53.74235124 -38.48015164
OS 53.74142668 -38.48754812
OS 53.73957756 -38.49771828
OS 53.73680388 -38.50973756
OS 53.73218108 -38.5226814
OS 53.72663372 -38.53562524
OS 53.71923724 -38.54856908
OS 53.71831268 -38.5504182
OS 53.715539 -38.55411644
OS 53.70999164 -38.56058836
OS 53.70259516 -38.56798484
OS 53.69334956 -38.57630588
OS 53.68225484 -38.58555148
OS 53.669311 -38.59387252
OS 53.65359348 -38.60219356
OS 53.65451804 -38.60219356
OS 53.65636716 -38.60311812
OS 53.65914084 -38.60404268
OS 53.66283908 -38.60496724
OS 53.67300924 -38.60866548
OS 53.68595308 -38.61421284
OS 53.70074604 -38.62160932
OS 53.715539 -38.63085492
OS 53.7294074 -38.6428742
OS 53.74235124 -38.6567426
OS 53.7432758 -38.65859172
OS 53.74697404 -38.66413908
OS 53.7525214 -38.67338468
OS 53.75806876 -38.68540396
OS 53.76361612 -38.70019692
OS 53.76916348 -38.71776356
OS 53.77286172 -38.73810388
OS 53.77378628 -38.76029332
OS 53.77378628 -38.76121788
OS 53.77378628 -38.76399156
OS 53.77378628 -38.76861436
OS 53.77286172 -38.77416172
OS 53.77193716 -38.7815582
OS 53.77008804 -38.78987924
OS 53.76823892 -38.79912484
OS 53.7663898 -38.809295
OS 53.75899332 -38.83148444
OS 53.75344596 -38.84350372
OS 53.7478986 -38.85459844
OS 53.74050212 -38.86661772
OS 53.73218108 -38.878637
OS 53.72293548 -38.89065628
OS 53.71184076 -38.901751
OS 53.7109162 -38.90267556
OS 53.70906708 -38.90452468
OS 53.70536884 -38.90729836
OS 53.70074604 -38.9109966
OS 53.69519868 -38.9156194
OS 53.6878022 -38.9202422
OS 53.67948116 -38.92578956
OS 53.669311 -38.93041236
OS 53.65914084 -38.93595972
OS 53.64712156 -38.94150708
OS 53.63510228 -38.94612988
OS 53.62123388 -38.95075268
OS 53.60644092 -38.95445092
OS 53.5907234 -38.9572246
OS 53.57500588 -38.95907372
OS 53.55743924 -38.95999828
OS 53.5491182 -38.95999828
OS 53.54357084 -38.95907372
OS 53.53617436 -38.95814916
OS 53.52785332 -38.9572246
OS 53.51860772 -38.95537548
OS 53.50843756 -38.95352636
OS 53.48624812 -38.947979
OS 53.46313412 -38.9387334
OS 53.45111484 -38.93318604
OS 53.44002012 -38.92671412
OS 53.4289254 -38.91839308
OS 53.41783068 -38.91007204
OS 53.41690612 -38.90914748
OS 53.415057 -38.90729836
OS 53.41228332 -38.90452468
OS 53.40950964 -38.90082644
OS 53.40488684 -38.89620364
OS 53.40026404 -38.88973172
OS 53.39471668 -38.8832598
OS 53.38916932 -38.87493876
OS 53.38362196 -38.86569316
OS 53.3780746 -38.85644756
OS 53.36790444 -38.83425812
OS 53.3595834 -38.80837044
OS 53.35680972 -38.79450204
OS 53.3549606 -38.77970908
OS 53.4335482 -38.76953892
OS 53.4335482 -38.77046348
OS 53.43447276 -38.7723126
OS 53.43539732 -38.77601084
OS 53.43632188 -38.78063364
OS 53.43724644 -38.786181
OS 53.43909556 -38.79265292
OS 53.44371836 -38.80652132
OS 53.45019028 -38.8231634
OS 53.45851132 -38.83888092
OS 53.46775692 -38.85367388
OS 53.47885164 -38.86661772
OS 53.48070076 -38.86754228
OS 53.484399 -38.87124052
OS 53.49179548 -38.87586332
OS 53.50104108 -38.88048612
OS 53.5121358 -38.88603348
OS 53.5260042 -38.89065628
OS 53.54172172 -38.89435452
OS 53.5583638 -38.89527908
OS 53.56391116 -38.89527908
OS 53.5676094 -38.89435452
OS 53.57777956 -38.89342996
OS 53.5907234 -38.89065628
OS 53.60551636 -38.88603348
OS 53.62123388 -38.87956156
OS 53.6369514 -38.87031596
OS 53.65174436 -38.85737212
OS 53.65359348 -38.855523
OS 53.65821628 -38.84997564
OS 53.66376364 -38.8416546
OS 53.67116012 -38.83055988
OS 53.6785566 -38.81669148
OS 53.68410396 -38.80097396
OS 53.68872676 -38.78248276
OS 53.69057588 -38.76214244
OS 53.69057588 -38.76121788
OS 53.69057588 -38.75936876
OS 53.69057588 -38.75659508
OS 53.68965132 -38.75289684
OS 53.68872676 -38.74272668
OS 53.68595308 -38.7307074
OS 53.68225484 -38.71591444
OS 53.67578292 -38.70112148
OS 53.66653732 -38.68632852
OS 53.65451804 -38.67246012
OS 53.65266892 -38.670611
OS 53.64804612 -38.66691276
OS 53.64064964 -38.6613654
OS 53.63047948 -38.65489348
OS 53.61753564 -38.64842156
OS 53.60181812 -38.6428742
OS 53.58425148 -38.63917596
OS 53.56483572 -38.63732684
OS 53.55651468 -38.63732684
OS 53.55004276 -38.6382514
OS 53.54172172 -38.63917596
OS 53.53247612 -38.64102508
OS 53.5213814 -38.6428742
OS 53.50936212 -38.64564788
OS 53.51860772 -38.57630588
OS 53.52323052 -38.57630588
OS 53.52692876 -38.57723044
OS 53.53894804 -38.57723044
OS 53.5491182 -38.57538132
OS 53.56113748 -38.5735322
OS 53.57500588 -38.57075852
OS 53.5907234 -38.56613572
OS 53.60551636 -38.5596638
OS 53.62123388 -38.55134276
OS 53.62215844 -38.55134276
OS 53.623083 -38.5504182
OS 53.6277058 -38.54671996
OS 53.63417772 -38.54024804
OS 53.6415742 -38.531927
OS 53.64897068 -38.51990772
OS 53.6554426 -38.50603932
OS 53.6600654 -38.4903218
OS 53.66191452 -38.4810762
OS 53.66191452 -38.47090604
OS 53.66191452 -38.46998148
OS 53.66191452 -38.46905692
OS 53.66191452 -38.46350956
OS 53.6600654 -38.45611308
OS 53.65821628 -38.44594292
OS 53.65451804 -38.4348482
OS 53.64989524 -38.42282892
OS 53.64249876 -38.41080964
OS 53.6323286 -38.39971492
OS 53.63140404 -38.39879036
OS 53.62678124 -38.39509212
OS 53.62030932 -38.39046932
OS 53.61198828 -38.38492196
OS 53.60089356 -38.38029916
OS 53.58794972 -38.37567636
OS 53.57315676 -38.37197812
OS 53.55651468 -38.37105356
OS 53.5491182 -38.37105356
OS 53.54079716 -38.37290268
OS 53.52970244 -38.3747518
OS 53.51768316 -38.37845004
OS 53.50566388 -38.38307284
OS 53.49272004 -38.39046932
OS 53.48070076 -38.39971492
OS 53.4797762 -38.40063948
OS 53.47607796 -38.40526228
OS 53.4705306 -38.4117342
OS 53.46405868 -38.4209798
OS 53.45758676 -38.43299908
OS 53.45111484 -38.44779204
OS 53.44556748 -38.46535868
OS 53.44186924 -38.485699
OS 53.36328164 -38.4718306
OS 53.36328164 -38.47090604
OS 53.3642062 -38.46813236
OS 53.36513076 -38.46443412
OS 53.36605532 -38.45888676
OS 53.36790444 -38.45241484
OS 53.37067812 -38.44501836
OS 53.37622548 -38.42745172
OS 53.38547108 -38.4071114
OS 53.3965658 -38.38677108
OS 53.4104342 -38.36735532
OS 53.42800084 -38.34978868
OS 53.4289254 -38.34886412
OS 53.43077452 -38.34793956
OS 53.4335482 -38.34609044
OS 53.43724644 -38.34331676
OS 53.44186924 -38.33961852
OS 53.44834116 -38.33592028
OS 53.45481308 -38.33222204
OS 53.46313412 -38.32759924
OS 53.48162532 -38.32020276
OS 53.5028902 -38.31280628
OS 53.52785332 -38.30818348
OS 53.54079716 -38.30633436
OS 53.56391116 -38.30633436
OS 53.57408132 -38.30725892
OE
OB 54.07889108 -38.30725892 I
OS 54.09091036 -38.30910804
OS 54.10477876 -38.31188172
OS 54.11957172 -38.31557996
OS 54.13528924 -38.32020276
OS 54.1500822 -38.32759924
OS 54.15100676 -38.32759924
OS 54.15193132 -38.3285238
OS 54.15655412 -38.33129748
OS 54.1639506 -38.33592028
OS 54.1731962 -38.3423922
OS 54.18336636 -38.3516378
OS 54.19446108 -38.36180796
OS 54.20463124 -38.37382724
OS 54.2148014 -38.38769564
OS 54.21572596 -38.38954476
OS 54.2194242 -38.39416756
OS 54.22312244 -38.4024886
OS 54.22959436 -38.41450788
OS 54.23514172 -38.42837628
OS 54.2425382 -38.4440938
OS 54.24901012 -38.462585
OS 54.25455748 -38.48292532
OS 54.25455748 -38.48384988
OS 54.25548204 -38.485699
OS 54.2564066 -38.48847268
OS 54.25733116 -38.49309548
OS 54.25825572 -38.49864284
OS 54.25918028 -38.50511476
OS 54.2610294 -38.5134358
OS 54.26195396 -38.5226814
OS 54.26380308 -38.53285156
OS 54.26472764 -38.54394628
OS 54.2656522 -38.55689012
OS 54.26750132 -38.56983396
OS 54.26842588 -38.58462692
OS 54.26842588 -38.59941988
OS 54.26935044 -38.61606196
OS 54.26935044 -38.6336286
OS 54.26935044 -38.63455316
OS 54.26935044 -38.6382514
OS 54.26935044 -38.64472332
OS 54.26935044 -38.6521198
OS 54.26842588 -38.66228996
OS 54.26842588 -38.67338468
OS 54.26750132 -38.68540396
OS 54.26657676 -38.6983478
OS 54.26380308 -38.72793372
OS 54.25918028 -38.7584442
OS 54.25363292 -38.78803012
OS 54.24993468 -38.80189852
OS 54.24531188 -38.81576692
OS 54.24531188 -38.81669148
OS 54.24438732 -38.8185406
OS 54.2425382 -38.82223884
OS 54.24068908 -38.82686164
OS 54.23883996 -38.83333356
OS 54.23514172 -38.83980548
OS 54.22774524 -38.855523
OS 54.21849964 -38.87216508
OS 54.20648036 -38.89065628
OS 54.19261196 -38.90729836
OS 54.17596988 -38.92301588
OS 54.17504532 -38.92301588
OS 54.17412076 -38.924865
OS 54.17134708 -38.92671412
OS 54.16764884 -38.92856324
OS 54.16302604 -38.93133692
OS 54.15840324 -38.93503516
OS 54.14453484 -38.94150708
OS 54.12789276 -38.947979
OS 54.108477 -38.95445092
OS 54.085363 -38.95814916
OS 54.06039988 -38.95999828
OS 54.05115428 -38.95999828
OS 54.04468236 -38.95907372
OS 54.03728588 -38.95814916
OS 54.02804028 -38.95630004
OS 54.01787012 -38.95445092
OS 54.0067754 -38.95167724
OS 53.99568068 -38.947979
OS 53.9836614 -38.94428076
OS 53.97164212 -38.9387334
OS 53.95962284 -38.93226148
OS 53.94760356 -38.924865
OS 53.93558428 -38.9156194
OS 53.92448956 -38.90544924
OS 53.9143194 -38.89435452
OS 53.91339484 -38.89342996
OS 53.91154572 -38.89065628
OS 53.90877204 -38.88603348
OS 53.90414924 -38.878637
OS 53.89952644 -38.87031596
OS 53.89490364 -38.85922124
OS 53.88843172 -38.8462774
OS 53.88288436 -38.83148444
OS 53.877337 -38.81484236
OS 53.87178964 -38.7954266
OS 53.86624228 -38.77416172
OS 53.86161948 -38.75012316
OS 53.85699668 -38.72423548
OS 53.854223 -38.69649868
OS 53.85237388 -38.6659882
OS 53.85144932 -38.6336286
OS 53.85144932 -38.63270404
OS 53.85144932 -38.6290058
OS 53.85144932 -38.62253388
OS 53.85144932 -38.6151374
OS 53.85237388 -38.60496724
OS 53.85237388 -38.59387252
OS 53.85329844 -38.58185324
OS 53.854223 -38.56798484
OS 53.85699668 -38.53932348
OS 53.86161948 -38.508813
OS 53.86716684 -38.47830252
OS 53.87086508 -38.46443412
OS 53.87456332 -38.45056572
OS 53.87456332 -38.44964116
OS 53.87548788 -38.44779204
OS 53.877337 -38.4440938
OS 53.87918612 -38.439471
OS 53.88103524 -38.43299908
OS 53.88473348 -38.42652716
OS 53.89212996 -38.41080964
OS 53.90137556 -38.39416756
OS 53.91339484 -38.37660092
OS 53.92726324 -38.35903428
OS 53.94390532 -38.34424132
OS 53.94482988 -38.34424132
OS 53.94575444 -38.3423922
OS 53.94852812 -38.34054308
OS 53.95222636 -38.33869396
OS 53.95684916 -38.33499572
OS 53.96239652 -38.33222204
OS 53.97626492 -38.32482556
OS 53.992907 -38.31835364
OS 54.01232276 -38.31188172
OS 54.03543676 -38.30818348
OS 54.06039988 -38.30633436
OS 54.06872092 -38.30633436
OS 54.07889108 -38.30725892
OE
OB 53.23846604 -38.94890356 I
OS 53.14878372 -38.94890356
OS 53.14878372 -38.85922124
OS 53.23846604 -38.85922124
OS 53.23846604 -38.94890356
OE
OB 53.00177868 -38.39231844 I
OS 52.74567556 -38.39231844
OS 52.71146684 -38.56521116
OS 52.7123914 -38.5642866
OS 52.71424052 -38.56336204
OS 52.7170142 -38.56151292
OS 52.721637 -38.55873924
OS 52.72718436 -38.55596556
OS 52.73365628 -38.55226732
OS 52.74844924 -38.54487084
OS 52.76694044 -38.53747436
OS 52.78728076 -38.53100244
OS 52.8094702 -38.52637964
OS 52.82056492 -38.52453052
OS 52.84090524 -38.52453052
OS 52.8464526 -38.52545508
OS 52.85384908 -38.52637964
OS 52.86217012 -38.5273042
OS 52.87141572 -38.52915332
OS 52.88158588 -38.531927
OS 52.90377532 -38.53839892
OS 52.9157946 -38.54302172
OS 52.92781388 -38.54949364
OS 52.93983316 -38.55596556
OS 52.95185244 -38.56336204
OS 52.96294716 -38.57260764
OS 52.97404188 -38.5827778
OS 52.97496644 -38.58370236
OS 52.97681556 -38.58555148
OS 52.97958924 -38.58832516
OS 52.98328748 -38.59294796
OS 52.98791028 -38.59941988
OS 52.99253308 -38.6058918
OS 52.99808044 -38.61421284
OS 53.0036278 -38.62345844
OS 53.0082506 -38.6336286
OS 53.01379796 -38.64472332
OS 53.01842076 -38.65766716
OS 53.02304356 -38.670611
OS 53.0267418 -38.6844794
OS 53.02951548 -38.70019692
OS 53.0313646 -38.71591444
OS 53.03228916 -38.73255652
OS 53.03228916 -38.73348108
OS 53.03228916 -38.73625476
OS 53.03228916 -38.74087756
OS 53.0313646 -38.74734948
OS 53.03044004 -38.75474596
OS 53.02951548 -38.763067
OS 53.02766636 -38.77323716
OS 53.02581724 -38.78340732
OS 53.02026988 -38.80744588
OS 53.01102428 -38.832409
OS 53.00547692 -38.84535284
OS 52.99808044 -38.85737212
OS 52.99068396 -38.87031596
OS 52.98143836 -38.88233524
OS 52.9805138 -38.8832598
OS 52.97866468 -38.88603348
OS 52.97496644 -38.88973172
OS 52.97034364 -38.89435452
OS 52.96387172 -38.89990188
OS 52.95647524 -38.90729836
OS 52.94722964 -38.91377028
OS 52.93705948 -38.92116676
OS 52.92596476 -38.92856324
OS 52.91302092 -38.93503516
OS 52.89915252 -38.94150708
OS 52.88435956 -38.947979
OS 52.86864204 -38.9526018
OS 52.8510754 -38.95630004
OS 52.8325842 -38.95907372
OS 52.81316844 -38.95999828
OS 52.8048474 -38.95999828
OS 52.79837548 -38.95907372
OS 52.790979 -38.95814916
OS 52.78265796 -38.9572246
OS 52.7724878 -38.95630004
OS 52.76231764 -38.95352636
OS 52.73920364 -38.947979
OS 52.71608964 -38.93965796
OS 52.70407036 -38.9341106
OS 52.69205108 -38.92763868
OS 52.68095636 -38.9202422
OS 52.66986164 -38.91192116
OS 52.66893708 -38.9109966
OS 52.66708796 -38.91007204
OS 52.66523884 -38.9063738
OS 52.6615406 -38.90267556
OS 52.6569178 -38.89805276
OS 52.652295 -38.8925054
OS 52.64674764 -38.88510892
OS 52.64212484 -38.87678788
OS 52.63657748 -38.86846684
OS 52.63103012 -38.85829668
OS 52.62085996 -38.83610724
OS 52.61253892 -38.81021956
OS 52.60976524 -38.79635116
OS 52.60791612 -38.7815582
OS 52.69020196 -38.77508628
OS 52.69020196 -38.77601084
OS 52.69020196 -38.77785996
OS 52.69112652 -38.78063364
OS 52.69205108 -38.78525644
OS 52.69482476 -38.7954266
OS 52.698523 -38.809295
OS 52.70407036 -38.8231634
OS 52.71146684 -38.83888092
OS 52.72071244 -38.85274932
OS 52.73180716 -38.86569316
OS 52.73365628 -38.86661772
OS 52.73735452 -38.87031596
OS 52.744751 -38.87493876
OS 52.75492116 -38.88048612
OS 52.76601588 -38.88603348
OS 52.77988428 -38.89065628
OS 52.7956018 -38.89435452
OS 52.81316844 -38.89527908
OS 52.8187158 -38.89527908
OS 52.82241404 -38.89435452
OS 52.83350876 -38.89342996
OS 52.8464526 -38.88973172
OS 52.86217012 -38.88510892
OS 52.87788764 -38.87771244
OS 52.89452972 -38.86661772
OS 52.9019262 -38.8601458
OS 52.90932268 -38.85274932
OS 52.91024724 -38.85182476
OS 52.9111718 -38.8509002
OS 52.91302092 -38.84812652
OS 52.9157946 -38.84535284
OS 52.92226652 -38.83518268
OS 52.929663 -38.82223884
OS 52.93613492 -38.80652132
OS 52.94260684 -38.78710556
OS 52.94722964 -38.76399156
OS 52.94907876 -38.75197228
OS 52.94907876 -38.73902844
OS 52.94907876 -38.73810388
OS 52.94907876 -38.73625476
OS 52.94907876 -38.73255652
OS 52.9481542 -38.72793372
OS 52.9481542 -38.72238636
OS 52.94722964 -38.71591444
OS 52.94445596 -38.70112148
OS 52.93983316 -38.68355484
OS 52.93336124 -38.6659882
OS 52.92411564 -38.64934612
OS 52.9111718 -38.6336286
OS 52.9111718 -38.63270404
OS 52.90932268 -38.63177948
OS 52.90469988 -38.62715668
OS 52.89637884 -38.62068476
OS 52.88528412 -38.61328828
OS 52.87049116 -38.60681636
OS 52.85384908 -38.60034444
OS 52.83443332 -38.59572164
OS 52.8233386 -38.59387252
OS 52.80577196 -38.59387252
OS 52.79837548 -38.59479708
OS 52.78912988 -38.59572164
OS 52.77803516 -38.59849532
OS 52.76694044 -38.601269
OS 52.75492116 -38.6058918
OS 52.74290188 -38.61143916
OS 52.74197732 -38.61236372
OS 52.73827908 -38.61421284
OS 52.73273172 -38.61883564
OS 52.72533524 -38.62345844
OS 52.71793876 -38.62993036
OS 52.71054228 -38.6382514
OS 52.70222124 -38.64657244
OS 52.69574932 -38.6567426
OS 52.62178452 -38.64657244
OS 52.68373004 -38.31742908
OS 53.00177868 -38.31742908
OS 53.00177868 -38.39231844
OE
OB 53.23846604 -38.57445676 I
OS 53.14878372 -38.57445676
OS 53.14878372 -38.48477444
OS 53.23846604 -38.48477444
OS 53.23846604 -38.57445676
OE
OB 54.48199924 -38.57445676 I
OS 54.39231692 -38.57445676
OS 54.39231692 -38.48477444
OS 54.48199924 -38.48477444
OS 54.48199924 -38.57445676
OE
OB 56.14990548 -38.3100326 I
OS 56.165623 -38.31095716
OS 56.18226508 -38.31188172
OS 56.1979826 -38.31373084
OS 56.211851 -38.31557996
OS 56.21370012 -38.31557996
OS 56.22017204 -38.31742908
OS 56.22849308 -38.3192782
OS 56.2395878 -38.32205188
OS 56.25160708 -38.32667468
OS 56.26455092 -38.33222204
OS 56.27841932 -38.33869396
OS 56.2904386 -38.34609044
OS 56.29228772 -38.347015
OS 56.29598596 -38.34978868
OS 56.30153332 -38.35533604
OS 56.3089298 -38.36180796
OS 56.31725084 -38.370129
OS 56.32557188 -38.38122372
OS 56.33481748 -38.393243
OS 56.34221396 -38.4071114
OS 56.34313852 -38.40896052
OS 56.34498764 -38.41358332
OS 56.34868588 -38.42190436
OS 56.35238412 -38.43299908
OS 56.3551578 -38.44594292
OS 56.35885604 -38.46073588
OS 56.36070516 -38.47737796
OS 56.36162972 -38.4949446
OS 56.36162972 -38.49586916
OS 56.36162972 -38.49864284
OS 56.36162972 -38.50234108
OS 56.36070516 -38.508813
OS 56.3597806 -38.51528492
OS 56.35885604 -38.52360596
OS 56.35700692 -38.53285156
OS 56.3551578 -38.54302172
OS 56.34868588 -38.5642866
OS 56.34498764 -38.57538132
OS 56.33944028 -38.5874006
OS 56.33296836 -38.59941988
OS 56.32649644 -38.6105146
OS 56.3181754 -38.62160932
OS 56.3089298 -38.63270404
OS 56.30800524 -38.6336286
OS 56.30615612 -38.63547772
OS 56.30338244 -38.6382514
OS 56.29875964 -38.64102508
OS 56.29321228 -38.64564788
OS 56.2858158 -38.65027068
OS 56.2765702 -38.65581804
OS 56.26640004 -38.66044084
OS 56.25438076 -38.6659882
OS 56.24051236 -38.67153556
OS 56.2257194 -38.67615836
OS 56.20815276 -38.6798566
OS 56.18966156 -38.68355484
OS 56.16932124 -38.68632852
OS 56.14620724 -38.68817764
OS 56.12216868 -38.6891022
OS 55.95852156 -38.6891022
OS 55.95852156 -38.94890356
OS 55.87346204 -38.94890356
OS 55.87346204 -38.30910804
OS 56.13603708 -38.30910804
OS 56.14990548 -38.3100326
OE
OB 57.07723916 -38.94890356 I
OS 56.99587788 -38.94890356
OS 56.99587788 -38.41358332
OS 56.80911676 -38.94890356
OS 56.73330284 -38.94890356
OS 56.54839084 -38.40433772
OS 56.54839084 -38.94890356
OS 56.46702956 -38.94890356
OS 56.46702956 -38.30910804
OS 56.59369428 -38.30910804
OS 56.74532212 -38.763067
OS 56.74532212 -38.76399156
OS 56.74624668 -38.76584068
OS 56.74717124 -38.76861436
OS 56.74902036 -38.77323716
OS 56.7527186 -38.78433188
OS 56.7573414 -38.79820028
OS 56.7619642 -38.8139178
OS 56.76751156 -38.82963532
OS 56.77213436 -38.84442828
OS 56.7758326 -38.85737212
OS 56.77675716 -38.855523
OS 56.77768172 -38.8509002
OS 56.7804554 -38.84257916
OS 56.78415364 -38.83148444
OS 56.78877644 -38.81669148
OS 56.79524836 -38.79912484
OS 56.80172028 -38.77878452
OS 56.81004132 -38.75474596
OS 56.96351828 -38.30910804
OS 57.07723916 -38.30910804
OS 57.07723916 -38.94890356
OE
OB 55.3150278 -38.30725892 I
OS 55.32704708 -38.30910804
OS 55.34184004 -38.31188172
OS 55.35848212 -38.31650452
OS 55.3751242 -38.32205188
OS 55.39176628 -38.32944836
OS 55.39269084 -38.32944836
OS 55.3936154 -38.33037292
OS 55.39916276 -38.3331466
OS 55.4074838 -38.33869396
OS 55.4167294 -38.34516588
OS 55.42782412 -38.35441148
OS 55.43891884 -38.36458164
OS 55.45001356 -38.37660092
OS 55.45925916 -38.39046932
OS 55.46018372 -38.39231844
OS 55.4629574 -38.39694124
OS 55.46665564 -38.40526228
OS 55.47127844 -38.41543244
OS 55.47590124 -38.42745172
OS 55.47959948 -38.44132012
OS 55.48237316 -38.45703764
OS 55.48329772 -38.47275516
OS 55.48329772 -38.47460428
OS 55.48329772 -38.48015164
OS 55.48237316 -38.48754812
OS 55.48052404 -38.49771828
OS 55.47775036 -38.50973756
OS 55.47312756 -38.5226814
OS 55.4675802 -38.53562524
OS 55.46018372 -38.54856908
OS 55.45925916 -38.5504182
OS 55.45648548 -38.55411644
OS 55.45093812 -38.56058836
OS 55.44354164 -38.56798484
OS 55.43429604 -38.57630588
OS 55.42320132 -38.58555148
OS 55.41025748 -38.59387252
OS 55.39453996 -38.60219356
OS 55.39546452 -38.60219356
OS 55.39731364 -38.60311812
OS 55.40008732 -38.60404268
OS 55.40378556 -38.60496724
OS 55.41395572 -38.60866548
OS 55.42689956 -38.61421284
OS 55.44169252 -38.62160932
OS 55.45648548 -38.63085492
OS 55.47035388 -38.6428742
OS 55.48329772 -38.6567426
OS 55.48422228 -38.65859172
OS 55.48792052 -38.66413908
OS 55.49346788 -38.67338468
OS 55.49901524 -38.68540396
OS 55.5045626 -38.70019692
OS 55.51010996 -38.71776356
OS 55.5138082 -38.73810388
OS 55.51473276 -38.76029332
OS 55.51473276 -38.76121788
OS 55.51473276 -38.76399156
OS 55.51473276 -38.76861436
OS 55.5138082 -38.77416172
OS 55.51288364 -38.7815582
OS 55.51103452 -38.78987924
OS 55.5091854 -38.79912484
OS 55.50733628 -38.809295
OS 55.4999398 -38.83148444
OS 55.49439244 -38.84350372
OS 55.48884508 -38.85459844
OS 55.4814486 -38.86661772
OS 55.47312756 -38.878637
OS 55.46388196 -38.89065628
OS 55.45278724 -38.901751
OS 55.45186268 -38.90267556
OS 55.45001356 -38.90452468
OS 55.44631532 -38.90729836
OS 55.44169252 -38.9109966
OS 55.43614516 -38.9156194
OS 55.42874868 -38.9202422
OS 55.42042764 -38.92578956
OS 55.41025748 -38.93041236
OS 55.40008732 -38.93595972
OS 55.38806804 -38.94150708
OS 55.37604876 -38.94612988
OS 55.36218036 -38.95075268
OS 55.3473874 -38.95445092
OS 55.33166988 -38.9572246
OS 55.31595236 -38.95907372
OS 55.29838572 -38.95999828
OS 55.29006468 -38.95999828
OS 55.28451732 -38.95907372
OS 55.27712084 -38.95814916
OS 55.2687998 -38.9572246
OS 55.2595542 -38.95537548
OS 55.24938404 -38.95352636
OS 55.2271946 -38.947979
OS 55.2040806 -38.9387334
OS 55.19206132 -38.93318604
OS 55.1809666 -38.92671412
OS 55.16987188 -38.91839308
OS 55.15877716 -38.91007204
OS 55.1578526 -38.90914748
OS 55.15600348 -38.90729836
OS 55.1532298 -38.90452468
OS 55.15045612 -38.90082644
OS 55.14583332 -38.89620364
OS 55.14121052 -38.88973172
OS 55.13566316 -38.8832598
OS 55.1301158 -38.87493876
OS 55.12456844 -38.86569316
OS 55.11902108 -38.85644756
OS 55.10885092 -38.83425812
OS 55.10052988 -38.80837044
OS 55.0977562 -38.79450204
OS 55.09590708 -38.77970908
OS 55.17449468 -38.76953892
OS 55.17449468 -38.77046348
OS 55.17541924 -38.7723126
OS 55.1763438 -38.77601084
OS 55.17726836 -38.78063364
OS 55.17819292 -38.786181
OS 55.18004204 -38.79265292
OS 55.18466484 -38.80652132
OS 55.19113676 -38.8231634
OS 55.1994578 -38.83888092
OS 55.2087034 -38.85367388
OS 55.21979812 -38.86661772
OS 55.22164724 -38.86754228
OS 55.22534548 -38.87124052
OS 55.23274196 -38.87586332
OS 55.24198756 -38.88048612
OS 55.25308228 -38.88603348
OS 55.26695068 -38.89065628
OS 55.2826682 -38.89435452
OS 55.29931028 -38.89527908
OS 55.30485764 -38.89527908
OS 55.30855588 -38.89435452
OS 55.31872604 -38.89342996
OS 55.33166988 -38.89065628
OS 55.34646284 -38.88603348
OS 55.36218036 -38.87956156
OS 55.37789788 -38.87031596
OS 55.39269084 -38.85737212
OS 55.39453996 -38.855523
OS 55.39916276 -38.84997564
OS 55.40471012 -38.8416546
OS 55.4121066 -38.83055988
OS 55.41950308 -38.81669148
OS 55.42505044 -38.80097396
OS 55.42967324 -38.78248276
OS 55.43152236 -38.76214244
OS 55.43152236 -38.76121788
OS 55.43152236 -38.75936876
OS 55.43152236 -38.75659508
OS 55.4305978 -38.75289684
OS 55.42967324 -38.74272668
OS 55.42689956 -38.7307074
OS 55.42320132 -38.71591444
OS 55.4167294 -38.70112148
OS 55.4074838 -38.68632852
OS 55.39546452 -38.67246012
OS 55.3936154 -38.670611
OS 55.3889926 -38.66691276
OS 55.38159612 -38.6613654
OS 55.37142596 -38.65489348
OS 55.35848212 -38.64842156
OS 55.3427646 -38.6428742
OS 55.32519796 -38.63917596
OS 55.3057822 -38.63732684
OS 55.29746116 -38.63732684
OS 55.29098924 -38.6382514
OS 55.2826682 -38.63917596
OS 55.2734226 -38.64102508
OS 55.26232788 -38.6428742
OS 55.2503086 -38.64564788
OS 55.2595542 -38.57630588
OS 55.264177 -38.57630588
OS 55.26787524 -38.57723044
OS 55.27989452 -38.57723044
OS 55.29006468 -38.57538132
OS 55.30208396 -38.5735322
OS 55.31595236 -38.57075852
OS 55.33166988 -38.56613572
OS 55.34646284 -38.5596638
OS 55.36218036 -38.55134276
OS 55.36310492 -38.55134276
OS 55.36402948 -38.5504182
OS 55.36865228 -38.54671996
OS 55.3751242 -38.54024804
OS 55.38252068 -38.531927
OS 55.38991716 -38.51990772
OS 55.39638908 -38.50603932
OS 55.40101188 -38.4903218
OS 55.402861 -38.4810762
OS 55.402861 -38.47090604
OS 55.402861 -38.46998148
OS 55.402861 -38.46905692
OS 55.402861 -38.46350956
OS 55.40101188 -38.45611308
OS 55.39916276 -38.44594292
OS 55.39546452 -38.4348482
OS 55.39084172 -38.42282892
OS 55.38344524 -38.41080964
OS 55.37327508 -38.39971492
OS 55.37235052 -38.39879036
OS 55.36772772 -38.39509212
OS 55.3612558 -38.39046932
OS 55.35293476 -38.38492196
OS 55.34184004 -38.38029916
OS 55.3288962 -38.37567636
OS 55.31410324 -38.37197812
OS 55.29746116 -38.37105356
OS 55.29006468 -38.37105356
OS 55.28174364 -38.37290268
OS 55.27064892 -38.3747518
OS 55.25862964 -38.37845004
OS 55.24661036 -38.38307284
OS 55.23366652 -38.39046932
OS 55.22164724 -38.39971492
OS 55.22072268 -38.40063948
OS 55.21702444 -38.40526228
OS 55.21147708 -38.4117342
OS 55.20500516 -38.4209798
OS 55.19853324 -38.43299908
OS 55.19206132 -38.44779204
OS 55.18651396 -38.46535868
OS 55.18281572 -38.485699
OS 55.10422812 -38.4718306
OS 55.10422812 -38.47090604
OS 55.10515268 -38.46813236
OS 55.10607724 -38.46443412
OS 55.1070018 -38.45888676
OS 55.10885092 -38.45241484
OS 55.1116246 -38.44501836
OS 55.11717196 -38.42745172
OS 55.12641756 -38.4071114
OS 55.13751228 -38.38677108
OS 55.15138068 -38.36735532
OS 55.16894732 -38.34978868
OS 55.16987188 -38.34886412
OS 55.171721 -38.34793956
OS 55.17449468 -38.34609044
OS 55.17819292 -38.34331676
OS 55.18281572 -38.33961852
OS 55.18928764 -38.33592028
OS 55.19575956 -38.33222204
OS 55.2040806 -38.32759924
OS 55.2225718 -38.32020276
OS 55.24383668 -38.31280628
OS 55.2687998 -38.30818348
OS 55.28174364 -38.30633436
OS 55.30485764 -38.30633436
OS 55.3150278 -38.30725892
OE
OB 54.48199924 -38.94890356 I
OS 54.39231692 -38.94890356
OS 54.39231692 -38.85922124
OS 54.48199924 -38.85922124
OS 54.48199924 -38.94890356
OE
OB 54.9914318 -38.39231844 I
OS 54.73532868 -38.39231844
OS 54.70111996 -38.56521116
OS 54.70204452 -38.5642866
OS 54.70389364 -38.56336204
OS 54.70666732 -38.56151292
OS 54.71129012 -38.55873924
OS 54.71683748 -38.55596556
OS 54.7233094 -38.55226732
OS 54.73810236 -38.54487084
OS 54.75659356 -38.53747436
OS 54.77693388 -38.53100244
OS 54.79912332 -38.52637964
OS 54.81021804 -38.52453052
OS 54.83055836 -38.52453052
OS 54.83610572 -38.52545508
OS 54.8435022 -38.52637964
OS 54.85182324 -38.5273042
OS 54.86106884 -38.52915332
OS 54.871239 -38.531927
OS 54.89342844 -38.53839892
OS 54.90544772 -38.54302172
OS 54.917467 -38.54949364
OS 54.92948628 -38.55596556
OS 54.94150556 -38.56336204
OS 54.95260028 -38.57260764
OS 54.963695 -38.5827778
OS 54.96461956 -38.58370236
OS 54.96646868 -38.58555148
OS 54.96924236 -38.58832516
OS 54.9729406 -38.59294796
OS 54.9775634 -38.59941988
OS 54.9821862 -38.6058918
OS 54.98773356 -38.61421284
OS 54.99328092 -38.62345844
OS 54.99790372 -38.6336286
OS 55.00345108 -38.64472332
OS 55.00807388 -38.65766716
OS 55.01269668 -38.670611
OS 55.01639492 -38.6844794
OS 55.0191686 -38.70019692
OS 55.02101772 -38.71591444
OS 55.02194228 -38.73255652
OS 55.02194228 -38.73348108
OS 55.02194228 -38.73625476
OS 55.02194228 -38.74087756
OS 55.02101772 -38.74734948
OS 55.02009316 -38.75474596
OS 55.0191686 -38.763067
OS 55.01731948 -38.77323716
OS 55.01547036 -38.78340732
OS 55.009923 -38.80744588
OS 55.0006774 -38.832409
OS 54.99513004 -38.84535284
OS 54.98773356 -38.85737212
OS 54.98033708 -38.87031596
OS 54.97109148 -38.88233524
OS 54.97016692 -38.8832598
OS 54.9683178 -38.88603348
OS 54.96461956 -38.88973172
OS 54.95999676 -38.89435452
OS 54.95352484 -38.89990188
OS 54.94612836 -38.90729836
OS 54.93688276 -38.91377028
OS 54.9267126 -38.92116676
OS 54.91561788 -38.92856324
OS 54.90267404 -38.93503516
OS 54.88880564 -38.94150708
OS 54.87401268 -38.947979
OS 54.85829516 -38.9526018
OS 54.84072852 -38.95630004
OS 54.82223732 -38.95907372
OS 54.80282156 -38.95999828
OS 54.79450052 -38.95999828
OS 54.7880286 -38.95907372
OS 54.78063212 -38.95814916
OS 54.77231108 -38.9572246
OS 54.76214092 -38.95630004
OS 54.75197076 -38.95352636
OS 54.72885676 -38.947979
OS 54.70574276 -38.93965796
OS 54.69372348 -38.9341106
OS 54.6817042 -38.92763868
OS 54.67060948 -38.9202422
OS 54.65951476 -38.91192116
OS 54.6585902 -38.9109966
OS 54.65674108 -38.91007204
OS 54.65489196 -38.9063738
OS 54.65119372 -38.90267556
OS 54.64657092 -38.89805276
OS 54.64194812 -38.8925054
OS 54.63640076 -38.88510892
OS 54.63177796 -38.87678788
OS 54.6262306 -38.86846684
OS 54.62068324 -38.85829668
OS 54.61051308 -38.83610724
OS 54.60219204 -38.81021956
OS 54.59941836 -38.79635116
OS 54.59756924 -38.7815582
OS 54.67985508 -38.77508628
OS 54.67985508 -38.77601084
OS 54.67985508 -38.77785996
OS 54.68077964 -38.78063364
OS 54.6817042 -38.78525644
OS 54.68447788 -38.7954266
OS 54.68817612 -38.809295
OS 54.69372348 -38.8231634
OS 54.70111996 -38.83888092
OS 54.71036556 -38.85274932
OS 54.72146028 -38.86569316
OS 54.7233094 -38.86661772
OS 54.72700764 -38.87031596
OS 54.73440412 -38.87493876
OS 54.74457428 -38.88048612
OS 54.755669 -38.88603348
OS 54.7695374 -38.89065628
OS 54.78525492 -38.89435452
OS 54.80282156 -38.89527908
OS 54.80836892 -38.89527908
OS 54.81206716 -38.89435452
OS 54.82316188 -38.89342996
OS 54.83610572 -38.88973172
OS 54.85182324 -38.88510892
OS 54.86754076 -38.87771244
OS 54.88418284 -38.86661772
OS 54.89157932 -38.8601458
OS 54.8989758 -38.85274932
OS 54.89990036 -38.85182476
OS 54.90082492 -38.8509002
OS 54.90267404 -38.84812652
OS 54.90544772 -38.84535284
OS 54.91191964 -38.83518268
OS 54.91931612 -38.82223884
OS 54.92578804 -38.80652132
OS 54.93225996 -38.78710556
OS 54.93688276 -38.76399156
OS 54.93873188 -38.75197228
OS 54.93873188 -38.73902844
OS 54.93873188 -38.73810388
OS 54.93873188 -38.73625476
OS 54.93873188 -38.73255652
OS 54.93780732 -38.72793372
OS 54.93780732 -38.72238636
OS 54.93688276 -38.71591444
OS 54.93410908 -38.70112148
OS 54.92948628 -38.68355484
OS 54.92301436 -38.6659882
OS 54.91376876 -38.64934612
OS 54.90082492 -38.6336286
OS 54.90082492 -38.63270404
OS 54.8989758 -38.63177948
OS 54.894353 -38.62715668
OS 54.88603196 -38.62068476
OS 54.87493724 -38.61328828
OS 54.86014428 -38.60681636
OS 54.8435022 -38.60034444
OS 54.82408644 -38.59572164
OS 54.81299172 -38.59387252
OS 54.79542508 -38.59387252
OS 54.7880286 -38.59479708
OS 54.778783 -38.59572164
OS 54.76768828 -38.59849532
OS 54.75659356 -38.601269
OS 54.74457428 -38.6058918
OS 54.732555 -38.61143916
OS 54.73163044 -38.61236372
OS 54.7279322 -38.61421284
OS 54.72238484 -38.61883564
OS 54.71498836 -38.62345844
OS 54.70759188 -38.62993036
OS 54.7001954 -38.6382514
OS 54.69187436 -38.64657244
OS 54.68540244 -38.6567426
OS 54.61143764 -38.64657244
OS 54.67338316 -38.31742908
OS 54.9914318 -38.31742908
OS 54.9914318 -38.39231844
OE
OB 49.95350436 -38.72331092 I
OS 50.040413 -38.72331092
OS 50.040413 -38.7954266
OS 49.95350436 -38.7954266
OS 49.95350436 -38.94890356
OS 49.87491676 -38.94890356
OS 49.87491676 -38.7954266
OS 49.5966242 -38.7954266
OS 49.5966242 -38.72331092
OS 49.88970972 -38.30910804
OS 49.95350436 -38.30910804
OS 49.95350436 -38.72331092
OE
OB 50.1467374 -38.95999828 I
OS 50.08386732 -38.95999828
OS 50.26970388 -38.29801332
OS 50.33257396 -38.29801332
OS 50.1467374 -38.95999828
OE
OB 49.35346492 -38.30725892 I
OS 49.3608614 -38.30818348
OS 49.370107 -38.30910804
OS 49.38027716 -38.31095716
OS 49.39044732 -38.31280628
OS 49.41448588 -38.3192782
OS 49.43852444 -38.3285238
OS 49.45054372 -38.33407116
OS 49.462563 -38.34054308
OS 49.47365772 -38.34886412
OS 49.48382788 -38.35810972
OS 49.48475244 -38.35903428
OS 49.48660156 -38.35995884
OS 49.48845068 -38.36365708
OS 49.49214892 -38.36735532
OS 49.49677172 -38.37197812
OS 49.50139452 -38.37845004
OS 49.50601732 -38.38492196
OS 49.51156468 -38.393243
OS 49.52081028 -38.41080964
OS 49.53005588 -38.43299908
OS 49.53375412 -38.4440938
OS 49.53560324 -38.45703764
OS 49.53745236 -38.46998148
OS 49.53837692 -38.48384988
OS 49.53837692 -38.485699
OS 49.53837692 -38.4903218
OS 49.53745236 -38.49771828
OS 49.5365278 -38.50788844
OS 49.53467868 -38.51898316
OS 49.53098044 -38.531927
OS 49.5272822 -38.5457954
OS 49.52173484 -38.5596638
OS 49.52081028 -38.56151292
OS 49.51896116 -38.56613572
OS 49.51526292 -38.5735322
OS 49.50971556 -38.58370236
OS 49.50231908 -38.59479708
OS 49.49307348 -38.60866548
OS 49.48197876 -38.62253388
OS 49.46903492 -38.6382514
OS 49.4671858 -38.64010052
OS 49.462563 -38.64564788
OS 49.4579402 -38.65027068
OS 49.4533174 -38.65489348
OS 49.44777004 -38.66044084
OS 49.44037356 -38.66783732
OS 49.43297708 -38.6752338
OS 49.42373148 -38.68355484
OS 49.41448588 -38.69280044
OS 49.40339116 -38.7029706
OS 49.39137188 -38.71314076
OS 49.37842804 -38.72516004
OS 49.36363508 -38.73717932
OS 49.34884212 -38.75012316
OS 49.34791756 -38.75104772
OS 49.34606844 -38.75289684
OS 49.3423702 -38.75567052
OS 49.3377474 -38.75936876
OS 49.33220004 -38.76491612
OS 49.32572812 -38.77046348
OS 49.31093516 -38.78248276
OS 49.29521764 -38.79635116
OS 49.28042468 -38.81021956
OS 49.26748084 -38.82223884
OS 49.26193348 -38.82686164
OS 49.25731068 -38.83148444
OS 49.25638612 -38.832409
OS 49.25361244 -38.83518268
OS 49.2499142 -38.83888092
OS 49.2452914 -38.84442828
OS 49.2406686 -38.8509002
OS 49.23512124 -38.85737212
OS 49.22402652 -38.87308964
OS 49.53930148 -38.87308964
OS 49.53930148 -38.94890356
OS 49.11492844 -38.94890356
OS 49.11492844 -38.947979
OS 49.11492844 -38.94428076
OS 49.11492844 -38.9387334
OS 49.115853 -38.93133692
OS 49.11677756 -38.92301588
OS 49.11862668 -38.91377028
OS 49.1204758 -38.90452468
OS 49.12417404 -38.89435452
OS 49.12417404 -38.89342996
OS 49.1250986 -38.8925054
OS 49.12694772 -38.88695804
OS 49.13064596 -38.878637
OS 49.13619332 -38.86754228
OS 49.1435898 -38.85459844
OS 49.1528354 -38.83980548
OS 49.16300556 -38.82501252
OS 49.1759494 -38.809295
OS 49.1759494 -38.80837044
OS 49.17779852 -38.80744588
OS 49.18242132 -38.80189852
OS 49.19074236 -38.79357748
OS 49.20276164 -38.7815582
OS 49.21663004 -38.7676898
OS 49.23419668 -38.75104772
OS 49.25546156 -38.73255652
OS 49.27857556 -38.71314076
OS 49.27950012 -38.7122162
OS 49.28319836 -38.70944252
OS 49.28874572 -38.70481972
OS 49.29521764 -38.69927236
OS 49.30353868 -38.69187588
OS 49.31370884 -38.68355484
OS 49.323879 -38.67430924
OS 49.33589828 -38.66413908
OS 49.35901228 -38.64194964
OS 49.38212628 -38.6197602
OS 49.393221 -38.60866548
OS 49.40339116 -38.59757076
OS 49.41263676 -38.5874006
OS 49.42003324 -38.57723044
OS 49.42003324 -38.57630588
OS 49.42188236 -38.57538132
OS 49.42373148 -38.57260764
OS 49.4255806 -38.5689094
OS 49.43205252 -38.55873924
OS 49.439449 -38.54671996
OS 49.44592092 -38.531927
OS 49.45239284 -38.51620948
OS 49.45609108 -38.49864284
OS 49.4579402 -38.48200076
OS 49.4579402 -38.4810762
OS 49.4579402 -38.48015164
OS 49.45701564 -38.47460428
OS 49.45609108 -38.46535868
OS 49.4533174 -38.45518852
OS 49.44961916 -38.44224468
OS 49.44314724 -38.42930084
OS 49.4348262 -38.416357
OS 49.42373148 -38.40341316
OS 49.42188236 -38.40156404
OS 49.41725956 -38.3978658
OS 49.41078764 -38.393243
OS 49.40061748 -38.38677108
OS 49.38767364 -38.38122372
OS 49.37288068 -38.37567636
OS 49.35531404 -38.37197812
OS 49.33589828 -38.37105356
OS 49.33035092 -38.37105356
OS 49.32665268 -38.37197812
OS 49.31555796 -38.37290268
OS 49.30261412 -38.37567636
OS 49.28874572 -38.3793746
OS 49.2730282 -38.38584652
OS 49.25823524 -38.39416756
OS 49.24436684 -38.40526228
OS 49.24251772 -38.4071114
OS 49.23881948 -38.4117342
OS 49.23327212 -38.41913068
OS 49.22772476 -38.4302254
OS 49.22125284 -38.44316924
OS 49.21570548 -38.45981132
OS 49.21200724 -38.47830252
OS 49.21015812 -38.4995674
OS 49.1297214 -38.49124636
OS 49.1297214 -38.4903218
OS 49.13064596 -38.48754812
OS 49.13064596 -38.48292532
OS 49.13157052 -38.4764534
OS 49.13341964 -38.46905692
OS 49.13526876 -38.46073588
OS 49.13804244 -38.45056572
OS 49.14081612 -38.44039556
OS 49.1482126 -38.41820612
OS 49.15930732 -38.39601668
OS 49.16577924 -38.38492196
OS 49.17410028 -38.37382724
OS 49.18242132 -38.36365708
OS 49.19166692 -38.35441148
OS 49.19259148 -38.35348692
OS 49.1944406 -38.35256236
OS 49.19721428 -38.34978868
OS 49.20183708 -38.347015
OS 49.20738444 -38.34331676
OS 49.21385636 -38.33961852
OS 49.22125284 -38.33499572
OS 49.23049844 -38.33037292
OS 49.2406686 -38.32575012
OS 49.25176332 -38.32112732
OS 49.2637826 -38.31742908
OS 49.27672644 -38.31373084
OS 49.29059484 -38.31095716
OS 49.3053878 -38.30818348
OS 49.32110532 -38.30725892
OS 49.3377474 -38.30633436
OS 49.346993 -38.30633436
OS 49.35346492 -38.30725892
OE
OB 48.67576244 -38.94890356 I
OS 48.59717484 -38.94890356
OS 48.59717484 -38.4487166
OS 48.59625028 -38.44964116
OS 48.59162748 -38.4533394
OS 48.58608012 -38.45888676
OS 48.57683452 -38.46535868
OS 48.56666436 -38.47367972
OS 48.55372052 -38.48292532
OS 48.53892756 -38.49309548
OS 48.52228548 -38.50326564
OS 48.52136092 -38.50326564
OS 48.52043636 -38.5041902
OS 48.514889 -38.50788844
OS 48.5056434 -38.51251124
OS 48.49454868 -38.5180586
OS 48.48160484 -38.52453052
OS 48.46773644 -38.53100244
OS 48.45386804 -38.53747436
OS 48.43999964 -38.54302172
OS 48.43999964 -38.4672078
OS 48.4409242 -38.4672078
OS 48.44277332 -38.46535868
OS 48.44647156 -38.46443412
OS 48.45109436 -38.46166044
OS 48.45664172 -38.45888676
OS 48.46311364 -38.45518852
OS 48.47883116 -38.44594292
OS 48.49732236 -38.43577276
OS 48.51581356 -38.42282892
OS 48.53522932 -38.40803596
OS 48.55464508 -38.39231844
OS 48.55556964 -38.39139388
OS 48.5564942 -38.39046932
OS 48.55926788 -38.38769564
OS 48.56296612 -38.38492196
OS 48.57128716 -38.37567636
OS 48.58238188 -38.36458164
OS 48.5934766 -38.3516378
OS 48.60549588 -38.33684484
OS 48.61566604 -38.32205188
OS 48.62491164 -38.30633436
OS 48.67576244 -38.30633436
OS 48.67576244 -38.94890356
OE
OB 48.9032042 -38.95999828 I
OS 48.84033412 -38.95999828
OS 49.02617068 -38.29801332
OS 49.08904076 -38.29801332
OS 48.9032042 -38.95999828
OE
OB 50.59699812 -38.30725892 I
OS 50.6043946 -38.30818348
OS 50.6136402 -38.30910804
OS 50.62381036 -38.31095716
OS 50.63398052 -38.31280628
OS 50.65801908 -38.3192782
OS 50.68205764 -38.3285238
OS 50.69407692 -38.33407116
OS 50.7060962 -38.34054308
OS 50.71719092 -38.34886412
OS 50.72736108 -38.35810972
OS 50.72828564 -38.35903428
OS 50.73013476 -38.35995884
OS 50.73198388 -38.36365708
OS 50.73568212 -38.36735532
OS 50.74030492 -38.37197812
OS 50.74492772 -38.37845004
OS 50.74955052 -38.38492196
OS 50.75509788 -38.393243
OS 50.76434348 -38.41080964
OS 50.77358908 -38.43299908
OS 50.77728732 -38.4440938
OS 50.77913644 -38.45703764
OS 50.78098556 -38.46998148
OS 50.78191012 -38.48384988
OS 50.78191012 -38.485699
OS 50.78191012 -38.4903218
OS 50.78098556 -38.49771828
OS 50.780061 -38.50788844
OS 50.77821188 -38.51898316
OS 50.77451364 -38.531927
OS 50.7708154 -38.5457954
OS 50.76526804 -38.5596638
OS 50.76434348 -38.56151292
OS 50.76249436 -38.56613572
OS 50.75879612 -38.5735322
OS 50.75324876 -38.58370236
OS 50.74585228 -38.59479708
OS 50.73660668 -38.60866548
OS 50.72551196 -38.62253388
OS 50.71256812 -38.6382514
OS 50.710719 -38.64010052
OS 50.7060962 -38.64564788
OS 50.7014734 -38.65027068
OS 50.6968506 -38.65489348
OS 50.69130324 -38.66044084
OS 50.68390676 -38.66783732
OS 50.67651028 -38.6752338
OS 50.66726468 -38.68355484
OS 50.65801908 -38.69280044
OS 50.64692436 -38.7029706
OS 50.63490508 -38.71314076
OS 50.62196124 -38.72516004
OS 50.60716828 -38.73717932
OS 50.59237532 -38.75012316
OS 50.59145076 -38.75104772
OS 50.58960164 -38.75289684
OS 50.5859034 -38.75567052
OS 50.5812806 -38.75936876
OS 50.57573324 -38.76491612
OS 50.56926132 -38.77046348
OS 50.55446836 -38.78248276
OS 50.53875084 -38.79635116
OS 50.52395788 -38.81021956
OS 50.51101404 -38.82223884
OS 50.50546668 -38.82686164
OS 50.50084388 -38.83148444
OS 50.49991932 -38.832409
OS 50.49714564 -38.83518268
OS 50.4934474 -38.83888092
OS 50.4888246 -38.84442828
OS 50.4842018 -38.8509002
OS 50.47865444 -38.85737212
OS 50.46755972 -38.87308964
OS 50.78283468 -38.87308964
OS 50.78283468 -38.94890356
OS 50.35846164 -38.94890356
OS 50.35846164 -38.947979
OS 50.35846164 -38.94428076
OS 50.35846164 -38.9387334
OS 50.3593862 -38.93133692
OS 50.36031076 -38.92301588
OS 50.36215988 -38.91377028
OS 50.364009 -38.90452468
OS 50.36770724 -38.89435452
OS 50.36770724 -38.89342996
OS 50.3686318 -38.8925054
OS 50.37048092 -38.88695804
OS 50.37417916 -38.878637
OS 50.37972652 -38.86754228
OS 50.387123 -38.85459844
OS 50.3963686 -38.83980548
OS 50.40653876 -38.82501252
OS 50.4194826 -38.809295
OS 50.4194826 -38.80837044
OS 50.42133172 -38.80744588
OS 50.42595452 -38.80189852
OS 50.43427556 -38.79357748
OS 50.44629484 -38.7815582
OS 50.46016324 -38.7676898
OS 50.47772988 -38.75104772
OS 50.49899476 -38.73255652
OS 50.52210876 -38.71314076
OS 50.52303332 -38.7122162
OS 50.52673156 -38.70944252
OS 50.53227892 -38.70481972
OS 50.53875084 -38.69927236
OS 50.54707188 -38.69187588
OS 50.55724204 -38.68355484
OS 50.5674122 -38.67430924
OS 50.57943148 -38.66413908
OS 50.60254548 -38.64194964
OS 50.62565948 -38.6197602
OS 50.6367542 -38.60866548
OS 50.64692436 -38.59757076
OS 50.65616996 -38.5874006
OS 50.66356644 -38.57723044
OS 50.66356644 -38.57630588
OS 50.66541556 -38.57538132
OS 50.66726468 -38.57260764
OS 50.6691138 -38.5689094
OS 50.67558572 -38.55873924
OS 50.6829822 -38.54671996
OS 50.68945412 -38.531927
OS 50.69592604 -38.51620948
OS 50.69962428 -38.49864284
OS 50.7014734 -38.48200076
OS 50.7014734 -38.4810762
OS 50.7014734 -38.48015164
OS 50.70054884 -38.47460428
OS 50.69962428 -38.46535868
OS 50.6968506 -38.45518852
OS 50.69315236 -38.44224468
OS 50.68668044 -38.42930084
OS 50.6783594 -38.416357
OS 50.66726468 -38.40341316
OS 50.66541556 -38.40156404
OS 50.66079276 -38.3978658
OS 50.65432084 -38.393243
OS 50.64415068 -38.38677108
OS 50.63120684 -38.38122372
OS 50.61641388 -38.37567636
OS 50.59884724 -38.37197812
OS 50.57943148 -38.37105356
OS 50.57388412 -38.37105356
OS 50.57018588 -38.37197812
OS 50.55909116 -38.37290268
OS 50.54614732 -38.37567636
OS 50.53227892 -38.3793746
OS 50.5165614 -38.38584652
OS 50.50176844 -38.39416756
OS 50.48790004 -38.40526228
OS 50.48605092 -38.4071114
OS 50.48235268 -38.4117342
OS 50.47680532 -38.41913068
OS 50.47125796 -38.4302254
OS 50.46478604 -38.44316924
OS 50.45923868 -38.45981132
OS 50.45554044 -38.47830252
OS 50.45369132 -38.4995674
OS 50.3732546 -38.49124636
OS 50.3732546 -38.4903218
OS 50.37417916 -38.48754812
OS 50.37417916 -38.48292532
OS 50.37510372 -38.4764534
OS 50.37695284 -38.46905692
OS 50.37880196 -38.46073588
OS 50.38157564 -38.45056572
OS 50.38434932 -38.44039556
OS 50.3917458 -38.41820612
OS 50.40284052 -38.39601668
OS 50.40931244 -38.38492196
OS 50.41763348 -38.37382724
OS 50.42595452 -38.36365708
OS 50.43520012 -38.35441148
OS 50.43612468 -38.35348692
OS 50.4379738 -38.35256236
OS 50.44074748 -38.34978868
OS 50.44537028 -38.347015
OS 50.45091764 -38.34331676
OS 50.45738956 -38.33961852
OS 50.46478604 -38.33499572
OS 50.47403164 -38.33037292
OS 50.4842018 -38.32575012
OS 50.49529652 -38.32112732
OS 50.5073158 -38.31742908
OS 50.52025964 -38.31373084
OS 50.53412804 -38.31095716
OS 50.548921 -38.30818348
OS 50.56463852 -38.30725892
OS 50.5812806 -38.30633436
OS 50.5905262 -38.30633436
OS 50.59699812 -38.30725892
OE
OB 51.0944114 -38.30725892 I
OS 51.10643068 -38.30910804
OS 51.12029908 -38.31188172
OS 51.13509204 -38.31557996
OS 51.15080956 -38.32020276
OS 51.16560252 -38.32759924
OS 51.16652708 -38.32759924
OS 51.16745164 -38.3285238
OS 51.17207444 -38.33129748
OS 51.17947092 -38.33592028
OS 51.18871652 -38.3423922
OS 51.19888668 -38.3516378
OS 51.2099814 -38.36180796
OS 51.22015156 -38.37382724
OS 51.23032172 -38.38769564
OS 51.23124628 -38.38954476
OS 51.23494452 -38.39416756
OS 51.23864276 -38.4024886
OS 51.24511468 -38.41450788
OS 51.25066204 -38.42837628
OS 51.25805852 -38.4440938
OS 51.26453044 -38.462585
OS 51.2700778 -38.48292532
OS 51.2700778 -38.48384988
OS 51.27100236 -38.485699
OS 51.27192692 -38.48847268
OS 51.27285148 -38.49309548
OS 51.27377604 -38.49864284
OS 51.2747006 -38.50511476
OS 51.27654972 -38.5134358
OS 51.27747428 -38.5226814
OS 51.2793234 -38.53285156
OS 51.28024796 -38.54394628
OS 51.28117252 -38.55689012
OS 51.28302164 -38.56983396
OS 51.2839462 -38.58462692
OS 51.2839462 -38.59941988
OS 51.28487076 -38.61606196
OS 51.28487076 -38.6336286
OS 51.28487076 -38.63455316
OS 51.28487076 -38.6382514
OS 51.28487076 -38.64472332
OS 51.28487076 -38.6521198
OS 51.2839462 -38.66228996
OS 51.2839462 -38.67338468
OS 51.28302164 -38.68540396
OS 51.28209708 -38.6983478
OS 51.2793234 -38.72793372
OS 51.2747006 -38.7584442
OS 51.26915324 -38.78803012
OS 51.265455 -38.80189852
OS 51.2608322 -38.81576692
OS 51.2608322 -38.81669148
OS 51.25990764 -38.8185406
OS 51.25805852 -38.82223884
OS 51.2562094 -38.82686164
OS 51.25436028 -38.83333356
OS 51.25066204 -38.83980548
OS 51.24326556 -38.855523
OS 51.23401996 -38.87216508
OS 51.22200068 -38.89065628
OS 51.20813228 -38.90729836
OS 51.1914902 -38.92301588
OS 51.19056564 -38.92301588
OS 51.18964108 -38.924865
OS 51.1868674 -38.92671412
OS 51.18316916 -38.92856324
OS 51.17854636 -38.93133692
OS 51.17392356 -38.93503516
OS 51.16005516 -38.94150708
OS 51.14341308 -38.947979
OS 51.12399732 -38.95445092
OS 51.10088332 -38.95814916
OS 51.0759202 -38.95999828
OS 51.0666746 -38.95999828
OS 51.06020268 -38.95907372
OS 51.0528062 -38.95814916
OS 51.0435606 -38.95630004
OS 51.03339044 -38.95445092
OS 51.02229572 -38.95167724
OS 51.011201 -38.947979
OS 50.99918172 -38.94428076
OS 50.98716244 -38.9387334
OS 50.97514316 -38.93226148
OS 50.96312388 -38.924865
OS 50.9511046 -38.9156194
OS 50.94000988 -38.90544924
OS 50.92983972 -38.89435452
OS 50.92891516 -38.89342996
OS 50.92706604 -38.89065628
OS 50.92429236 -38.88603348
OS 50.91966956 -38.878637
OS 50.91504676 -38.87031596
OS 50.91042396 -38.85922124
OS 50.90395204 -38.8462774
OS 50.89840468 -38.83148444
OS 50.89285732 -38.81484236
OS 50.88730996 -38.7954266
OS 50.8817626 -38.77416172
OS 50.8771398 -38.75012316
OS 50.872517 -38.72423548
OS 50.86974332 -38.69649868
OS 50.8678942 -38.6659882
OS 50.86696964 -38.6336286
OS 50.86696964 -38.63270404
OS 50.86696964 -38.6290058
OS 50.86696964 -38.62253388
OS 50.86696964 -38.6151374
OS 50.8678942 -38.60496724
OS 50.8678942 -38.59387252
OS 50.86881876 -38.58185324
OS 50.86974332 -38.56798484
OS 50.872517 -38.53932348
OS 50.8771398 -38.508813
OS 50.88268716 -38.47830252
OS 50.8863854 -38.46443412
OS 50.89008364 -38.45056572
OS 50.89008364 -38.44964116
OS 50.8910082 -38.44779204
OS 50.89285732 -38.4440938
OS 50.89470644 -38.439471
OS 50.89655556 -38.43299908
OS 50.9002538 -38.42652716
OS 50.90765028 -38.41080964
OS 50.91689588 -38.39416756
OS 50.92891516 -38.37660092
OS 50.94278356 -38.35903428
OS 50.95942564 -38.34424132
OS 50.9603502 -38.34424132
OS 50.96127476 -38.3423922
OS 50.96404844 -38.34054308
OS 50.96774668 -38.33869396
OS 50.97236948 -38.33499572
OS 50.97791684 -38.33222204
OS 50.99178524 -38.32482556
OS 51.00842732 -38.31835364
OS 51.02784308 -38.31188172
OS 51.05095708 -38.30818348
OS 51.0759202 -38.30633436
OS 51.08424124 -38.30633436
OS 51.0944114 -38.30725892
OE
OB 51.59182468 -38.30725892 I
OS 51.59922116 -38.30818348
OS 51.60846676 -38.30910804
OS 51.61863692 -38.31095716
OS 51.62880708 -38.31280628
OS 51.65284564 -38.3192782
OS 51.6768842 -38.3285238
OS 51.68890348 -38.33407116
OS 51.70092276 -38.34054308
OS 51.71201748 -38.34886412
OS 51.72218764 -38.35810972
OS 51.7231122 -38.35903428
OS 51.72496132 -38.35995884
OS 51.72681044 -38.36365708
OS 51.73050868 -38.36735532
OS 51.73513148 -38.37197812
OS 51.73975428 -38.37845004
OS 51.74437708 -38.38492196
OS 51.74992444 -38.393243
OS 51.75917004 -38.41080964
OS 51.76841564 -38.43299908
OS 51.77211388 -38.4440938
OS 51.773963 -38.45703764
OS 51.77581212 -38.46998148
OS 51.77673668 -38.48384988
OS 51.77673668 -38.485699
OS 51.77673668 -38.4903218
OS 51.77581212 -38.49771828
OS 51.77488756 -38.50788844
OS 51.77303844 -38.51898316
OS 51.7693402 -38.531927
OS 51.76564196 -38.5457954
OS 51.7600946 -38.5596638
OS 51.75917004 -38.56151292
OS 51.75732092 -38.56613572
OS 51.75362268 -38.5735322
OS 51.74807532 -38.58370236
OS 51.74067884 -38.59479708
OS 51.73143324 -38.60866548
OS 51.72033852 -38.62253388
OS 51.70739468 -38.6382514
OS 51.70554556 -38.64010052
OS 51.70092276 -38.64564788
OS 51.69629996 -38.65027068
OS 51.69167716 -38.65489348
OS 51.6861298 -38.66044084
OS 51.67873332 -38.66783732
OS 51.67133684 -38.6752338
OS 51.66209124 -38.68355484
OS 51.65284564 -38.69280044
OS 51.64175092 -38.7029706
OS 51.62973164 -38.71314076
OS 51.6167878 -38.72516004
OS 51.60199484 -38.73717932
OS 51.58720188 -38.75012316
OS 51.58627732 -38.75104772
OS 51.5844282 -38.75289684
OS 51.58072996 -38.75567052
OS 51.57610716 -38.75936876
OS 51.5705598 -38.76491612
OS 51.56408788 -38.77046348
OS 51.54929492 -38.78248276
OS 51.5335774 -38.79635116
OS 51.51878444 -38.81021956
OS 51.5058406 -38.82223884
OS 51.50029324 -38.82686164
OS 51.49567044 -38.83148444
OS 51.49474588 -38.832409
OS 51.4919722 -38.83518268
OS 51.48827396 -38.83888092
OS 51.48365116 -38.84442828
OS 51.47902836 -38.8509002
OS 51.473481 -38.85737212
OS 51.46238628 -38.87308964
OS 51.77766124 -38.87308964
OS 51.77766124 -38.94890356
OS 51.3532882 -38.94890356
OS 51.3532882 -38.947979
OS 51.3532882 -38.94428076
OS 51.3532882 -38.9387334
OS 51.35421276 -38.93133692
OS 51.35513732 -38.92301588
OS 51.35698644 -38.91377028
OS 51.35883556 -38.90452468
OS 51.3625338 -38.89435452
OS 51.3625338 -38.89342996
OS 51.36345836 -38.8925054
OS 51.36530748 -38.88695804
OS 51.36900572 -38.878637
OS 51.37455308 -38.86754228
OS 51.38194956 -38.85459844
OS 51.39119516 -38.83980548
OS 51.40136532 -38.82501252
OS 51.41430916 -38.809295
OS 51.41430916 -38.80837044
OS 51.41615828 -38.80744588
OS 51.42078108 -38.80189852
OS 51.42910212 -38.79357748
OS 51.4411214 -38.7815582
OS 51.4549898 -38.7676898
OS 51.47255644 -38.75104772
OS 51.49382132 -38.73255652
OS 51.51693532 -38.71314076
OS 51.51785988 -38.7122162
OS 51.52155812 -38.70944252
OS 51.52710548 -38.70481972
OS 51.5335774 -38.69927236
OS 51.54189844 -38.69187588
OS 51.5520686 -38.68355484
OS 51.56223876 -38.67430924
OS 51.57425804 -38.66413908
OS 51.59737204 -38.64194964
OS 51.62048604 -38.6197602
OS 51.63158076 -38.60866548
OS 51.64175092 -38.59757076
OS 51.65099652 -38.5874006
OS 51.658393 -38.57723044
OS 51.658393 -38.57630588
OS 51.66024212 -38.57538132
OS 51.66209124 -38.57260764
OS 51.66394036 -38.5689094
OS 51.67041228 -38.55873924
OS 51.67780876 -38.54671996
OS 51.68428068 -38.531927
OS 51.6907526 -38.51620948
OS 51.69445084 -38.49864284
OS 51.69629996 -38.48200076
OS 51.69629996 -38.4810762
OS 51.69629996 -38.48015164
OS 51.6953754 -38.47460428
OS 51.69445084 -38.46535868
OS 51.69167716 -38.45518852
OS 51.68797892 -38.44224468
OS 51.681507 -38.42930084
OS 51.67318596 -38.416357
OS 51.66209124 -38.40341316
OS 51.66024212 -38.40156404
OS 51.65561932 -38.3978658
OS 51.6491474 -38.393243
OS 51.63897724 -38.38677108
OS 51.6260334 -38.38122372
OS 51.61124044 -38.37567636
OS 51.5936738 -38.37197812
OS 51.57425804 -38.37105356
OS 51.56871068 -38.37105356
OS 51.56501244 -38.37197812
OS 51.55391772 -38.37290268
OS 51.54097388 -38.37567636
OS 51.52710548 -38.3793746
OS 51.51138796 -38.38584652
OS 51.496595 -38.39416756
OS 51.4827266 -38.40526228
OS 51.48087748 -38.4071114
OS 51.47717924 -38.4117342
OS 51.47163188 -38.41913068
OS 51.46608452 -38.4302254
OS 51.4596126 -38.44316924
OS 51.45406524 -38.45981132
OS 51.450367 -38.47830252
OS 51.44851788 -38.4995674
OS 51.36808116 -38.49124636
OS 51.36808116 -38.4903218
OS 51.36900572 -38.48754812
OS 51.36900572 -38.48292532
OS 51.36993028 -38.4764534
OS 51.3717794 -38.46905692
OS 51.37362852 -38.46073588
OS 51.3764022 -38.45056572
OS 51.37917588 -38.44039556
OS 51.38657236 -38.41820612
OS 51.39766708 -38.39601668
OS 51.404139 -38.38492196
OS 51.41246004 -38.37382724
OS 51.42078108 -38.36365708
OS 51.43002668 -38.35441148
OS 51.43095124 -38.35348692
OS 51.43280036 -38.35256236
OS 51.43557404 -38.34978868
OS 51.44019684 -38.347015
OS 51.4457442 -38.34331676
OS 51.45221612 -38.33961852
OS 51.4596126 -38.33499572
OS 51.4688582 -38.33037292
OS 51.47902836 -38.32575012
OS 51.49012308 -38.32112732
OS 51.50214236 -38.31742908
OS 51.5150862 -38.31373084
OS 51.5289546 -38.31095716
OS 51.54374756 -38.30818348
OS 51.55946508 -38.30725892
OS 51.57610716 -38.30633436
OS 51.58535276 -38.30633436
OS 51.59182468 -38.30725892
OE
OB 52.08184148 -38.30725892 I
OS 52.09386076 -38.30910804
OS 52.10865372 -38.31188172
OS 52.1252958 -38.31650452
OS 52.14193788 -38.32205188
OS 52.15857996 -38.32944836
OS 52.15950452 -38.32944836
OS 52.16042908 -38.33037292
OS 52.16597644 -38.3331466
OS 52.17429748 -38.33869396
OS 52.18354308 -38.34516588
OS 52.1946378 -38.35441148
OS 52.20573252 -38.36458164
OS 52.21682724 -38.37660092
OS 52.22607284 -38.39046932
OS 52.2269974 -38.39231844
OS 52.22977108 -38.39694124
OS 52.23346932 -38.40526228
OS 52.23809212 -38.41543244
OS 52.24271492 -38.42745172
OS 52.24641316 -38.44132012
OS 52.24918684 -38.45703764
OS 52.2501114 -38.47275516
OS 52.2501114 -38.47460428
OS 52.2501114 -38.48015164
OS 52.24918684 -38.48754812
OS 52.24733772 -38.49771828
OS 52.24456404 -38.50973756
OS 52.23994124 -38.5226814
OS 52.23439388 -38.53562524
OS 52.2269974 -38.54856908
OS 52.22607284 -38.5504182
OS 52.22329916 -38.55411644
OS 52.2177518 -38.56058836
OS 52.21035532 -38.56798484
OS 52.20110972 -38.57630588
OS 52.190015 -38.58555148
OS 52.17707116 -38.59387252
OS 52.16135364 -38.60219356
OS 52.1622782 -38.60219356
OS 52.16412732 -38.60311812
OS 52.166901 -38.60404268
OS 52.17059924 -38.60496724
OS 52.1807694 -38.60866548
OS 52.19371324 -38.61421284
OS 52.2085062 -38.62160932
OS 52.22329916 -38.63085492
OS 52.23716756 -38.6428742
OS 52.2501114 -38.6567426
OS 52.25103596 -38.65859172
OS 52.2547342 -38.66413908
OS 52.26028156 -38.67338468
OS 52.26582892 -38.68540396
OS 52.27137628 -38.70019692
OS 52.27692364 -38.71776356
OS 52.28062188 -38.73810388
OS 52.28154644 -38.76029332
OS 52.28154644 -38.76121788
OS 52.28154644 -38.76399156
OS 52.28154644 -38.76861436
OS 52.28062188 -38.77416172
OS 52.27969732 -38.7815582
OS 52.2778482 -38.78987924
OS 52.27599908 -38.79912484
OS 52.27414996 -38.809295
OS 52.26675348 -38.83148444
OS 52.26120612 -38.84350372
OS 52.25565876 -38.85459844
OS 52.24826228 -38.86661772
OS 52.23994124 -38.878637
OS 52.23069564 -38.89065628
OS 52.21960092 -38.901751
OS 52.21867636 -38.90267556
OS 52.21682724 -38.90452468
OS 52.213129 -38.90729836
OS 52.2085062 -38.9109966
OS 52.20295884 -38.9156194
OS 52.19556236 -38.9202422
OS 52.18724132 -38.92578956
OS 52.17707116 -38.93041236
OS 52.166901 -38.93595972
OS 52.15488172 -38.94150708
OS 52.14286244 -38.94612988
OS 52.12899404 -38.95075268
OS 52.11420108 -38.95445092
OS 52.09848356 -38.9572246
OS 52.08276604 -38.95907372
OS 52.0651994 -38.95999828
OS 52.05687836 -38.95999828
OS 52.051331 -38.95907372
OS 52.04393452 -38.95814916
OS 52.03561348 -38.9572246
OS 52.02636788 -38.95537548
OS 52.01619772 -38.95352636
OS 51.99400828 -38.947979
OS 51.97089428 -38.9387334
OS 51.958875 -38.93318604
OS 51.94778028 -38.92671412
OS 51.93668556 -38.91839308
OS 51.92559084 -38.91007204
OS 51.92466628 -38.90914748
OS 51.92281716 -38.90729836
OS 51.92004348 -38.90452468
OS 51.9172698 -38.90082644
OS 51.912647 -38.89620364
OS 51.9080242 -38.88973172
OS 51.90247684 -38.8832598
OS 51.89692948 -38.87493876
OS 51.89138212 -38.86569316
OS 51.88583476 -38.85644756
OS 51.8756646 -38.83425812
OS 51.86734356 -38.80837044
OS 51.86456988 -38.79450204
OS 51.86272076 -38.77970908
OS 51.94130836 -38.76953892
OS 51.94130836 -38.77046348
OS 51.94223292 -38.7723126
OS 51.94315748 -38.77601084
OS 51.94408204 -38.78063364
OS 51.9450066 -38.786181
OS 51.94685572 -38.79265292
OS 51.95147852 -38.80652132
OS 51.95795044 -38.8231634
OS 51.96627148 -38.83888092
OS 51.97551708 -38.85367388
OS 51.9866118 -38.86661772
OS 51.98846092 -38.86754228
OS 51.99215916 -38.87124052
OS 51.99955564 -38.87586332
OS 52.00880124 -38.88048612
OS 52.01989596 -38.88603348
OS 52.03376436 -38.89065628
OS 52.04948188 -38.89435452
OS 52.06612396 -38.89527908
OS 52.07167132 -38.89527908
OS 52.07536956 -38.89435452
OS 52.08553972 -38.89342996
OS 52.09848356 -38.89065628
OS 52.11327652 -38.88603348
OS 52.12899404 -38.87956156
OS 52.14471156 -38.87031596
OS 52.15950452 -38.85737212
OS 52.16135364 -38.855523
OS 52.16597644 -38.84997564
OS 52.1715238 -38.8416546
OS 52.17892028 -38.83055988
OS 52.18631676 -38.81669148
OS 52.19186412 -38.80097396
OS 52.19648692 -38.78248276
OS 52.19833604 -38.76214244
OS 52.19833604 -38.76121788
OS 52.19833604 -38.75936876
OS 52.19833604 -38.75659508
OS 52.19741148 -38.75289684
OS 52.19648692 -38.74272668
OS 52.19371324 -38.7307074
OS 52.190015 -38.71591444
OS 52.18354308 -38.70112148
OS 52.17429748 -38.68632852
OS 52.1622782 -38.67246012
OS 52.16042908 -38.670611
OS 52.15580628 -38.66691276
OS 52.1484098 -38.6613654
OS 52.13823964 -38.65489348
OS 52.1252958 -38.64842156
OS 52.10957828 -38.6428742
OS 52.09201164 -38.63917596
OS 52.07259588 -38.63732684
OS 52.06427484 -38.63732684
OS 52.05780292 -38.6382514
OS 52.04948188 -38.63917596
OS 52.04023628 -38.64102508
OS 52.02914156 -38.6428742
OS 52.01712228 -38.64564788
OS 52.02636788 -38.57630588
OS 52.03099068 -38.57630588
OS 52.03468892 -38.57723044
OS 52.0467082 -38.57723044
OS 52.05687836 -38.57538132
OS 52.06889764 -38.5735322
OS 52.08276604 -38.57075852
OS 52.09848356 -38.56613572
OS 52.11327652 -38.5596638
OS 52.12899404 -38.55134276
OS 52.1299186 -38.55134276
OS 52.13084316 -38.5504182
OS 52.13546596 -38.54671996
OS 52.14193788 -38.54024804
OS 52.14933436 -38.531927
OS 52.15673084 -38.51990772
OS 52.16320276 -38.50603932
OS 52.16782556 -38.4903218
OS 52.16967468 -38.4810762
OS 52.16967468 -38.47090604
OS 52.16967468 -38.46998148
OS 52.16967468 -38.46905692
OS 52.16967468 -38.46350956
OS 52.16782556 -38.45611308
OS 52.16597644 -38.44594292
OS 52.1622782 -38.4348482
OS 52.1576554 -38.42282892
OS 52.15025892 -38.41080964
OS 52.14008876 -38.39971492
OS 52.1391642 -38.39879036
OS 52.1345414 -38.39509212
OS 52.12806948 -38.39046932
OS 52.11974844 -38.38492196
OS 52.10865372 -38.38029916
OS 52.09570988 -38.37567636
OS 52.08091692 -38.37197812
OS 52.06427484 -38.37105356
OS 52.05687836 -38.37105356
OS 52.04855732 -38.37290268
OS 52.0374626 -38.3747518
OS 52.02544332 -38.37845004
OS 52.01342404 -38.38307284
OS 52.0004802 -38.39046932
OS 51.98846092 -38.39971492
OS 51.98753636 -38.40063948
OS 51.98383812 -38.40526228
OS 51.97829076 -38.4117342
OS 51.97181884 -38.4209798
OS 51.96534692 -38.43299908
OS 51.958875 -38.44779204
OS 51.95332764 -38.46535868
OS 51.9496294 -38.485699
OS 51.8710418 -38.4718306
OS 51.8710418 -38.47090604
OS 51.87196636 -38.46813236
OS 51.87289092 -38.46443412
OS 51.87381548 -38.45888676
OS 51.8756646 -38.45241484
OS 51.87843828 -38.44501836
OS 51.88398564 -38.42745172
OS 51.89323124 -38.4071114
OS 51.90432596 -38.38677108
OS 51.91819436 -38.36735532
OS 51.935761 -38.34978868
OS 51.93668556 -38.34886412
OS 51.93853468 -38.34793956
OS 51.94130836 -38.34609044
OS 51.9450066 -38.34331676
OS 51.9496294 -38.33961852
OS 51.95610132 -38.33592028
OS 51.96257324 -38.33222204
OS 51.97089428 -38.32759924
OS 51.98938548 -38.32020276
OS 52.01065036 -38.31280628
OS 52.03561348 -38.30818348
OS 52.04855732 -38.30633436
OS 52.07167132 -38.30633436
OS 52.08184148 -38.30725892
OE
OB 51.07499564 -38.37105356 H
OS 51.06944828 -38.37105356
OS 51.06575004 -38.37197812
OS 51.05557988 -38.37382724
OS 51.0435606 -38.37660092
OS 51.0296922 -38.38214828
OS 51.01489924 -38.39046932
OS 51.00750276 -38.39601668
OS 51.00010628 -38.40156404
OS 50.99363436 -38.40896052
OS 50.98716244 -38.41728156
OS 50.98716244 -38.41820612
OS 50.98531332 -38.42005524
OS 50.9834642 -38.42375348
OS 50.98069052 -38.42837628
OS 50.97791684 -38.43577276
OS 50.9742186 -38.4440938
OS 50.97144492 -38.45426396
OS 50.96774668 -38.46628324
OS 50.96404844 -38.48015164
OS 50.9603502 -38.49586916
OS 50.95665196 -38.5134358
OS 50.95387828 -38.53285156
OS 50.9511046 -38.555041
OS 50.94925548 -38.57907956
OS 50.94833092 -38.60496724
OS 50.94740636 -38.6336286
OS 50.94740636 -38.63547772
OS 50.94740636 -38.64010052
OS 50.94740636 -38.64842156
OS 50.94833092 -38.65951628
OS 50.94833092 -38.67153556
OS 50.94925548 -38.68632852
OS 50.95018004 -38.70204604
OS 50.95202916 -38.71868812
OS 50.95665196 -38.75474596
OS 50.95942564 -38.7723126
OS 50.96312388 -38.78895468
OS 50.96682212 -38.8046722
OS 50.97236948 -38.81946516
OS 50.97791684 -38.832409
OS 50.98438876 -38.84350372
OS 50.98438876 -38.84442828
OS 50.98623788 -38.84535284
OS 50.99086068 -38.85182476
OS 50.99918172 -38.8601458
OS 51.00935188 -38.8693914
OS 51.02322028 -38.878637
OS 51.0389378 -38.88695804
OS 51.05650444 -38.89342996
OS 51.06575004 -38.89435452
OS 51.0759202 -38.89527908
OS 51.08146756 -38.89527908
OS 51.0851658 -38.89435452
OS 51.0944114 -38.8925054
OS 51.10735524 -38.88880716
OS 51.12122364 -38.88233524
OS 51.13694116 -38.87308964
OS 51.14433764 -38.86754228
OS 51.15173412 -38.8601458
OS 51.1591306 -38.85274932
OS 51.16652708 -38.84350372
OS 51.16652708 -38.84257916
OS 51.1683762 -38.84073004
OS 51.17022532 -38.83795636
OS 51.17207444 -38.83333356
OS 51.17577268 -38.82686164
OS 51.17854636 -38.8185406
OS 51.1822446 -38.809295
OS 51.18594284 -38.79820028
OS 51.18871652 -38.78433188
OS 51.19241476 -38.76953892
OS 51.196113 -38.75197228
OS 51.19888668 -38.73348108
OS 51.2007358 -38.71129164
OS 51.20258492 -38.68817764
OS 51.20443404 -38.66228996
OS 51.20443404 -38.6336286
OS 51.20443404 -38.63270404
OS 51.20443404 -38.63177948
OS 51.20443404 -38.62715668
OS 51.20443404 -38.61883564
OS 51.20350948 -38.60774092
OS 51.20350948 -38.59572164
OS 51.20258492 -38.58092868
OS 51.20166036 -38.56521116
OS 51.19981124 -38.54764452
OS 51.19518844 -38.51251124
OS 51.19241476 -38.4949446
OS 51.18871652 -38.47830252
OS 51.18501828 -38.462585
OS 51.17947092 -38.44779204
OS 51.17392356 -38.4348482
OS 51.16745164 -38.42375348
OS 51.16745164 -38.42282892
OS 51.16560252 -38.42190436
OS 51.1637534 -38.41913068
OS 51.16097972 -38.41543244
OS 51.15265868 -38.4071114
OS 51.14248852 -38.39694124
OS 51.12862012 -38.38769564
OS 51.1129026 -38.3793746
OS 51.10458156 -38.37567636
OS 51.09533596 -38.37290268
OS 51.0851658 -38.37197812
OS 51.07499564 -38.37105356
OE
OB 54.05947532 -38.37105356 H
OS 54.05392796 -38.37105356
OS 54.05022972 -38.37197812
OS 54.04005956 -38.37382724
OS 54.02804028 -38.37660092
OS 54.01417188 -38.38214828
OS 53.99937892 -38.39046932
OS 53.99198244 -38.39601668
OS 53.98458596 -38.40156404
OS 53.97811404 -38.40896052
OS 53.97164212 -38.41728156
OS 53.97164212 -38.41820612
OS 53.969793 -38.42005524
OS 53.96794388 -38.42375348
OS 53.9651702 -38.42837628
OS 53.96239652 -38.43577276
OS 53.95869828 -38.4440938
OS 53.9559246 -38.45426396
OS 53.95222636 -38.46628324
OS 53.94852812 -38.48015164
OS 53.94482988 -38.49586916
OS 53.94113164 -38.5134358
OS 53.93835796 -38.53285156
OS 53.93558428 -38.555041
OS 53.93373516 -38.57907956
OS 53.9328106 -38.60496724
OS 53.93188604 -38.6336286
OS 53.93188604 -38.63547772
OS 53.93188604 -38.64010052
OS 53.93188604 -38.64842156
OS 53.9328106 -38.65951628
OS 53.9328106 -38.67153556
OS 53.93373516 -38.68632852
OS 53.93465972 -38.70204604
OS 53.93650884 -38.71868812
OS 53.94113164 -38.75474596
OS 53.94390532 -38.7723126
OS 53.94760356 -38.78895468
OS 53.9513018 -38.8046722
OS 53.95684916 -38.81946516
OS 53.96239652 -38.832409
OS 53.96886844 -38.84350372
OS 53.96886844 -38.84442828
OS 53.97071756 -38.84535284
OS 53.97534036 -38.85182476
OS 53.9836614 -38.8601458
OS 53.99383156 -38.8693914
OS 54.00769996 -38.878637
OS 54.02341748 -38.88695804
OS 54.04098412 -38.89342996
OS 54.05022972 -38.89435452
OS 54.06039988 -38.89527908
OS 54.06594724 -38.89527908
OS 54.06964548 -38.89435452
OS 54.07889108 -38.8925054
OS 54.09183492 -38.88880716
OS 54.10570332 -38.88233524
OS 54.12142084 -38.87308964
OS 54.12881732 -38.86754228
OS 54.1362138 -38.8601458
OS 54.14361028 -38.85274932
OS 54.15100676 -38.84350372
OS 54.15100676 -38.84257916
OS 54.15285588 -38.84073004
OS 54.154705 -38.83795636
OS 54.15655412 -38.83333356
OS 54.16025236 -38.82686164
OS 54.16302604 -38.8185406
OS 54.16672428 -38.809295
OS 54.17042252 -38.79820028
OS 54.1731962 -38.78433188
OS 54.17689444 -38.76953892
OS 54.18059268 -38.75197228
OS 54.18336636 -38.73348108
OS 54.18521548 -38.71129164
OS 54.1870646 -38.68817764
OS 54.18891372 -38.66228996
OS 54.18891372 -38.6336286
OS 54.18891372 -38.63270404
OS 54.18891372 -38.63177948
OS 54.18891372 -38.62715668
OS 54.18891372 -38.61883564
OS 54.18798916 -38.60774092
OS 54.18798916 -38.59572164
OS 54.1870646 -38.58092868
OS 54.18614004 -38.56521116
OS 54.18429092 -38.54764452
OS 54.17966812 -38.51251124
OS 54.17689444 -38.4949446
OS 54.1731962 -38.47830252
OS 54.16949796 -38.462585
OS 54.1639506 -38.44779204
OS 54.15840324 -38.4348482
OS 54.15193132 -38.42375348
OS 54.15193132 -38.42282892
OS 54.1500822 -38.42190436
OS 54.14823308 -38.41913068
OS 54.1454594 -38.41543244
OS 54.13713836 -38.4071114
OS 54.1269682 -38.39694124
OS 54.1130998 -38.38769564
OS 54.09738228 -38.3793746
OS 54.08906124 -38.37567636
OS 54.07981564 -38.37290268
OS 54.06964548 -38.37197812
OS 54.05947532 -38.37105356
OE
OB 49.87491676 -38.43669732 H
OS 49.67336268 -38.72331092
OS 49.87491676 -38.72331092
OS 49.87491676 -38.43669732
OE
OB 56.14158444 -38.38492196 H
OS 55.95852156 -38.38492196
OS 55.95852156 -38.61328828
OS 56.13048972 -38.61328828
OS 56.13696164 -38.61236372
OS 56.14343356 -38.61236372
OS 56.15083004 -38.61143916
OS 56.16839668 -38.60959004
OS 56.18781244 -38.6058918
OS 56.2072282 -38.60034444
OS 56.22479484 -38.59294796
OS 56.23311588 -38.58832516
OS 56.2395878 -38.5827778
OS 56.24143692 -38.58092868
OS 56.24513516 -38.57723044
OS 56.25068252 -38.56983396
OS 56.25715444 -38.56058836
OS 56.26362636 -38.54856908
OS 56.26917372 -38.53377612
OS 56.27287196 -38.51713404
OS 56.27472108 -38.49771828
OS 56.27472108 -38.49679372
OS 56.27472108 -38.49586916
OS 56.27472108 -38.49124636
OS 56.27379652 -38.48292532
OS 56.2719474 -38.47367972
OS 56.27009828 -38.46350956
OS 56.26640004 -38.45149028
OS 56.26085268 -38.44039556
OS 56.25438076 -38.42930084
OS 56.2534562 -38.42837628
OS 56.25068252 -38.42467804
OS 56.24605972 -38.42005524
OS 56.24051236 -38.41358332
OS 56.23219132 -38.4071114
OS 56.22294572 -38.40156404
OS 56.21277556 -38.39601668
OS 56.20075628 -38.39139388
OS 56.19983172 -38.39139388
OS 56.19613348 -38.39046932
OS 56.19058612 -38.38954476
OS 56.18318964 -38.38769564
OS 56.17209492 -38.38677108
OS 56.15822652 -38.38584652
OS 56.14158444 -38.38492196
OE
SE

### steps/pcb/layers/bottom_solder/features
UNITS=MM
#Layer_Color=16711935
#
#Feature symbol names
#
$0 r99.9998
$1 rect700.00114x1402.87502
$2 rect700.00114x1399.99974
$3 rect1150.00024x1849.99884
$4 rect1150.00024x1000.00054
$5 rect669.99866x719.99856
$6 rect519.99896x539.99892
$7 r6300.0001
$8 rect2400.00028x3400.00082
$9 rect900.00074x1549.99944
$10 rect699.9986x399.9992
$11 rect399.9992x1825.00016
$12 rect1399.99974x1749.99904
$13 rect699.9986x719.99856
$14 rect559.99888x519.99896
$15 rect519.99896x559.99888
$16 rect719.99856x699.9986
$17 rect719.99856x669.99866
$18 r1999.99854
$19 r2190.0007
$20 r5699.99876
$21 r1662.00074
$22 r1623.9998
$23 r1899.99874

#
#Feature attribute names
#
@0 .nomenclature
@1 .string
@2 .string_angle
@3 .geometry
@4 .pad_usage

#
#Feature attribute text strings
#
&0 SMD_RectX1050.0004Y1749.9990
&1 SMD_RectX1050.0004Y900.0007
&2 SMD_RectX569.9989Y619.9988
&3 SMD_RectX419.9992Y439.9991
&4 SMD_RoundX6200.0003Y6200.0003
&5 SMD_RectX2300.0005Y3300.0010
&6 SMD_RectX800.0009Y1449.9996
&7 SMD_RectX599.9988Y299.9994
&8 SMD_RectX299.9994Y1725.0004
&9 SMD_RectX1299.9999Y1649.9992
&10 SMD_RectX599.9988Y619.9988
&11 SMD_RectX459.9991Y419.9992
&12 SMD_RectX419.9992Y459.9991
&13 SMD_RectX619.9988Y599.9988
&14 SMD_RectX619.9988Y569.9989
&15 SMD_RoundX1000.0005Y1000.0005
&16 Pad_Simple_X2090.0009Y2090.0009H1090.0004C2106.0004
&17 Pad_Simple_X5299.9996Y5299.9996H2999.9991C4015.9991
&18 Pad_Simple_X1562.0009Y1562.0009H961.9996C1977.9996
&19 Pad_Simple_X1524.0000Y1524.0000H762.0000C1778.0000
&20 Pad_Simple_X0.0000Y0.0000H3700.0002C4716.0002
&21 Pad_Simple_X1799.9989Y1799.9989H1200.0001C2216.0001

#
#Layer features
#
L -9.5600012 -24.45999934 40.4400004 -24.45999934 0 P 0
L -9.5600012 -35.9599992 -9.5600012 -24.45999934 0 P 0
L -9.5600012 -35.9599992 28.439999 -35.9599992 0 P 0
L -9.5600012 -39.45999982 -9.5600012 -35.9599992 0 P 0
L -9.5600012 -39.45999982 28.439999 -39.45999982 0 P 0
L -9.5600012 -42.96000044 -9.5600012 -39.45999982 0 P 0
L -9.5600012 -42.96000044 28.439999 -42.96000044 0 P 0
L -10.0600002 -23.96000034 62.93999858 -23.96000034 0 P 0
L -10.0600002 -43.45999944 -10.0600002 -23.96000034 0 P 0
L -10.0600002 -43.45999944 62.93999858 -43.45999944 0 P 0
L 28.439999 -35.96000174 45.44000056 -35.9599992 0 P 0
L 28.439999 -39.45999982 28.439999 -35.9599992 0 P 0
L 28.439999 -39.46000236 45.44000056 -39.45999982 0 P 0
L 28.439999 -42.96000044 28.439999 -39.45999982 0 P 0
L 28.439999 -42.96000298 45.44000056 -42.96000044 0 P 0
L 40.4400004 -24.45999934 62.43999958 -24.45999934 0 P 0
L 40.4400004 -35.9599992 40.4400004 -24.45999934 0 P 0
L 45.44000056 -35.9599992 62.43999958 -35.9599992 0 P 0
L 45.44000056 -39.45999982 62.43999958 -39.45999982 0 P 0
L 45.44000056 -42.96000044 45.44000056 -35.9599992 0 P 0
L 45.44000056 -42.96000044 62.43999958 -42.96000044 0 P 0
L 62.43999958 -35.9599992 62.43999958 -24.45999934 0 P 0
L 62.43999958 -42.96000044 62.43999958 -35.9599992 0 P 0
L 62.93999858 -43.45999944 62.93999858 -23.96000034 0 P 0
P -2.38499904 43.5150006 18 P 0 0 ;3=15,4=0
P 0 0 19 P 0 0 ;3=16,4=0
P 0 40.64 19 P 0 0 ;3=16,4=0
P 2.0779994 43.3299997 19 P 0 0 ;3=16,4=0
P 4.39999882 2.00000108 0 P 0 0 ;3=20,4=0
P 4.39999882 2.00000108 7 P 0 0 ;3=4,4=0
P 4.39999882 38.599999 0 P 0 0 ;3=20,4=0
P 4.39999882 38.599999 7 P 0 0 ;3=4,4=0
P 4.8300005 7.63999996 23 P 0 0 ;3=21,4=0
P 4.8300005 7.63999996 22 P 0 0 ;3=19,4=0
P 4.8300005 12.71999996 23 P 0 0 ;3=21,4=0
P 4.8300005 12.71999996 22 P 0 0 ;3=19,4=0
P 4.8300005 17.79999996 23 P 0 0 ;3=21,4=0
P 4.8300005 17.79999996 22 P 0 0 ;3=19,4=0
P 4.8300005 33.03999996 22 P 0 0 ;3=19,4=0
P 4.8300005 33.03999996 23 P 0 0 ;3=21,4=0
P 5.1259994 43.3299997 19 P 0 0 ;3=16,4=0
P 8.1739994 43.3299997 19 P 0 0 ;3=16,4=0
P 11.2219994 43.3299997 19 P 0 0 ;3=16,4=0
P 13.9050014 18.0150008 5 P 0 0 ;3=2,4=0
P 13.9050014 19.16500104 5 P 0 0 ;3=2,4=0
P 14.2699994 43.3299997 19 P 0 0 ;3=16,4=0
P 14.86499948 18.0150008 5 P 0 0 ;3=2,4=0
P 14.86499948 19.16500104 5 P 0 0 ;3=2,4=0
P 14.86499948 20.21500148 15 P 0 0 ;3=12,4=0
P 14.86499948 20.87500016 15 P 0 0 ;3=12,4=0
P 15.86500002 20.21500148 6 P 0 0 ;3=3,4=0
P 15.86500002 20.89500012 6 P 0 0 ;3=3,4=0
P 15.91499992 7.38999792 12 P 0 0 ;3=9,4=0
P 15.91499992 9.7899982 12 P 0 0 ;3=9,4=0
P 15.91499992 12.39000062 12 P 0 0 ;3=9,4=0
P 16.29499916 22.29000114 14 P 0 0 ;3=11,4=0
P 16.31500166 18.04000202 10 P 0 0 ;3=7,4=0
P 16.31500166 18.49000112 10 P 0 0 ;3=7,4=0
P 16.31500166 18.94000276 10 P 0 0 ;3=7,4=0
P 16.31503976 18.43856612 1 P 0 0
P 16.41500146 16.99000158 9 P 0 0 ;3=6,4=0
P 16.65500352 14.7900009 13 P 0 0 ;3=10,4=0
P 16.95499784 20.21500148 17 P 0 0 ;3=14,4=0
P 16.95499784 21.17499956 17 P 0 0 ;3=14,4=0
P 16.95499784 22.29000114 14 P 0 0 ;3=11,4=0
P 17.1650025 16.85250122 11 P 0 0 ;3=8,4=0
P 17.57500168 14.7900009 13 P 0 0 ;3=10,4=0
P 17.7150014 7.38999792 12 P 0 0 ;3=9,4=0
P 17.7150014 9.7899982 12 P 0 0 ;3=9,4=0
P 17.7150014 12.39000062 12 P 0 0 ;3=9,4=0
P 17.915001 16.99000158 9 P 0 0 ;3=6,4=0
P 18.01495762 18.44000376 2 P 0 0
P 18.0150008 18.04000202 10 P 0 0 ;3=7,4=0
P 18.0150008 18.49000112 10 P 0 0 ;3=7,4=0
P 18.0150008 18.94000276 10 P 0 0 ;3=7,4=0
P 18.22000166 21.17499956 13 P 0 0 ;3=10,4=0
P 19.13999982 21.17499956 13 P 0 0 ;3=10,4=0
P 20.24000016 42.13999954 20 P 0 0 ;3=17,4=0
P 20.43999976 -1.26000002 20 P 0 0 ;3=17,4=0
P 20.76500038 16.85250122 8 P 0 0 ;3=5,4=0
P 22.41500216 7.7900022 12 P 0 0 ;3=9,4=0
P 22.41500216 10.29000228 12 P 0 0 ;3=9,4=0
P 22.95500362 12.29000082 13 P 0 0 ;3=10,4=0
P 23.87500178 12.29000082 13 P 0 0 ;3=10,4=0
P 24.21500364 7.7900022 12 P 0 0 ;3=9,4=0
P 24.21500364 10.29000228 12 P 0 0 ;3=9,4=0
P 26.06499994 16.85250122 8 P 0 0 ;3=5,4=0
P 32.24000156 7.63999996 3 P 0 0 ;3=0,4=0
P 35.24000064 7.63999996 3 P 0 0 ;3=0,4=0
P 35.50000012 -1.00000054 0 P 0 0 ;3=20,4=0
P 35.50000012 -1.00000054 7 P 0 0 ;3=4,4=0
P 36.20000126 40.10000108 0 P 0 0 ;3=20,4=0
P 36.20000126 40.10000108 7 P 0 0 ;3=4,4=0
P 37.8500005 7.63999996 23 P 0 0 ;3=21,4=0
P 37.8500005 7.63999996 21 P 0 0 ;3=18,4=0
P 37.8500005 9.94000044 13 P 0 0 ;3=10,4=0
P 37.8500005 12.71999996 23 P 0 0 ;3=21,4=0
P 37.8500005 12.71999996 21 P 0 0 ;3=18,4=0
P 37.8500005 17.79999996 23 P 0 0 ;3=21,4=0
P 37.8500005 17.79999996 21 P 0 0 ;3=18,4=0
P 37.8500005 22.87999996 21 P 0 0 ;3=18,4=0
P 37.8500005 22.87999996 23 P 0 0 ;3=21,4=0
P 37.8500005 33.03999996 21 P 0 0 ;3=18,4=0
P 37.8500005 33.03999996 23 P 0 0 ;3=21,4=0
P 38.76999866 9.94000044 13 P 0 0 ;3=10,4=0
P 39.78999916 14.51500018 4 P 0 0 ;3=1,4=0
P 39.78999916 15.96499982 4 P 0 0 ;3=1,4=0
P 40.0900011 7.63999996 16 P 0 0 ;3=13,4=0
P 40.0900011 8.55999812 16 P 0 0 ;3=13,4=0
P 40.64 0 19 P 0 0 ;3=16,4=0
P 40.64 40.64 19 P 0 0 ;3=16,4=0
P 40.67999992 20.33999996 19 P 0 0 ;3=16,4=0
P 43.11499886 43.5150006 18 P 0 0 ;3=15,4=0
P 43.18999998 -2.80999946 18 P 0 0 ;3=15,4=0
S P 0
OB -2.46623586 -38.48662356 I
OS -2.45236746 -38.48754812
OS -2.4375745 -38.48939724
OS -2.42185698 -38.49309548
OS -2.4052149 -38.49679372
OS -2.38949738 -38.50234108
OS -2.38857282 -38.50234108
OS -2.38764826 -38.50326564
OS -2.38302546 -38.50511476
OS -2.37562898 -38.508813
OS -2.36638338 -38.5134358
OS -2.35621322 -38.51990772
OS -2.34604306 -38.5273042
OS -2.33679746 -38.53562524
OS -2.32847642 -38.54487084
OS -2.32755186 -38.5457954
OS -2.32570274 -38.54949364
OS -2.3220045 -38.55596556
OS -2.3173817 -38.56336204
OS -2.3127589 -38.57445676
OS -2.3081361 -38.58647604
OS -2.30443786 -38.60034444
OS -2.30073962 -38.61606196
OS -2.3774781 -38.62623212
OS -2.3774781 -38.624383
OS -2.37840266 -38.62068476
OS -2.38025178 -38.61421284
OS -2.38302546 -38.6058918
OS -2.38764826 -38.59757076
OS -2.39319562 -38.58832516
OS -2.39966754 -38.57907956
OS -2.40891314 -38.57075852
OS -2.4098377 -38.56983396
OS -2.41353594 -38.56798484
OS -2.4190833 -38.5642866
OS -2.42740434 -38.56058836
OS -2.43664994 -38.55689012
OS -2.44866922 -38.55319188
OS -2.46346218 -38.55134276
OS -2.4791797 -38.5504182
OS -2.4884253 -38.5504182
OS -2.4976709 -38.55134276
OS -2.50969018 -38.55226732
OS -2.52170946 -38.555041
OS -2.5346533 -38.55781468
OS -2.54667258 -38.56243748
OS -2.55684274 -38.5689094
OS -2.5577673 -38.56983396
OS -2.56054098 -38.57168308
OS -2.56423922 -38.57538132
OS -2.56793746 -38.58092868
OS -2.57256026 -38.58647604
OS -2.5762585 -38.59387252
OS -2.57903218 -38.60219356
OS -2.57995674 -38.6105146
OS -2.57995674 -38.61143916
OS -2.57995674 -38.61328828
OS -2.57903218 -38.61606196
OS -2.57903218 -38.6197602
OS -2.5762585 -38.6290058
OS -2.57071114 -38.6382514
OS -2.56978658 -38.63917596
OS -2.56886202 -38.64010052
OS -2.5670129 -38.6428742
OS -2.56331466 -38.64564788
OS -2.55961642 -38.64842156
OS -2.55406906 -38.6521198
OS -2.54759714 -38.65489348
OS -2.54020066 -38.65859172
OS -2.5392761 -38.65859172
OS -2.53742698 -38.65951628
OS -2.53372874 -38.66044084
OS -2.52725682 -38.66321452
OS -2.51801122 -38.6659882
OS -2.50599194 -38.66876188
OS -2.49859546 -38.67153556
OS -2.49027442 -38.67338468
OS -2.48102882 -38.67615836
OS -2.47085866 -38.67893204
OS -2.4699341 -38.67893204
OS -2.46716042 -38.6798566
OS -2.46253762 -38.68078116
OS -2.45699026 -38.68263028
OS -2.45051834 -38.6844794
OS -2.4421973 -38.68632852
OS -2.42463066 -38.69187588
OS -2.4052149 -38.69742324
OS -2.38579914 -38.70389516
OS -2.3682325 -38.71036708
OS -2.36083602 -38.71314076
OS -2.3543641 -38.71591444
OS -2.35251498 -38.716839
OS -2.34881674 -38.71868812
OS -2.34326938 -38.7214618
OS -2.33494834 -38.7260846
OS -2.3266273 -38.73163196
OS -2.31830626 -38.73902844
OS -2.30998522 -38.74734948
OS -2.30258874 -38.75659508
OS -2.30166418 -38.75751964
OS -2.29981506 -38.76121788
OS -2.29611682 -38.76676524
OS -2.29241858 -38.77508628
OS -2.2896449 -38.78525644
OS -2.28594666 -38.79635116
OS -2.28409754 -38.809295
OS -2.28317298 -38.82408796
OS -2.28317298 -38.82593708
OS -2.28317298 -38.83055988
OS -2.28409754 -38.83795636
OS -2.28594666 -38.84812652
OS -2.28872034 -38.85922124
OS -2.29334314 -38.87124052
OS -2.2988905 -38.88510892
OS -2.30628698 -38.89805276
OS -2.30721154 -38.89990188
OS -2.31090978 -38.90360012
OS -2.31553258 -38.91007204
OS -2.32292906 -38.91746852
OS -2.33309922 -38.92578956
OS -2.34419394 -38.93503516
OS -2.35713778 -38.9433562
OS -2.3728553 -38.95167724
OS -2.37377986 -38.95167724
OS -2.37470442 -38.9526018
OS -2.38025178 -38.95445092
OS -2.38949738 -38.9572246
OS -2.40151666 -38.96092284
OS -2.41630962 -38.96462108
OS -2.4329517 -38.96739476
OS -2.45051834 -38.96924388
OS -2.47085866 -38.97016844
OS -2.4791797 -38.97016844
OS -2.48565162 -38.96924388
OS -2.4930481 -38.96924388
OS -2.5022937 -38.96831932
OS -2.5115393 -38.96739476
OS -2.52170946 -38.96554564
OS -2.5438989 -38.96092284
OS -2.5670129 -38.95445092
OS -2.58920234 -38.94520532
OS -2.5993725 -38.93965796
OS -2.6086181 -38.93318604
OS -2.60954266 -38.93226148
OS -2.61046722 -38.93133692
OS -2.61601458 -38.92578956
OS -2.62433562 -38.91746852
OS -2.63358122 -38.90452468
OS -2.64375138 -38.88880716
OS -2.65392154 -38.87031596
OS -2.66224258 -38.84720196
OS -2.6687145 -38.82131428
OS -2.59105146 -38.809295
OS -2.59105146 -38.81021956
OS -2.59105146 -38.81114412
OS -2.58920234 -38.81669148
OS -2.58735322 -38.82593708
OS -2.58365498 -38.83610724
OS -2.57903218 -38.84720196
OS -2.57348482 -38.85922124
OS -2.56516378 -38.87124052
OS -2.55499362 -38.88141068
OS -2.5531445 -38.88233524
OS -2.54944626 -38.88510892
OS -2.54204978 -38.88880716
OS -2.53280418 -38.89342996
OS -2.5207849 -38.89805276
OS -2.5069165 -38.901751
OS -2.49027442 -38.90452468
OS -2.47085866 -38.90544924
OS -2.46161306 -38.90544924
OS -2.45236746 -38.90452468
OS -2.44034818 -38.90267556
OS -2.42740434 -38.89990188
OS -2.41353594 -38.89620364
OS -2.40151666 -38.89158084
OS -2.39042194 -38.88418436
OS -2.38949738 -38.8832598
OS -2.38579914 -38.88048612
OS -2.3821009 -38.87586332
OS -2.37655354 -38.8693914
OS -2.37193074 -38.86199492
OS -2.36730794 -38.85274932
OS -2.36453426 -38.84350372
OS -2.3636097 -38.832409
OS -2.3636097 -38.83148444
OS -2.3636097 -38.8277862
OS -2.36453426 -38.8231634
OS -2.36638338 -38.81669148
OS -2.36915706 -38.81021956
OS -2.37377986 -38.80374764
OS -2.37932722 -38.79635116
OS -2.38764826 -38.7908038
OS -2.38857282 -38.78987924
OS -2.3913465 -38.78895468
OS -2.3959693 -38.786181
OS -2.40336578 -38.78340732
OS -2.4144605 -38.77970908
OS -2.42093242 -38.7769354
OS -2.4283289 -38.77508628
OS -2.43664994 -38.7723126
OS -2.44589554 -38.76953892
OS -2.4560657 -38.76676524
OS -2.46808498 -38.76399156
OS -2.46900954 -38.76399156
OS -2.47178322 -38.763067
OS -2.47640602 -38.76214244
OS -2.48195338 -38.76029332
OS -2.48934986 -38.7584442
OS -2.4976709 -38.75567052
OS -2.51523754 -38.75104772
OS -2.53557786 -38.7445758
OS -2.55499362 -38.73902844
OS -2.57348482 -38.73255652
OS -2.58180586 -38.72885828
OS -2.58827778 -38.7260846
OS -2.5901269 -38.72516004
OS -2.59382514 -38.72331092
OS -2.5993725 -38.71961268
OS -2.60676898 -38.71498988
OS -2.61509002 -38.70851796
OS -2.62341106 -38.70112148
OS -2.6317321 -38.69280044
OS -2.63912858 -38.68263028
OS -2.64005314 -38.68170572
OS -2.64190226 -38.67800748
OS -2.64467594 -38.67153556
OS -2.64744962 -38.66413908
OS -2.6502233 -38.65489348
OS -2.65299698 -38.64379876
OS -2.6548461 -38.63270404
OS -2.65577066 -38.6197602
OS -2.65577066 -38.61791108
OS -2.65577066 -38.61421284
OS -2.6548461 -38.60866548
OS -2.65392154 -38.60034444
OS -2.65207242 -38.5920234
OS -2.6502233 -38.58185324
OS -2.64652506 -38.57260764
OS -2.64190226 -38.56243748
OS -2.6409777 -38.56151292
OS -2.63912858 -38.55781468
OS -2.6363549 -38.55319188
OS -2.6317321 -38.54671996
OS -2.62618474 -38.54024804
OS -2.61971282 -38.531927
OS -2.61231634 -38.52453052
OS -2.60307074 -38.5180586
OS -2.60214618 -38.51713404
OS -2.5993725 -38.51620948
OS -2.59567426 -38.5134358
OS -2.5901269 -38.51066212
OS -2.58273042 -38.50696388
OS -2.57440938 -38.50326564
OS -2.56423922 -38.4995674
OS -2.5531445 -38.49586916
OS -2.55129538 -38.4949446
OS -2.54759714 -38.49402004
OS -2.54112522 -38.49217092
OS -2.53280418 -38.4903218
OS -2.52263402 -38.48847268
OS -2.5115393 -38.48754812
OS -2.49859546 -38.485699
OS -2.47640602 -38.485699
OS -2.46623586 -38.48662356
OE
OB -1.98638922 -38.48662356 I
OS -1.97806818 -38.48754812
OS -1.96882258 -38.48939724
OS -1.95865242 -38.49124636
OS -1.94663314 -38.49309548
OS -1.92167002 -38.50141652
OS -1.90872618 -38.50603932
OS -1.89578234 -38.51251124
OS -1.8828385 -38.51898316
OS -1.86989466 -38.52822876
OS -1.85787538 -38.53747436
OS -1.8458561 -38.54856908
OS -1.84493154 -38.54949364
OS -1.84308242 -38.55134276
OS -1.84030874 -38.555041
OS -1.8366105 -38.5596638
OS -1.8319877 -38.56613572
OS -1.82644034 -38.57445676
OS -1.82089298 -38.58370236
OS -1.81534562 -38.59387252
OS -1.80979826 -38.60496724
OS -1.8042509 -38.61883564
OS -1.79870354 -38.63270404
OS -1.79408074 -38.64842156
OS -1.7903825 -38.66506364
OS -1.78760882 -38.68263028
OS -1.7857597 -38.70112148
OS -1.78483514 -38.7214618
OS -1.78483514 -38.72238636
OS -1.78483514 -38.72516004
OS -1.78483514 -38.72978284
OS -1.78483514 -38.73625476
OS -1.7857597 -38.74365124
OS -1.78668426 -38.75289684
OS -1.78668426 -38.76214244
OS -1.78853338 -38.7723126
OS -1.79130706 -38.7954266
OS -1.79685442 -38.8185406
OS -1.80332634 -38.8416546
OS -1.81257194 -38.86291948
OS -1.81257194 -38.86384404
OS -1.8134965 -38.8647686
OS -1.81534562 -38.86754228
OS -1.81719474 -38.87124052
OS -1.82366666 -38.88048612
OS -1.8319877 -38.89158084
OS -1.84308242 -38.90452468
OS -1.85695082 -38.91746852
OS -1.87266834 -38.93041236
OS -1.89115954 -38.94243164
OS -1.8920841 -38.94243164
OS -1.89300866 -38.9433562
OS -1.89578234 -38.94520532
OS -1.90040514 -38.94705444
OS -1.90502794 -38.94890356
OS -1.9105753 -38.95075268
OS -1.9244437 -38.95630004
OS -1.94016122 -38.96092284
OS -1.95957698 -38.96554564
OS -1.9799173 -38.96924388
OS -2.00210674 -38.97016844
OS -2.01135234 -38.97016844
OS -2.01874882 -38.96924388
OS -2.02706986 -38.96831932
OS -2.03631546 -38.9664702
OS -2.04741018 -38.96462108
OS -2.0585049 -38.96277196
OS -2.08346802 -38.95537548
OS -2.09733642 -38.94982812
OS -2.11028026 -38.94428076
OS -2.1232241 -38.93688428
OS -2.13616794 -38.92856324
OS -2.14818722 -38.91931764
OS -2.1602065 -38.90822292
OS -2.16113106 -38.90729836
OS -2.16298018 -38.90544924
OS -2.16575386 -38.901751
OS -2.1694521 -38.89620364
OS -2.1740749 -38.88973172
OS -2.1786977 -38.88233524
OS -2.18424506 -38.87308964
OS -2.18979242 -38.86199492
OS -2.19533978 -38.84997564
OS -2.20088714 -38.83610724
OS -2.20550994 -38.82131428
OS -2.21013274 -38.80559676
OS -2.21383098 -38.78803012
OS -2.21660466 -38.76953892
OS -2.21845378 -38.7491986
OS -2.21937834 -38.72793372
OS -2.21937834 -38.7260846
OS -2.21937834 -38.72238636
OS -2.21845378 -38.71591444
OS -2.21845378 -38.70666884
OS -2.21752922 -38.69649868
OS -2.2156801 -38.68355484
OS -2.21383098 -38.670611
OS -2.21013274 -38.65581804
OS -2.2064345 -38.64102508
OS -2.2018117 -38.62530756
OS -2.19626434 -38.60866548
OS -2.18886786 -38.59294796
OS -2.18147138 -38.578155
OS -2.17130122 -38.56336204
OS -2.16113106 -38.54949364
OS -2.14818722 -38.53747436
OS -2.14726266 -38.5365498
OS -2.14541354 -38.53562524
OS -2.1417153 -38.53285156
OS -2.1370925 -38.52915332
OS -2.13154514 -38.52545508
OS -2.12414866 -38.52083228
OS -2.11675218 -38.51620948
OS -2.10750658 -38.51158668
OS -2.09733642 -38.50696388
OS -2.0862417 -38.50234108
OS -2.06127858 -38.49402004
OS -2.03261722 -38.48754812
OS -2.01782426 -38.48662356
OS -2.00210674 -38.485699
OS -1.99286114 -38.485699
OS -1.98638922 -38.48662356
OE
OB -3.38339938 -38.48662356 I
OS -3.37692746 -38.48662356
OS -3.37045554 -38.48754812
OS -3.35473802 -38.4903218
OS -3.33809594 -38.4949446
OS -3.3205293 -38.50234108
OS -3.30296266 -38.51158668
OS -3.2881697 -38.52453052
OS -3.28632058 -38.52637964
OS -3.28262234 -38.531927
OS -3.27615042 -38.54024804
OS -3.27337674 -38.54671996
OS -3.2696785 -38.55319188
OS -3.26598026 -38.56151292
OS -3.26320658 -38.56983396
OS -3.25950834 -38.57907956
OS -3.25673466 -38.59017428
OS -3.25488554 -38.601269
OS -3.25303642 -38.61421284
OS -3.2511873 -38.62715668
OS -3.2511873 -38.64194964
OS -3.2511873 -38.95999828
OS -3.3297749 -38.95999828
OS -3.3297749 -38.66876188
OS -3.3297749 -38.66783732
OS -3.3297749 -38.66691276
OS -3.3297749 -38.6613654
OS -3.3297749 -38.65304436
OS -3.33069946 -38.6428742
OS -3.33162402 -38.63177948
OS -3.33254858 -38.62068476
OS -3.3343977 -38.60959004
OS -3.33717138 -38.601269
OS -3.33717138 -38.60034444
OS -3.3390205 -38.59757076
OS -3.34086962 -38.59387252
OS -3.3436433 -38.58924972
OS -3.34734154 -38.58370236
OS -3.35196434 -38.578155
OS -3.3575117 -38.57260764
OS -3.36490818 -38.56706028
OS -3.36583274 -38.56613572
OS -3.36860642 -38.56521116
OS -3.37230466 -38.56336204
OS -3.37877658 -38.56058836
OS -3.3852485 -38.55781468
OS -3.39356954 -38.55596556
OS -3.40189058 -38.555041
OS -3.41206074 -38.55411644
OS -3.41668354 -38.55411644
OS -3.42038178 -38.555041
OS -3.42962738 -38.55596556
OS -3.4407221 -38.55781468
OS -3.45366594 -38.56243748
OS -3.46753434 -38.56798484
OS -3.48140274 -38.57630588
OS -3.49434658 -38.5874006
OS -3.49527114 -38.58924972
OS -3.49896938 -38.59387252
OS -3.50451674 -38.601269
OS -3.5100641 -38.61236372
OS -3.51653602 -38.62715668
OS -3.52115882 -38.64472332
OS -3.52485706 -38.6659882
OS -3.52670618 -38.69095132
OS -3.52670618 -38.95999828
OS -3.60529378 -38.95999828
OS -3.60529378 -38.65951628
OS -3.60529378 -38.65859172
OS -3.60529378 -38.6567426
OS -3.60529378 -38.65489348
OS -3.60529378 -38.65119524
OS -3.60621834 -38.64102508
OS -3.60806746 -38.62993036
OS -3.60991658 -38.61698652
OS -3.61361482 -38.60404268
OS -3.61823762 -38.5920234
OS -3.62470954 -38.58092868
OS -3.6256341 -38.58000412
OS -3.62840778 -38.57630588
OS -3.63303058 -38.57260764
OS -3.6395025 -38.56706028
OS -3.64782354 -38.56243748
OS -3.65891826 -38.55781468
OS -3.6718621 -38.555041
OS -3.68757962 -38.55411644
OS -3.69312698 -38.55411644
OS -3.6995989 -38.555041
OS -3.70699538 -38.55596556
OS -3.71624098 -38.55873924
OS -3.7273357 -38.56151292
OS -3.73750586 -38.56613572
OS -3.74860058 -38.57168308
OS -3.74952514 -38.57260764
OS -3.75322338 -38.57538132
OS -3.75784618 -38.57907956
OS -3.7643181 -38.58462692
OS -3.77079002 -38.5920234
OS -3.77726194 -38.601269
OS -3.78373386 -38.61143916
OS -3.78928122 -38.62345844
OS -3.79020578 -38.62530756
OS -3.79113034 -38.62993036
OS -3.79297946 -38.63732684
OS -3.79575314 -38.647497
OS -3.79852682 -38.6613654
OS -3.80037594 -38.67800748
OS -3.8013005 -38.69742324
OS -3.80222506 -38.71961268
OS -3.80222506 -38.95999828
OS -3.88081266 -38.95999828
OS -3.88081266 -38.49586916
OS -3.8105461 -38.49586916
OS -3.8105461 -38.56243748
OS -3.80962154 -38.56058836
OS -3.80684786 -38.55689012
OS -3.8013005 -38.5504182
OS -3.79482858 -38.54302172
OS -3.78650754 -38.53377612
OS -3.77633738 -38.52453052
OS -3.76524266 -38.51528492
OS -3.75229882 -38.50696388
OS -3.7504497 -38.50603932
OS -3.7458269 -38.50326564
OS -3.73843042 -38.50049196
OS -3.72826026 -38.49586916
OS -3.71624098 -38.49217092
OS -3.70237258 -38.48939724
OS -3.68665506 -38.48662356
OS -3.67001298 -38.485699
OS -3.66169194 -38.485699
OS -3.65152178 -38.48662356
OS -3.64042706 -38.48847268
OS -3.62655866 -38.49124636
OS -3.61269026 -38.4949446
OS -3.59882186 -38.50049196
OS -3.58587802 -38.50788844
OS -3.5840289 -38.508813
OS -3.58033066 -38.51158668
OS -3.5747833 -38.51620948
OS -3.56738682 -38.52360596
OS -3.55999034 -38.531927
OS -3.5516693 -38.54209716
OS -3.54427282 -38.55411644
OS -3.53872546 -38.56798484
OS -3.5378009 -38.56706028
OS -3.53595178 -38.5642866
OS -3.5331781 -38.56058836
OS -3.5285553 -38.555041
OS -3.52300794 -38.54856908
OS -3.51653602 -38.54209716
OS -3.50913954 -38.53470068
OS -3.49989394 -38.52637964
OS -3.48972378 -38.51898316
OS -3.47955362 -38.51158668
OS -3.46753434 -38.50511476
OS -3.4545905 -38.49864284
OS -3.4407221 -38.49309548
OS -3.42592914 -38.48939724
OS -3.41113618 -38.48662356
OS -3.3944941 -38.485699
OS -3.38802218 -38.485699
OS -3.38339938 -38.48662356
OE
OB -2.6872057 -39.1375138 I
OS -3.20773298 -39.1375138
OS -3.20773298 -39.08111564
OS -2.6872057 -39.08111564
OS -2.6872057 -39.1375138
OE
OB -1.12100106 -38.95999828 I
OS -1.1940413 -38.95999828
OS -1.1940413 -38.901751
OS -1.19496586 -38.90267556
OS -1.19589042 -38.90452468
OS -1.1986641 -38.90822292
OS -1.20236234 -38.91284572
OS -1.20698514 -38.91746852
OS -1.2125325 -38.92301588
OS -1.21900442 -38.9294878
OS -1.22732546 -38.93595972
OS -1.2356465 -38.94243164
OS -1.2448921 -38.94890356
OS -1.25598682 -38.95445092
OS -1.2680061 -38.95907372
OS -1.28002538 -38.96369652
OS -1.29389378 -38.96739476
OS -1.30868674 -38.96924388
OS -1.32440426 -38.97016844
OS -1.32995162 -38.97016844
OS -1.33364986 -38.96924388
OS -1.34474458 -38.96831932
OS -1.35768842 -38.9664702
OS -1.37340594 -38.96277196
OS -1.39097258 -38.9572246
OS -1.40853922 -38.94982812
OS -1.42610586 -38.93965796
OS -1.42703042 -38.93965796
OS -1.42795498 -38.93780884
OS -1.43350234 -38.9341106
OS -1.44182338 -38.92671412
OS -1.45199354 -38.91746852
OS -1.46401282 -38.90544924
OS -1.4760321 -38.89065628
OS -1.48805138 -38.8740142
OS -1.49822154 -38.85459844
OS -1.49822154 -38.85367388
OS -1.4991461 -38.85182476
OS -1.50007066 -38.84905108
OS -1.50191978 -38.84535284
OS -1.5037689 -38.83980548
OS -1.50654258 -38.83333356
OS -1.5083917 -38.82686164
OS -1.51024082 -38.8185406
OS -1.51486362 -38.8000494
OS -1.51948642 -38.77878452
OS -1.5222601 -38.75474596
OS -1.52318466 -38.72885828
OS -1.52318466 -38.72793372
OS -1.52318466 -38.7260846
OS -1.52318466 -38.72238636
OS -1.52318466 -38.716839
OS -1.5222601 -38.71129164
OS -1.5222601 -38.70389516
OS -1.52041098 -38.68725308
OS -1.5176373 -38.66783732
OS -1.5130145 -38.64657244
OS -1.50746714 -38.624383
OS -1.50007066 -38.60311812
OS -1.50007066 -38.60219356
OS -1.4991461 -38.60034444
OS -1.49729698 -38.59757076
OS -1.49544786 -38.59387252
OS -1.4899005 -38.58370236
OS -1.48250402 -38.57075852
OS -1.47325842 -38.55689012
OS -1.46123914 -38.54302172
OS -1.44737074 -38.52822876
OS -1.43072866 -38.51620948
OS -1.4298041 -38.51620948
OS -1.42887954 -38.51528492
OS -1.42610586 -38.5134358
OS -1.42240762 -38.51158668
OS -1.41316202 -38.50696388
OS -1.40021818 -38.50049196
OS -1.38542522 -38.4949446
OS -1.36785858 -38.4903218
OS -1.34844282 -38.48662356
OS -1.3281025 -38.485699
OS -1.32070602 -38.485699
OS -1.31330954 -38.48662356
OS -1.30313938 -38.48754812
OS -1.2911201 -38.4903218
OS -1.27817626 -38.49309548
OS -1.26523242 -38.49771828
OS -1.25321314 -38.5041902
OS -1.25136402 -38.50511476
OS -1.24766578 -38.50696388
OS -1.24211842 -38.51158668
OS -1.23472194 -38.51620948
OS -1.22547634 -38.5226814
OS -1.2171553 -38.53100244
OS -1.2079097 -38.53932348
OS -1.19958866 -38.54949364
OS -1.19958866 -38.32020276
OS -1.12100106 -38.32020276
OS -1.12100106 -38.95999828
OE
OB -0.31386018 -38.48662356 I
OS -0.30369002 -38.48847268
OS -0.29167074 -38.49217092
OS -0.2787269 -38.49679372
OS -0.26393394 -38.50326564
OS -0.24821642 -38.51158668
OS -0.27687778 -38.58370236
OS -0.27780234 -38.5827778
OS -0.28150058 -38.58092868
OS -0.28704794 -38.578155
OS -0.29444442 -38.57538132
OS -0.30276546 -38.57260764
OS -0.31293562 -38.56983396
OS -0.32310578 -38.56798484
OS -0.33327594 -38.56706028
OS -0.33789874 -38.56706028
OS -0.34252154 -38.56798484
OS -0.34899346 -38.5689094
OS -0.35546538 -38.57075852
OS -0.36378642 -38.5735322
OS -0.37210746 -38.57723044
OS -0.37950394 -38.5827778
OS -0.3804285 -38.58370236
OS -0.38320218 -38.58555148
OS -0.38597586 -38.58924972
OS -0.39059866 -38.59387252
OS -0.39522146 -38.60034444
OS -0.39984426 -38.60774092
OS -0.40446706 -38.61606196
OS -0.4081653 -38.62623212
OS -0.40908986 -38.62808124
OS -0.41001442 -38.6336286
OS -0.41186354 -38.64194964
OS -0.41463722 -38.65304436
OS -0.4174109 -38.66691276
OS -0.41926002 -38.68263028
OS -0.42018458 -38.69927236
OS -0.42110914 -38.71776356
OS -0.42110914 -38.95999828
OS -0.49969674 -38.95999828
OS -0.49969674 -38.49586916
OS -0.42850562 -38.49586916
OS -0.42850562 -38.56613572
OS -0.42758106 -38.56521116
OS -0.42388282 -38.55873924
OS -0.41926002 -38.5504182
OS -0.41186354 -38.54024804
OS -0.40446706 -38.53007788
OS -0.39614602 -38.51898316
OS -0.38782498 -38.50973756
OS -0.37950394 -38.50234108
OS -0.37857938 -38.50141652
OS -0.3758057 -38.4995674
OS -0.37025834 -38.49679372
OS -0.36471098 -38.49402004
OS -0.3573145 -38.49124636
OS -0.3480689 -38.48847268
OS -0.3388233 -38.48662356
OS -0.32865314 -38.485699
OS -0.32218122 -38.485699
OS -0.31386018 -38.48662356
OE
OB -0.1307973 -38.42745172 I
OS -0.15206218 -38.54671996
OS -0.20106386 -38.54671996
OS -0.22047962 -38.42745172
OS -0.22047962 -38.32020276
OS -0.1307973 -38.32020276
OS -0.1307973 -38.42745172
OE
OB -1.61564066 -38.95999828 I
OS -1.69422826 -38.95999828
OS -1.69422826 -38.32020276
OS -1.61564066 -38.32020276
OS -1.61564066 -38.95999828
OE
OB -0.79093314 -38.48662356 I
OS -0.78353666 -38.48754812
OS -0.77429106 -38.48939724
OS -0.7641209 -38.49124636
OS -0.75210162 -38.49402004
OS -0.7410069 -38.49679372
OS -0.72806306 -38.50141652
OS -0.71604378 -38.50603932
OS -0.70309994 -38.51251124
OS -0.6901561 -38.51990772
OS -0.67721226 -38.52822876
OS -0.66519298 -38.53839892
OS -0.65409826 -38.54949364
OS -0.6531737 -38.5504182
OS -0.65132458 -38.55226732
OS -0.6485509 -38.55596556
OS -0.64485266 -38.56151292
OS -0.64022986 -38.56798484
OS -0.63560706 -38.57538132
OS -0.6300597 -38.58462692
OS -0.62451234 -38.59572164
OS -0.61896498 -38.60774092
OS -0.61341762 -38.62068476
OS -0.60879482 -38.63547772
OS -0.60417202 -38.65119524
OS -0.60047378 -38.66876188
OS -0.5977001 -38.68725308
OS -0.59585098 -38.70666884
OS -0.59492642 -38.72793372
OS -0.59492642 -38.72885828
OS -0.59492642 -38.73255652
OS -0.59492642 -38.73902844
OS -0.59585098 -38.74827404
OS -0.94256098 -38.74827404
OS -0.94256098 -38.7491986
OS -0.94256098 -38.75197228
OS -0.94163642 -38.75567052
OS -0.94163642 -38.76121788
OS -0.94071186 -38.7676898
OS -0.93886274 -38.77508628
OS -0.93608906 -38.79172836
OS -0.9305417 -38.81021956
OS -0.92314522 -38.83055988
OS -0.91297506 -38.84905108
OS -0.90003122 -38.86569316
OS -0.89910666 -38.86569316
OS -0.8981821 -38.86754228
OS -0.89263474 -38.87216508
OS -0.8843137 -38.878637
OS -0.87321898 -38.88510892
OS -0.85842602 -38.8925054
OS -0.84178394 -38.89897732
OS -0.82329274 -38.90360012
OS -0.81312258 -38.90452468
OS -0.80202786 -38.90544924
OS -0.79463138 -38.90544924
OS -0.78631034 -38.90452468
OS -0.77614018 -38.90267556
OS -0.76504546 -38.89990188
OS -0.75210162 -38.89620364
OS -0.74008234 -38.89065628
OS -0.72806306 -38.8832598
OS -0.7271385 -38.88233524
OS -0.7225157 -38.878637
OS -0.71696834 -38.87308964
OS -0.71049642 -38.86569316
OS -0.70309994 -38.855523
OS -0.6947789 -38.84257916
OS -0.68645786 -38.8277862
OS -0.67906138 -38.81021956
OS -0.5977001 -38.82038972
OS -0.5977001 -38.82131428
OS -0.59862466 -38.8231634
OS -0.59954922 -38.82686164
OS -0.60139834 -38.832409
OS -0.60417202 -38.83795636
OS -0.6069457 -38.84535284
OS -0.61434218 -38.86107036
OS -0.62358778 -38.878637
OS -0.63653162 -38.8971282
OS -0.65132458 -38.91469484
OS -0.66981578 -38.93133692
OS -0.67074034 -38.93133692
OS -0.67258946 -38.93318604
OS -0.67536314 -38.93503516
OS -0.67906138 -38.93780884
OS -0.68460874 -38.94058252
OS -0.6901561 -38.9433562
OS -0.69755258 -38.94705444
OS -0.70587362 -38.95075268
OS -0.71511922 -38.95445092
OS -0.72436482 -38.95814916
OS -0.74747882 -38.96369652
OS -0.7733665 -38.96831932
OS -0.80202786 -38.97016844
OS -0.81219802 -38.97016844
OS -0.81866994 -38.96924388
OS -0.82699098 -38.96831932
OS -0.83716114 -38.9664702
OS -0.84825586 -38.96462108
OS -0.86027514 -38.96277196
OS -0.88616282 -38.95537548
OS -0.90003122 -38.94982812
OS -0.91297506 -38.94428076
OS -0.92684346 -38.93688428
OS -0.9397873 -38.92856324
OS -0.95180658 -38.91931764
OS -0.96382586 -38.90822292
OS -0.96475042 -38.90729836
OS -0.96659954 -38.90544924
OS -0.96937322 -38.901751
OS -0.97307146 -38.89620364
OS -0.97769426 -38.88973172
OS -0.98231706 -38.88233524
OS -0.98786442 -38.87308964
OS -0.99341178 -38.86291948
OS -0.99895914 -38.8509002
OS -1.0045065 -38.83795636
OS -1.0091293 -38.8231634
OS -1.0137521 -38.80744588
OS -1.01745034 -38.7908038
OS -1.02022402 -38.7723126
OS -1.02207314 -38.75289684
OS -1.0229977 -38.73255652
OS -1.0229977 -38.73163196
OS -1.0229977 -38.72700916
OS -1.0229977 -38.7214618
OS -1.02207314 -38.71314076
OS -1.02114858 -38.7029706
OS -1.02022402 -38.69187588
OS -1.0183749 -38.67893204
OS -1.01560122 -38.6659882
OS -1.00820474 -38.63640228
OS -1.00358194 -38.62160932
OS -0.99803458 -38.6058918
OS -0.9906381 -38.59109884
OS -0.98231706 -38.57723044
OS -0.97307146 -38.56336204
OS -0.9629013 -38.5504182
OS -0.96197674 -38.54949364
OS -0.96012762 -38.54764452
OS -0.95642938 -38.54487084
OS -0.95180658 -38.54024804
OS -0.94625922 -38.53562524
OS -0.93886274 -38.53007788
OS -0.9305417 -38.52360596
OS -0.92037154 -38.5180586
OS -0.91020138 -38.51158668
OS -0.8981821 -38.50603932
OS -0.88523826 -38.50049196
OS -0.87136986 -38.49586916
OS -0.8565769 -38.49124636
OS -0.84085938 -38.48847268
OS -0.8242173 -38.48662356
OS -0.80665066 -38.485699
OS -0.79740506 -38.485699
OS -0.79093314 -38.48662356
OE
OB -5.16872474 -38.48662356 I
OS -5.1604037 -38.48754812
OS -5.1511581 -38.48939724
OS -5.14098794 -38.49124636
OS -5.12896866 -38.49309548
OS -5.10400554 -38.50141652
OS -5.0910617 -38.50603932
OS -5.07811786 -38.51251124
OS -5.06517402 -38.51898316
OS -5.05223018 -38.52822876
OS -5.0402109 -38.53747436
OS -5.02819162 -38.54856908
OS -5.02726706 -38.54949364
OS -5.02541794 -38.55134276
OS -5.02264426 -38.555041
OS -5.01894602 -38.5596638
OS -5.01432322 -38.56613572
OS -5.00877586 -38.57445676
OS -5.0032285 -38.58370236
OS -4.99768114 -38.59387252
OS -4.99213378 -38.60496724
OS -4.98658642 -38.61883564
OS -4.98103906 -38.63270404
OS -4.97641626 -38.64842156
OS -4.97271802 -38.66506364
OS -4.96994434 -38.68263028
OS -4.96809522 -38.70112148
OS -4.96717066 -38.7214618
OS -4.96717066 -38.72238636
OS -4.96717066 -38.72516004
OS -4.96717066 -38.72978284
OS -4.96717066 -38.73625476
OS -4.96809522 -38.74365124
OS -4.96901978 -38.75289684
OS -4.96901978 -38.76214244
OS -4.9708689 -38.7723126
OS -4.97364258 -38.7954266
OS -4.97918994 -38.8185406
OS -4.98566186 -38.8416546
OS -4.99490746 -38.86291948
OS -4.99490746 -38.86384404
OS -4.99583202 -38.8647686
OS -4.99768114 -38.86754228
OS -4.99953026 -38.87124052
OS -5.00600218 -38.88048612
OS -5.01432322 -38.89158084
OS -5.02541794 -38.90452468
OS -5.03928634 -38.91746852
OS -5.05500386 -38.93041236
OS -5.07349506 -38.94243164
OS -5.07441962 -38.94243164
OS -5.07534418 -38.9433562
OS -5.07811786 -38.94520532
OS -5.08274066 -38.94705444
OS -5.08736346 -38.94890356
OS -5.09291082 -38.95075268
OS -5.10677922 -38.95630004
OS -5.12249674 -38.96092284
OS -5.1419125 -38.96554564
OS -5.16225282 -38.96924388
OS -5.18444226 -38.97016844
OS -5.19368786 -38.97016844
OS -5.20108434 -38.96924388
OS -5.20940538 -38.96831932
OS -5.21865098 -38.9664702
OS -5.2297457 -38.96462108
OS -5.24084042 -38.96277196
OS -5.26580354 -38.95537548
OS -5.27967194 -38.94982812
OS -5.29261578 -38.94428076
OS -5.30555962 -38.93688428
OS -5.31850346 -38.92856324
OS -5.33052274 -38.91931764
OS -5.34254202 -38.90822292
OS -5.34346658 -38.90729836
OS -5.3453157 -38.90544924
OS -5.34808938 -38.901751
OS -5.35178762 -38.89620364
OS -5.35641042 -38.88973172
OS -5.36103322 -38.88233524
OS -5.36658058 -38.87308964
OS -5.37212794 -38.86199492
OS -5.3776753 -38.84997564
OS -5.38322266 -38.83610724
OS -5.38784546 -38.82131428
OS -5.39246826 -38.80559676
OS -5.3961665 -38.78803012
OS -5.39894018 -38.76953892
OS -5.4007893 -38.7491986
OS -5.40171386 -38.72793372
OS -5.40171386 -38.7260846
OS -5.40171386 -38.72238636
OS -5.4007893 -38.71591444
OS -5.4007893 -38.70666884
OS -5.39986474 -38.69649868
OS -5.39801562 -38.68355484
OS -5.3961665 -38.670611
OS -5.39246826 -38.65581804
OS -5.38877002 -38.64102508
OS -5.38414722 -38.62530756
OS -5.37859986 -38.60866548
OS -5.37120338 -38.59294796
OS -5.3638069 -38.578155
OS -5.35363674 -38.56336204
OS -5.34346658 -38.54949364
OS -5.33052274 -38.53747436
OS -5.32959818 -38.5365498
OS -5.32774906 -38.53562524
OS -5.32405082 -38.53285156
OS -5.31942802 -38.52915332
OS -5.31388066 -38.52545508
OS -5.30648418 -38.52083228
OS -5.2990877 -38.51620948
OS -5.2898421 -38.51158668
OS -5.27967194 -38.50696388
OS -5.26857722 -38.50234108
OS -5.2436141 -38.49402004
OS -5.21495274 -38.48754812
OS -5.20015978 -38.48662356
OS -5.18444226 -38.485699
OS -5.17519666 -38.485699
OS -5.16872474 -38.48662356
OE
OB -4.78318322 -38.49586916 I
OS -4.70367106 -38.49586916
OS -4.70367106 -38.55689012
OS -4.78318322 -38.55689012
OS -4.78318322 -38.82963532
OS -4.78318322 -38.83148444
OS -4.78318322 -38.83518268
OS -4.78318322 -38.84073004
OS -4.78225866 -38.84720196
OS -4.7813341 -38.86199492
OS -4.78040954 -38.86846684
OS -4.77948498 -38.87308964
OS -4.77856042 -38.87493876
OS -4.77578674 -38.878637
OS -4.7720885 -38.8832598
OS -4.76561658 -38.8878826
OS -4.76376746 -38.88880716
OS -4.75914466 -38.89065628
OS -4.75082362 -38.8925054
OS -4.73880434 -38.89342996
OS -4.72955874 -38.89342996
OS -4.72493594 -38.8925054
OS -4.71846402 -38.8925054
OS -4.71106754 -38.89158084
OS -4.70367106 -38.89065628
OS -4.6935009 -38.95999828
OS -4.69535002 -38.95999828
OS -4.69904826 -38.96092284
OS -4.70552018 -38.9618474
OS -4.71384122 -38.96277196
OS -4.72308682 -38.96462108
OS -4.73325698 -38.96554564
OS -4.7535973 -38.9664702
OS -4.76099378 -38.9664702
OS -4.76839026 -38.96554564
OS -4.77763586 -38.96462108
OS -4.78873058 -38.96369652
OS -4.7998253 -38.96092284
OS -4.80999546 -38.95814916
OS -4.82016562 -38.95352636
OS -4.82109018 -38.9526018
OS -4.82386386 -38.95075268
OS -4.8275621 -38.947979
OS -4.83310946 -38.9433562
OS -4.83773226 -38.9387334
OS -4.84327962 -38.93226148
OS -4.84882698 -38.92578956
OS -4.85252522 -38.91746852
OS -4.85252522 -38.91654396
OS -4.85437434 -38.91284572
OS -4.8552989 -38.9063738
OS -4.85714802 -38.8971282
OS -4.85899714 -38.88510892
OS -4.8599217 -38.87771244
OS -4.8599217 -38.8693914
OS -4.86084626 -38.85922124
OS -4.86177082 -38.84905108
OS -4.86177082 -38.83795636
OS -4.86177082 -38.82501252
OS -4.86177082 -38.55689012
OS -4.9200181 -38.55689012
OS -4.9200181 -38.49586916
OS -4.86177082 -38.49586916
OS -4.86177082 -38.38122372
OS -4.78318322 -38.33407116
OS -4.78318322 -38.49586916
OE
OB -5.79280274 -38.54856908 I
OS -5.79187818 -38.54764452
OS -5.79095362 -38.5457954
OS -5.78817994 -38.54302172
OS -5.78355714 -38.53839892
OS -5.77893434 -38.53377612
OS -5.77338698 -38.52822876
OS -5.7659905 -38.5226814
OS -5.75859402 -38.51713404
OS -5.74010282 -38.50511476
OS -5.71883794 -38.49586916
OS -5.70681866 -38.49124636
OS -5.69387482 -38.48847268
OS -5.68000642 -38.48662356
OS -5.66613802 -38.485699
OS -5.65874154 -38.485699
OS -5.6504205 -38.48662356
OS -5.64025034 -38.48754812
OS -5.62823106 -38.4903218
OS -5.61436266 -38.49309548
OS -5.5995697 -38.49771828
OS -5.5857013 -38.50326564
OS -5.58385218 -38.5041902
OS -5.57922938 -38.50603932
OS -5.5718329 -38.51066212
OS -5.56351186 -38.51620948
OS -5.5533417 -38.5226814
OS -5.54317154 -38.53100244
OS -5.53207682 -38.5411726
OS -5.52283122 -38.55226732
OS -5.52190666 -38.55319188
OS -5.51913298 -38.55781468
OS -5.51451018 -38.5642866
OS -5.50896282 -38.57260764
OS -5.5024909 -38.58370236
OS -5.49601898 -38.5966462
OS -5.48954706 -38.61143916
OS -5.4839997 -38.62715668
OS -5.4839997 -38.62808124
OS -5.48307514 -38.6290058
OS -5.48215058 -38.63177948
OS -5.48122602 -38.63455316
OS -5.4793769 -38.64379876
OS -5.47660322 -38.65581804
OS -5.47382954 -38.66968644
OS -5.47105586 -38.68540396
OS -5.4701313 -38.7029706
OS -5.46920674 -38.7214618
OS -5.46920674 -38.72238636
OS -5.46920674 -38.72700916
OS -5.46920674 -38.73255652
OS -5.4701313 -38.74087756
OS -5.47105586 -38.75104772
OS -5.47198042 -38.76214244
OS -5.47382954 -38.77508628
OS -5.47660322 -38.78895468
OS -5.4839997 -38.8185406
OS -5.4886225 -38.83425812
OS -5.49416986 -38.84905108
OS -5.50064178 -38.8647686
OS -5.50896282 -38.878637
OS -5.51820842 -38.8925054
OS -5.52837858 -38.90544924
OS -5.52930314 -38.9063738
OS -5.53115226 -38.90822292
OS -5.53392594 -38.9109966
OS -5.53854874 -38.9156194
OS -5.54502066 -38.9202422
OS -5.55149258 -38.92578956
OS -5.55888906 -38.93133692
OS -5.56813466 -38.93780884
OS -5.57830482 -38.9433562
OS -5.58847498 -38.94982812
OS -5.6134381 -38.95999828
OS -5.62638194 -38.96462108
OS -5.64025034 -38.96739476
OS -5.6550433 -38.96924388
OS -5.66983626 -38.97016844
OS -5.6735345 -38.97016844
OS -5.6781573 -38.96924388
OS -5.68370466 -38.96924388
OS -5.69017658 -38.96831932
OS -5.69849762 -38.9664702
OS -5.71698882 -38.9618474
OS -5.72715898 -38.95814916
OS -5.73732914 -38.95352636
OS -5.74842386 -38.947979
OS -5.75859402 -38.94150708
OS -5.76968874 -38.93318604
OS -5.7798589 -38.92394044
OS -5.7891045 -38.91377028
OS -5.7983501 -38.901751
OS -5.7983501 -38.95999828
OS -5.87139034 -38.95999828
OS -5.87139034 -38.32020276
OS -5.79280274 -38.32020276
OS -5.79280274 -38.54856908
OE
OB -5.97031826 -38.42745172 I
OS -5.99158314 -38.54671996
OS -6.04058482 -38.54671996
OS -6.06000058 -38.42745172
OS -6.06000058 -38.32020276
OS -5.97031826 -38.32020276
OS -5.97031826 -38.42745172
OE
OB -4.17389818 -38.48662356 I
OS -4.16557714 -38.48754812
OS -4.15633154 -38.48939724
OS -4.14616138 -38.49124636
OS -4.1341421 -38.49309548
OS -4.10917898 -38.50141652
OS -4.09623514 -38.50603932
OS -4.0832913 -38.51251124
OS -4.07034746 -38.51898316
OS -4.05740362 -38.52822876
OS -4.04538434 -38.53747436
OS -4.03336506 -38.54856908
OS -4.0324405 -38.54949364
OS -4.03059138 -38.55134276
OS -4.0278177 -38.555041
OS -4.02411946 -38.5596638
OS -4.01949666 -38.56613572
OS -4.0139493 -38.57445676
OS -4.00840194 -38.58370236
OS -4.00285458 -38.59387252
OS -3.99730722 -38.60496724
OS -3.99175986 -38.61883564
OS -3.9862125 -38.63270404
OS -3.9815897 -38.64842156
OS -3.97789146 -38.66506364
OS -3.97511778 -38.68263028
OS -3.97326866 -38.70112148
OS -3.9723441 -38.7214618
OS -3.9723441 -38.72238636
OS -3.9723441 -38.72516004
OS -3.9723441 -38.72978284
OS -3.9723441 -38.73625476
OS -3.97326866 -38.74365124
OS -3.97419322 -38.75289684
OS -3.97419322 -38.76214244
OS -3.97604234 -38.7723126
OS -3.97881602 -38.7954266
OS -3.98436338 -38.8185406
OS -3.9908353 -38.8416546
OS -4.0000809 -38.86291948
OS -4.0000809 -38.86384404
OS -4.00100546 -38.8647686
OS -4.00285458 -38.86754228
OS -4.0047037 -38.87124052
OS -4.01117562 -38.88048612
OS -4.01949666 -38.89158084
OS -4.03059138 -38.90452468
OS -4.04445978 -38.91746852
OS -4.0601773 -38.93041236
OS -4.0786685 -38.94243164
OS -4.07959306 -38.94243164
OS -4.08051762 -38.9433562
OS -4.0832913 -38.94520532
OS -4.0879141 -38.94705444
OS -4.0925369 -38.94890356
OS -4.09808426 -38.95075268
OS -4.11195266 -38.95630004
OS -4.12767018 -38.96092284
OS -4.14708594 -38.96554564
OS -4.16742626 -38.96924388
OS -4.1896157 -38.97016844
OS -4.1988613 -38.97016844
OS -4.20625778 -38.96924388
OS -4.21457882 -38.96831932
OS -4.22382442 -38.9664702
OS -4.23491914 -38.96462108
OS -4.24601386 -38.96277196
OS -4.27097698 -38.95537548
OS -4.28484538 -38.94982812
OS -4.29778922 -38.94428076
OS -4.31073306 -38.93688428
OS -4.3236769 -38.92856324
OS -4.33569618 -38.91931764
OS -4.34771546 -38.90822292
OS -4.34864002 -38.90729836
OS -4.35048914 -38.90544924
OS -4.35326282 -38.901751
OS -4.35696106 -38.89620364
OS -4.36158386 -38.88973172
OS -4.36620666 -38.88233524
OS -4.37175402 -38.87308964
OS -4.37730138 -38.86199492
OS -4.38284874 -38.84997564
OS -4.3883961 -38.83610724
OS -4.3930189 -38.82131428
OS -4.3976417 -38.80559676
OS -4.40133994 -38.78803012
OS -4.40411362 -38.76953892
OS -4.40596274 -38.7491986
OS -4.4068873 -38.72793372
OS -4.4068873 -38.7260846
OS -4.4068873 -38.72238636
OS -4.40596274 -38.71591444
OS -4.40596274 -38.70666884
OS -4.40503818 -38.69649868
OS -4.40318906 -38.68355484
OS -4.40133994 -38.670611
OS -4.3976417 -38.65581804
OS -4.39394346 -38.64102508
OS -4.38932066 -38.62530756
OS -4.3837733 -38.60866548
OS -4.37637682 -38.59294796
OS -4.36898034 -38.578155
OS -4.35881018 -38.56336204
OS -4.34864002 -38.54949364
OS -4.33569618 -38.53747436
OS -4.33477162 -38.5365498
OS -4.3329225 -38.53562524
OS -4.32922426 -38.53285156
OS -4.32460146 -38.52915332
OS -4.3190541 -38.52545508
OS -4.31165762 -38.52083228
OS -4.30426114 -38.51620948
OS -4.29501554 -38.51158668
OS -4.28484538 -38.50696388
OS -4.27375066 -38.50234108
OS -4.24878754 -38.49402004
OS -4.22012618 -38.48754812
OS -4.20533322 -38.48662356
OS -4.1896157 -38.485699
OS -4.1803701 -38.485699
OS -4.17389818 -38.48662356
OE
OB -4.53447658 -38.49586916 I
OS -4.45496442 -38.49586916
OS -4.45496442 -38.55689012
OS -4.53447658 -38.55689012
OS -4.53447658 -38.82963532
OS -4.53447658 -38.83148444
OS -4.53447658 -38.83518268
OS -4.53447658 -38.84073004
OS -4.53355202 -38.84720196
OS -4.53262746 -38.86199492
OS -4.5317029 -38.86846684
OS -4.53077834 -38.87308964
OS -4.52985378 -38.87493876
OS -4.5270801 -38.878637
OS -4.52338186 -38.8832598
OS -4.51690994 -38.8878826
OS -4.51506082 -38.88880716
OS -4.51043802 -38.89065628
OS -4.50211698 -38.8925054
OS -4.4900977 -38.89342996
OS -4.4808521 -38.89342996
OS -4.4762293 -38.8925054
OS -4.46975738 -38.8925054
OS -4.4623609 -38.89158084
OS -4.45496442 -38.89065628
OS -4.44479426 -38.95999828
OS -4.44664338 -38.95999828
OS -4.45034162 -38.96092284
OS -4.45681354 -38.9618474
OS -4.46513458 -38.96277196
OS -4.47438018 -38.96462108
OS -4.48455034 -38.96554564
OS -4.50489066 -38.9664702
OS -4.51228714 -38.9664702
OS -4.51968362 -38.96554564
OS -4.52892922 -38.96462108
OS -4.54002394 -38.96369652
OS -4.55111866 -38.96092284
OS -4.56128882 -38.95814916
OS -4.57145898 -38.95352636
OS -4.57238354 -38.9526018
OS -4.57515722 -38.95075268
OS -4.57885546 -38.947979
OS -4.58440282 -38.9433562
OS -4.58902562 -38.9387334
OS -4.59457298 -38.93226148
OS -4.60012034 -38.92578956
OS -4.60381858 -38.91746852
OS -4.60381858 -38.91654396
OS -4.6056677 -38.91284572
OS -4.60659226 -38.9063738
OS -4.60844138 -38.8971282
OS -4.6102905 -38.88510892
OS -4.61121506 -38.87771244
OS -4.61121506 -38.8693914
OS -4.61213962 -38.85922124
OS -4.61306418 -38.84905108
OS -4.61306418 -38.83795636
OS -4.61306418 -38.82501252
OS -4.61306418 -38.55689012
OS -4.67131146 -38.55689012
OS -4.67131146 -38.49586916
OS -4.61306418 -38.49586916
OS -4.61306418 -38.38122372
OS -4.53447658 -38.33407116
OS -4.53447658 -38.49586916
OE
OB -4.1896157 -38.5504182 H
OS -4.19516306 -38.5504182
OS -4.19978586 -38.55134276
OS -4.20995602 -38.55226732
OS -4.22382442 -38.55596556
OS -4.23954194 -38.56151292
OS -4.25618402 -38.5689094
OS -4.27190154 -38.58000412
OS -4.28022258 -38.5874006
OS -4.28761906 -38.59479708
OS -4.28761906 -38.59572164
OS -4.28946818 -38.5966462
OS -4.2913173 -38.59941988
OS -4.29409098 -38.60311812
OS -4.29686466 -38.60774092
OS -4.29963834 -38.61328828
OS -4.30333658 -38.62068476
OS -4.30703482 -38.62808124
OS -4.31073306 -38.63732684
OS -4.3144313 -38.64657244
OS -4.31720498 -38.65766716
OS -4.31997866 -38.66968644
OS -4.32275234 -38.68263028
OS -4.32460146 -38.69649868
OS -4.32552602 -38.7122162
OS -4.32645058 -38.72793372
OS -4.32645058 -38.72885828
OS -4.32645058 -38.73163196
OS -4.32645058 -38.73625476
OS -4.32552602 -38.74272668
OS -4.32552602 -38.75012316
OS -4.32460146 -38.7584442
OS -4.32182778 -38.77785996
OS -4.31720498 -38.8000494
OS -4.3098085 -38.82223884
OS -4.3005629 -38.84350372
OS -4.29409098 -38.85274932
OS -4.28761906 -38.86199492
OS -4.2866945 -38.86199492
OS -4.28576994 -38.86384404
OS -4.28022258 -38.86846684
OS -4.27190154 -38.87586332
OS -4.26080682 -38.8832598
OS -4.24693842 -38.89158084
OS -4.23029634 -38.89897732
OS -4.21088058 -38.90360012
OS -4.20071042 -38.90452468
OS -4.1896157 -38.90544924
OS -4.18406834 -38.90544924
OS -4.17944554 -38.90452468
OS -4.16927538 -38.90267556
OS -4.15540698 -38.89990188
OS -4.14061402 -38.89435452
OS -4.12397194 -38.88695804
OS -4.10825442 -38.87586332
OS -4.09993338 -38.86846684
OS -4.0925369 -38.86107036
OS -4.09161234 -38.8601458
OS -4.09068778 -38.85922124
OS -4.08883866 -38.85644756
OS -4.08606498 -38.85274932
OS -4.0832913 -38.84812652
OS -4.07959306 -38.84257916
OS -4.07589482 -38.83518268
OS -4.07219658 -38.8277862
OS -4.06849834 -38.8185406
OS -4.06572466 -38.80837044
OS -4.06202642 -38.79727572
OS -4.05925274 -38.78525644
OS -4.05647906 -38.77138804
OS -4.05462994 -38.75751964
OS -4.05278082 -38.74180212
OS -4.05278082 -38.72516004
OS -4.05278082 -38.72423548
OS -4.05278082 -38.7214618
OS -4.05278082 -38.716839
OS -4.05370538 -38.71129164
OS -4.05370538 -38.70389516
OS -4.05462994 -38.69557412
OS -4.05740362 -38.67615836
OS -4.06202642 -38.65581804
OS -4.0694229 -38.6336286
OS -4.07959306 -38.61328828
OS -4.08514042 -38.60311812
OS -4.0925369 -38.59479708
OS -4.0925369 -38.59387252
OS -4.09438602 -38.59294796
OS -4.09993338 -38.5874006
OS -4.10825442 -38.58092868
OS -4.11934914 -38.57260764
OS -4.13321754 -38.5642866
OS -4.14985962 -38.55689012
OS -4.16835082 -38.55226732
OS -4.17852098 -38.55134276
OS -4.1896157 -38.5504182
OE
OB -5.6642889 -38.5504182 H
OS -5.6781573 -38.5504182
OS -5.68185554 -38.55134276
OS -5.6920257 -38.55319188
OS -5.70404498 -38.55596556
OS -5.71791338 -38.56151292
OS -5.73270634 -38.56983396
OS -5.74010282 -38.57445676
OS -5.7474993 -38.58092868
OS -5.75489578 -38.5874006
OS -5.76229226 -38.59572164
OS -5.76229226 -38.5966462
OS -5.76414138 -38.59757076
OS -5.7659905 -38.60034444
OS -5.76783962 -38.60404268
OS -5.7706133 -38.60866548
OS -5.77431154 -38.61421284
OS -5.77708522 -38.62068476
OS -5.78078346 -38.62808124
OS -5.7844817 -38.63732684
OS -5.78725538 -38.64657244
OS -5.79095362 -38.65766716
OS -5.7937273 -38.66876188
OS -5.79557642 -38.68170572
OS -5.79742554 -38.69557412
OS -5.79927466 -38.70944252
OS -5.79927466 -38.72516004
OS -5.79927466 -38.7260846
OS -5.79927466 -38.72885828
OS -5.79927466 -38.73348108
OS -5.79927466 -38.73902844
OS -5.7983501 -38.74550036
OS -5.7983501 -38.7538214
OS -5.79650098 -38.77138804
OS -5.7937273 -38.7908038
OS -5.79002906 -38.81114412
OS -5.7844817 -38.82963532
OS -5.78078346 -38.83795636
OS -5.77708522 -38.84535284
OS -5.77708522 -38.8462774
OS -5.7752361 -38.84812652
OS -5.77338698 -38.8509002
OS -5.7706133 -38.85459844
OS -5.76229226 -38.8647686
OS -5.75027298 -38.87493876
OS -5.73640458 -38.88603348
OS -5.71883794 -38.89620364
OS -5.70959234 -38.89990188
OS -5.69849762 -38.90267556
OS -5.68832746 -38.90452468
OS -5.67630818 -38.90544924
OS -5.67168538 -38.90544924
OS -5.66798714 -38.90452468
OS -5.65781698 -38.90267556
OS -5.6457977 -38.89990188
OS -5.6319293 -38.89435452
OS -5.61713634 -38.88695804
OS -5.60234338 -38.87586332
OS -5.5949469 -38.86846684
OS -5.58755042 -38.86107036
OS -5.58755042 -38.8601458
OS -5.5857013 -38.85922124
OS -5.58385218 -38.85644756
OS -5.58200306 -38.85274932
OS -5.57830482 -38.84812652
OS -5.57553114 -38.84257916
OS -5.5718329 -38.83518268
OS -5.56813466 -38.8277862
OS -5.56536098 -38.8185406
OS -5.56166274 -38.809295
OS -5.5579645 -38.79820028
OS -5.55519082 -38.786181
OS -5.5533417 -38.77323716
OS -5.55149258 -38.75936876
OS -5.54964346 -38.74365124
OS -5.54964346 -38.72793372
OS -5.54964346 -38.72700916
OS -5.54964346 -38.72423548
OS -5.54964346 -38.71961268
OS -5.55056802 -38.71314076
OS -5.55056802 -38.70574428
OS -5.55149258 -38.69649868
OS -5.55426626 -38.67708292
OS -5.5579645 -38.65581804
OS -5.56443642 -38.63270404
OS -5.57368202 -38.61236372
OS -5.57922938 -38.60219356
OS -5.5857013 -38.59387252
OS -5.5857013 -38.59294796
OS -5.58755042 -38.5920234
OS -5.59217322 -38.5874006
OS -5.5995697 -38.58000412
OS -5.60973986 -38.57168308
OS -5.6226837 -38.5642866
OS -5.63747666 -38.55689012
OS -5.6550433 -38.55226732
OS -5.6642889 -38.5504182
OE
OB -0.8057261 -38.5504182 H
OS -0.81127346 -38.5504182
OS -0.8149717 -38.55134276
OS -0.82514186 -38.55226732
OS -0.83716114 -38.555041
OS -0.8519541 -38.5596638
OS -0.86767162 -38.56613572
OS -0.88246458 -38.57538132
OS -0.89725754 -38.5874006
OS -0.89910666 -38.58924972
OS -0.9028049 -38.59387252
OS -0.90927682 -38.60219356
OS -0.91574874 -38.61328828
OS -0.92314522 -38.62623212
OS -0.92961714 -38.6428742
OS -0.9351645 -38.66228996
OS -0.93793818 -38.68355484
OS -0.67813682 -38.68355484
OS -0.67813682 -38.68263028
OS -0.67813682 -38.68078116
OS -0.67906138 -38.67800748
OS -0.67906138 -38.67430924
OS -0.6809105 -38.66321452
OS -0.68368418 -38.65119524
OS -0.68830698 -38.63640228
OS -0.69292978 -38.62253388
OS -0.70032626 -38.60866548
OS -0.7086473 -38.5966462
OS -0.7086473 -38.59572164
OS -0.71049642 -38.59479708
OS -0.71511922 -38.58924972
OS -0.72344026 -38.58185324
OS -0.73453498 -38.5735322
OS -0.74840338 -38.56521116
OS -0.76504546 -38.55781468
OS -0.78446122 -38.55226732
OS -0.79463138 -38.55134276
OS -0.8057261 -38.5504182
OE
OB -2.00210674 -38.5504182 H
OS -2.0076541 -38.5504182
OS -2.0122769 -38.55134276
OS -2.02244706 -38.55226732
OS -2.03631546 -38.55596556
OS -2.05203298 -38.56151292
OS -2.06867506 -38.5689094
OS -2.08439258 -38.58000412
OS -2.09271362 -38.5874006
OS -2.1001101 -38.59479708
OS -2.1001101 -38.59572164
OS -2.10195922 -38.5966462
OS -2.10380834 -38.59941988
OS -2.10658202 -38.60311812
OS -2.1093557 -38.60774092
OS -2.11212938 -38.61328828
OS -2.11582762 -38.62068476
OS -2.11952586 -38.62808124
OS -2.1232241 -38.63732684
OS -2.12692234 -38.64657244
OS -2.12969602 -38.65766716
OS -2.1324697 -38.66968644
OS -2.13524338 -38.68263028
OS -2.1370925 -38.69649868
OS -2.13801706 -38.7122162
OS -2.13894162 -38.72793372
OS -2.13894162 -38.72885828
OS -2.13894162 -38.73163196
OS -2.13894162 -38.73625476
OS -2.13801706 -38.74272668
OS -2.13801706 -38.75012316
OS -2.1370925 -38.7584442
OS -2.13431882 -38.77785996
OS -2.12969602 -38.8000494
OS -2.12229954 -38.82223884
OS -2.11305394 -38.84350372
OS -2.10658202 -38.85274932
OS -2.1001101 -38.86199492
OS -2.09918554 -38.86199492
OS -2.09826098 -38.86384404
OS -2.09271362 -38.86846684
OS -2.08439258 -38.87586332
OS -2.07329786 -38.8832598
OS -2.05942946 -38.89158084
OS -2.04278738 -38.89897732
OS -2.02337162 -38.90360012
OS -2.01320146 -38.90452468
OS -2.00210674 -38.90544924
OS -1.99655938 -38.90544924
OS -1.99193658 -38.90452468
OS -1.98176642 -38.90267556
OS -1.96789802 -38.89990188
OS -1.95310506 -38.89435452
OS -1.93646298 -38.88695804
OS -1.92074546 -38.87586332
OS -1.91242442 -38.86846684
OS -1.90502794 -38.86107036
OS -1.90410338 -38.8601458
OS -1.90317882 -38.85922124
OS -1.9013297 -38.85644756
OS -1.89855602 -38.85274932
OS -1.89578234 -38.84812652
OS -1.8920841 -38.84257916
OS -1.88838586 -38.83518268
OS -1.88468762 -38.8277862
OS -1.88098938 -38.8185406
OS -1.8782157 -38.80837044
OS -1.87451746 -38.79727572
OS -1.87174378 -38.78525644
OS -1.8689701 -38.77138804
OS -1.86712098 -38.75751964
OS -1.86527186 -38.74180212
OS -1.86527186 -38.72516004
OS -1.86527186 -38.72423548
OS -1.86527186 -38.7214618
OS -1.86527186 -38.716839
OS -1.86619642 -38.71129164
OS -1.86619642 -38.70389516
OS -1.86712098 -38.69557412
OS -1.86989466 -38.67615836
OS -1.87451746 -38.65581804
OS -1.88191394 -38.6336286
OS -1.8920841 -38.61328828
OS -1.89763146 -38.60311812
OS -1.90502794 -38.59479708
OS -1.90502794 -38.59387252
OS -1.90687706 -38.59294796
OS -1.91242442 -38.5874006
OS -1.92074546 -38.58092868
OS -1.93184018 -38.57260764
OS -1.94570858 -38.5642866
OS -1.96235066 -38.55689012
OS -1.98084186 -38.55226732
OS -1.99101202 -38.55134276
OS -2.00210674 -38.5504182
OE
OB -1.31978146 -38.5504182 H
OS -1.32440426 -38.5504182
OS -1.3281025 -38.55134276
OS -1.33827266 -38.55226732
OS -1.35029194 -38.55596556
OS -1.36416034 -38.56058836
OS -1.3789533 -38.5689094
OS -1.39374626 -38.57907956
OS -1.40114274 -38.58647604
OS -1.40761466 -38.59387252
OS -1.40761466 -38.59479708
OS -1.40946378 -38.59572164
OS -1.41038834 -38.59849532
OS -1.41316202 -38.60219356
OS -1.4159357 -38.60681636
OS -1.41870938 -38.61236372
OS -1.42148306 -38.61883564
OS -1.4251813 -38.62623212
OS -1.42887954 -38.63547772
OS -1.43165322 -38.64564788
OS -1.4344269 -38.6567426
OS -1.43720058 -38.66876188
OS -1.4390497 -38.68170572
OS -1.44089882 -38.69649868
OS -1.44274794 -38.7122162
OS -1.44274794 -38.72885828
OS -1.44274794 -38.72978284
OS -1.44274794 -38.73255652
OS -1.44274794 -38.73717932
OS -1.44182338 -38.74365124
OS -1.44182338 -38.75104772
OS -1.44089882 -38.75936876
OS -1.43812514 -38.77878452
OS -1.43350234 -38.8000494
OS -1.42703042 -38.82223884
OS -1.41778482 -38.84350372
OS -1.41223746 -38.85274932
OS -1.40576554 -38.86199492
OS -1.40484098 -38.86199492
OS -1.40391642 -38.86384404
OS -1.39929362 -38.86846684
OS -1.39097258 -38.87586332
OS -1.38080242 -38.8832598
OS -1.36785858 -38.89158084
OS -1.35214106 -38.89897732
OS -1.33549898 -38.90360012
OS -1.32625338 -38.90452468
OS -1.31700778 -38.90544924
OS -1.31238498 -38.90544924
OS -1.30868674 -38.90452468
OS -1.29851658 -38.90360012
OS -1.2864973 -38.89990188
OS -1.2726289 -38.89527908
OS -1.25783594 -38.8878826
OS -1.24304298 -38.87771244
OS -1.2356465 -38.87124052
OS -1.22917458 -38.86384404
OS -1.22917458 -38.86291948
OS -1.22732546 -38.86199492
OS -1.22547634 -38.85922124
OS -1.22362722 -38.855523
OS -1.22085354 -38.8509002
OS -1.2171553 -38.8462774
OS -1.21438162 -38.83888092
OS -1.21068338 -38.83148444
OS -1.20698514 -38.8231634
OS -1.20421146 -38.8139178
OS -1.20051322 -38.80282308
OS -1.19773954 -38.79172836
OS -1.19589042 -38.77878452
OS -1.1940413 -38.76584068
OS -1.19219218 -38.75104772
OS -1.19219218 -38.7353302
OS -1.19219218 -38.73440564
OS -1.19219218 -38.7307074
OS -1.19219218 -38.7260846
OS -1.19311674 -38.71961268
OS -1.19311674 -38.7122162
OS -1.1940413 -38.7029706
OS -1.19496586 -38.69280044
OS -1.19681498 -38.68170572
OS -1.20143778 -38.65951628
OS -1.2079097 -38.63640228
OS -1.2171553 -38.61421284
OS -1.22270266 -38.60496724
OS -1.22917458 -38.59572164
OS -1.22917458 -38.59479708
OS -1.2310237 -38.59387252
OS -1.2356465 -38.58832516
OS -1.24396754 -38.58092868
OS -1.2541377 -38.57260764
OS -1.26708154 -38.5642866
OS -1.28279906 -38.55781468
OS -1.3003657 -38.55226732
OS -1.3096113 -38.55134276
OS -1.31978146 -38.5504182
OE
OB -5.18444226 -38.5504182 H
OS -5.18998962 -38.5504182
OS -5.19461242 -38.55134276
OS -5.20478258 -38.55226732
OS -5.21865098 -38.55596556
OS -5.2343685 -38.56151292
OS -5.25101058 -38.5689094
OS -5.2667281 -38.58000412
OS -5.27504914 -38.5874006
OS -5.28244562 -38.59479708
OS -5.28244562 -38.59572164
OS -5.28429474 -38.5966462
OS -5.28614386 -38.59941988
OS -5.28891754 -38.60311812
OS -5.29169122 -38.60774092
OS -5.2944649 -38.61328828
OS -5.29816314 -38.62068476
OS -5.30186138 -38.62808124
OS -5.30555962 -38.63732684
OS -5.30925786 -38.64657244
OS -5.31203154 -38.65766716
OS -5.31480522 -38.66968644
OS -5.3175789 -38.68263028
OS -5.31942802 -38.69649868
OS -5.32035258 -38.7122162
OS -5.32127714 -38.72793372
OS -5.32127714 -38.72885828
OS -5.32127714 -38.73163196
OS -5.32127714 -38.73625476
OS -5.32035258 -38.74272668
OS -5.32035258 -38.75012316
OS -5.31942802 -38.7584442
OS -5.31665434 -38.77785996
OS -5.31203154 -38.8000494
OS -5.30463506 -38.82223884
OS -5.29538946 -38.84350372
OS -5.28891754 -38.85274932
OS -5.28244562 -38.86199492
OS -5.28152106 -38.86199492
OS -5.2805965 -38.86384404
OS -5.27504914 -38.86846684
OS -5.2667281 -38.87586332
OS -5.25563338 -38.8832598
OS -5.24176498 -38.89158084
OS -5.2251229 -38.89897732
OS -5.20570714 -38.90360012
OS -5.19553698 -38.90452468
OS -5.18444226 -38.90544924
OS -5.1788949 -38.90544924
OS -5.1742721 -38.90452468
OS -5.16410194 -38.90267556
OS -5.15023354 -38.89990188
OS -5.13544058 -38.89435452
OS -5.1187985 -38.88695804
OS -5.10308098 -38.87586332
OS -5.09475994 -38.86846684
OS -5.08736346 -38.86107036
OS -5.0864389 -38.8601458
OS -5.08551434 -38.85922124
OS -5.08366522 -38.85644756
OS -5.08089154 -38.85274932
OS -5.07811786 -38.84812652
OS -5.07441962 -38.84257916
OS -5.07072138 -38.83518268
OS -5.06702314 -38.8277862
OS -5.0633249 -38.8185406
OS -5.06055122 -38.80837044
OS -5.05685298 -38.79727572
OS -5.0540793 -38.78525644
OS -5.05130562 -38.77138804
OS -5.0494565 -38.75751964
OS -5.04760738 -38.74180212
OS -5.04760738 -38.72516004
OS -5.04760738 -38.72423548
OS -5.04760738 -38.7214618
OS -5.04760738 -38.716839
OS -5.04853194 -38.71129164
OS -5.04853194 -38.70389516
OS -5.0494565 -38.69557412
OS -5.05223018 -38.67615836
OS -5.05685298 -38.65581804
OS -5.06424946 -38.6336286
OS -5.07441962 -38.61328828
OS -5.07996698 -38.60311812
OS -5.08736346 -38.59479708
OS -5.08736346 -38.59387252
OS -5.08921258 -38.59294796
OS -5.09475994 -38.5874006
OS -5.10308098 -38.58092868
OS -5.1141757 -38.57260764
OS -5.1280441 -38.5642866
OS -5.14468618 -38.55689012
OS -5.16317738 -38.55226732
OS -5.17334754 -38.55134276
OS -5.18444226 -38.5504182
OE
SE
S P 0
OB -4.66714078 -36.5016923 I
OS -4.65465922 -36.5016923
OS -4.62553558 -36.50307914
OS -4.5950251 -36.50723966
OS -4.56174094 -36.51140018
OS -4.53123046 -36.51833438
OS -4.51597522 -36.5224949
OS -4.50349366 -36.52665542
OS -4.50210682 -36.52665542
OS -4.50071998 -36.52804226
OS -4.49239894 -36.53220278
OS -4.47991738 -36.53775014
OS -4.46466214 -36.54745802
OS -4.44802006 -36.55993958
OS -4.42999114 -36.57658166
OS -4.41334906 -36.59599742
OS -4.39670698 -36.61818686
OS -4.39670698 -36.6195737
OS -4.39532014 -36.62096054
OS -4.38977278 -36.62928158
OS -4.38422542 -36.64314998
OS -4.37590438 -36.6611789
OS -4.36897018 -36.6819815
OS -4.36203598 -36.70694462
OS -4.35787546 -36.73329458
OS -4.35648862 -36.76241822
OS -4.35648862 -36.76380506
OS -4.35648862 -36.76657874
OS -4.35648862 -36.7721261
OS -4.35787546 -36.7790603
OS -4.35787546 -36.78876818
OS -4.3592623 -36.79847606
OS -4.36480966 -36.82205234
OS -4.3731307 -36.84978914
OS -4.38422542 -36.87891278
OS -4.4008675 -36.90803642
OS -4.41196222 -36.92190482
OS -4.42305694 -36.93577322
OS -4.42444378 -36.93716006
OS -4.42583062 -36.9385469
OS -4.42999114 -36.94270742
OS -4.4355385 -36.94686794
OS -4.4424727 -36.9524153
OS -4.45079374 -36.95796266
OS -4.46188846 -36.96489686
OS -4.47298318 -36.9732179
OS -4.48685158 -36.9801521
OS -4.50210682 -36.9870863
OS -4.5187489 -36.99540734
OS -4.53677782 -37.00234154
OS -4.55758042 -37.0078889
OS -4.57838302 -37.0148231
OS -4.6019593 -37.01898362
OS -4.62692242 -37.02314414
OS -4.62414874 -37.02453098
OS -4.61860138 -37.02730466
OS -4.61028034 -37.03285202
OS -4.59918562 -37.03839938
OS -4.5742225 -37.05365462
OS -4.56174094 -37.0633625
OS -4.55064622 -37.07168354
OS -4.54787254 -37.07445722
OS -4.54093834 -37.08139142
OS -4.52984362 -37.09248614
OS -4.51597522 -37.10635454
OS -4.50071998 -37.1257703
OS -4.48269106 -37.1465729
OS -4.46466214 -37.17153602
OS -4.44524638 -37.19927282
OS -4.28021242 -37.45999874
OS -4.43831218 -37.45999874
OS -4.56451462 -37.26029378
OS -4.56451462 -37.25890694
OS -4.5672883 -37.25613326
OS -4.57006198 -37.25197274
OS -4.5742225 -37.24642538
OS -4.58393038 -37.23117014
OS -4.59641194 -37.21175438
OS -4.61166718 -37.19095178
OS -4.62692242 -37.16876234
OS -4.64217766 -37.14795974
OS -4.65604606 -37.12854398
OS -4.6574329 -37.12715714
OS -4.66159342 -37.12160978
OS -4.66852762 -37.11328874
OS -4.6782355 -37.10358086
OS -4.6990381 -37.08277826
OS -4.71013282 -37.07307038
OS -4.72122754 -37.06474934
OS -4.72261438 -37.0633625
OS -4.72538806 -37.06197566
OS -4.73093542 -37.05920198
OS -4.73925646 -37.05504146
OS -4.7475775 -37.05088094
OS -4.75728538 -37.04672042
OS -4.77947482 -37.03978622
OS -4.78086166 -37.03978622
OS -4.78363534 -37.03839938
OS -4.7891827 -37.03839938
OS -4.7961169 -37.03701254
OS -4.80582478 -37.0356257
OS -4.8169195 -37.0356257
OS -4.83217474 -37.03423886
OS -4.99582186 -37.03423886
OS -4.99582186 -37.45999874
OS -5.12341114 -37.45999874
OS -5.12341114 -36.50030546
OS -4.6782355 -36.50030546
OS -4.66714078 -36.5016923
OE
OB -1.0100437 -37.45999874 I
OS -1.13208562 -37.45999874
OS -1.13208562 -36.65701838
OS -1.4122273 -37.45999874
OS -1.52594818 -37.45999874
OS -1.80331618 -36.64314998
OS -1.80331618 -37.45999874
OS -1.9253581 -37.45999874
OS -1.9253581 -36.50030546
OS -1.73536102 -36.50030546
OS -1.50791926 -37.1812439
OS -1.50791926 -37.18263074
OS -1.50653242 -37.18540442
OS -1.50514558 -37.18956494
OS -1.5023719 -37.19649914
OS -1.49682454 -37.21314122
OS -1.48989034 -37.23394382
OS -1.48295614 -37.2575201
OS -1.4746351 -37.28109638
OS -1.4677009 -37.30328582
OS -1.46215354 -37.32270158
OS -1.4607667 -37.3199279
OS -1.45937986 -37.3129937
OS -1.45521934 -37.30051214
OS -1.44967198 -37.28387006
OS -1.44273778 -37.26168062
OS -1.4330299 -37.23533066
OS -1.42332202 -37.20482018
OS -1.41084046 -37.16876234
OS -1.18062502 -36.50030546
OS -1.0100437 -36.50030546
OS -1.0100437 -37.45999874
OE
OB -2.02382374 -37.45999874 I
OS -2.1680551 -37.45999874
OS -2.28038914 -37.16876234
OS -2.68257274 -37.16876234
OS -2.78658574 -37.45999874
OS -2.92110922 -37.45999874
OS -2.55498346 -36.50030546
OS -2.41629946 -36.50030546
OS -2.02382374 -37.45999874
OE
OB -3.02928274 -37.45999874 I
OS -3.16103254 -37.45999874
OS -3.66306862 -36.70694462
OS -3.66306862 -37.45999874
OS -3.78511054 -37.45999874
OS -3.78511054 -36.50030546
OS -3.65474758 -36.50030546
OS -3.15132466 -37.25474642
OS -3.15132466 -36.50030546
OS -3.02928274 -36.50030546
OS -3.02928274 -37.45999874
OE
OB -5.3231161 -36.61402634 I
OS -5.89033366 -36.61402634
OS -5.89033366 -36.90664958
OS -5.35917394 -36.90664958
OS -5.35917394 -37.02037046
OS -5.89033366 -37.02037046
OS -5.89033366 -37.34627786
OS -5.30092666 -37.34627786
OS -5.30092666 -37.45999874
OS -6.01792294 -37.45999874
OS -6.01792294 -36.50030546
OS -5.3231161 -36.50030546
OS -5.3231161 -36.61402634
OE
OB -0.10721086 -36.61402634 I
OS -0.67442842 -36.61402634
OS -0.67442842 -36.90664958
OS -0.1432687 -36.90664958
OS -0.1432687 -37.02037046
OS -0.67442842 -37.02037046
OS -0.67442842 -37.34627786
OS -0.08502142 -37.34627786
OS -0.08502142 -37.45999874
OS -0.8020177 -37.45999874
OS -0.8020177 -36.50030546
OS -0.10721086 -36.50030546
OS -0.10721086 -36.61402634
OE
OB -8.43241138 -37.34627786 I
OS -7.95949894 -37.34627786
OS -7.95949894 -37.45999874
OS -8.56000066 -37.45999874
OS -8.56000066 -36.50030546
OS -8.43241138 -36.50030546
OS -8.43241138 -37.34627786
OE
OB -6.51718534 -37.05365462 I
OS -6.51718534 -37.45999874
OS -6.64477462 -37.45999874
OS -6.64477462 -37.05365462
OS -7.0150609 -36.50030546
OS -6.86112166 -36.50030546
OS -6.67251142 -36.79154186
OS -6.67251142 -36.7929287
OS -6.66973774 -36.79570238
OS -6.66696406 -36.7998629
OS -6.66419038 -36.80541026
OS -6.65864302 -36.81234446
OS -6.65309566 -36.8206655
OS -6.6406141 -36.8414681
OS -6.62535886 -36.86643122
OS -6.60871678 -36.89416802
OS -6.59068786 -36.92329166
OS -6.57404578 -36.95380214
OS -6.57404578 -36.9524153
OS -6.57265894 -36.94964162
OS -6.56988526 -36.9454811
OS -6.56572474 -36.93993374
OS -6.56156422 -36.93299954
OS -6.55601686 -36.9246785
OS -6.5435353 -36.9038759
OS -6.52828006 -36.87891278
OS -6.51025114 -36.84978914
OS -6.48944854 -36.81789182
OS -6.4672591 -36.78322082
OS -6.28280938 -36.50030546
OS -6.1344175 -36.50030546
OS -6.51718534 -37.05365462
OE
OB -7.01644774 -37.45999874 I
OS -7.1606791 -37.45999874
OS -7.27301314 -37.16876234
OS -7.67519674 -37.16876234
OS -7.77920974 -37.45999874
OS -7.91373322 -37.45999874
OS -7.54760746 -36.50030546
OS -7.40892346 -36.50030546
OS -7.01644774 -37.45999874
OE
OB -7.48103914 -36.60015794 H
OS -7.48103914 -36.60154478
OS -7.48242598 -36.60431846
OS -7.48242598 -36.60986582
OS -7.48519966 -36.61541318
OS -7.4865865 -36.62512106
OS -7.48936018 -36.63482894
OS -7.49490754 -36.65840522
OS -7.50184174 -36.68614202
OS -7.51154962 -36.7166525
OS -7.5212575 -36.74993666
OS -7.53373906 -36.78460766
OS -7.63775206 -37.06474934
OS -7.3132315 -37.06474934
OS -7.41308398 -36.80124974
OS -7.41308398 -36.7998629
OS -7.41447082 -36.79570238
OS -7.4172445 -36.78876818
OS -7.42001818 -36.78044714
OS -7.4241787 -36.77073926
OS -7.42833922 -36.7582577
OS -7.43249974 -36.7443893
OS -7.4380471 -36.7305209
OS -7.44914182 -36.69862358
OS -7.46023654 -36.66533942
OS -7.47133126 -36.63205526
OS -7.48103914 -36.60015794
OE
OB -4.69349074 -36.60709214 H
OS -4.99582186 -36.60709214
OS -4.99582186 -36.9246785
OS -4.71013282 -36.9246785
OS -4.69349074 -36.92329166
OS -4.67407498 -36.92190482
OS -4.65188554 -36.92051798
OS -4.6296961 -36.9177443
OS -4.60750666 -36.91358378
OS -4.5880909 -36.90803642
OS -4.58531722 -36.90664958
OS -4.57976986 -36.9038759
OS -4.57144882 -36.89971538
OS -4.5603541 -36.89416802
OS -4.54787254 -36.88584698
OS -4.53539098 -36.8761391
OS -4.52290942 -36.86365754
OS -4.51320154 -36.84978914
OS -4.5118147 -36.8484023
OS -4.50904102 -36.84285494
OS -4.5048805 -36.8345339
OS -4.49933314 -36.82343918
OS -4.49517262 -36.81095762
OS -4.4910121 -36.79708922
OS -4.48823842 -36.78044714
OS -4.48685158 -36.76380506
OS -4.48685158 -36.76241822
OS -4.48685158 -36.76103138
OS -4.48823842 -36.75271034
OS -4.48962526 -36.74022878
OS -4.49239894 -36.7235867
OS -4.49933314 -36.70694462
OS -4.50765418 -36.68752886
OS -4.52013574 -36.66949994
OS -4.53677782 -36.65147102
OS -4.5395515 -36.65008418
OS -4.5464857 -36.64453682
OS -4.55758042 -36.63760262
OS -4.57560934 -36.62928158
OS -4.59641194 -36.62096054
OS -4.62414874 -36.61402634
OS -4.65604606 -36.60847898
OS -4.69349074 -36.60709214
OE
OB -2.48841514 -36.60015794 H
OS -2.48841514 -36.60154478
OS -2.48980198 -36.60431846
OS -2.48980198 -36.60986582
OS -2.49257566 -36.61541318
OS -2.4939625 -36.62512106
OS -2.49673618 -36.63482894
OS -2.50228354 -36.65840522
OS -2.50921774 -36.68614202
OS -2.51892562 -36.7166525
OS -2.5286335 -36.74993666
OS -2.54111506 -36.78460766
OS -2.64512806 -37.06474934
OS -2.3206075 -37.06474934
OS -2.42045998 -36.80124974
OS -2.42045998 -36.7998629
OS -2.42184682 -36.79570238
OS -2.4246205 -36.78876818
OS -2.42739418 -36.78044714
OS -2.4315547 -36.77073926
OS -2.43571522 -36.7582577
OS -2.43987574 -36.7443893
OS -2.4454231 -36.7305209
OS -2.45651782 -36.69862358
OS -2.46761254 -36.66533942
OS -2.47870726 -36.63205526
OS -2.48841514 -36.60015794
OE
SE
S P 0
OB 35.73690338 -37.45999874 I
OS 35.61486146 -37.45999874
OS 35.61486146 -36.65701838
OS 35.33471978 -37.45999874
OS 35.2209989 -37.45999874
OS 34.9436309 -36.64314998
OS 34.9436309 -37.45999874
OS 34.82158898 -37.45999874
OS 34.82158898 -36.50030546
OS 35.01158606 -36.50030546
OS 35.23902782 -37.1812439
OS 35.23902782 -37.18263074
OS 35.24041466 -37.18540442
OS 35.2418015 -37.18956494
OS 35.24457518 -37.19649914
OS 35.25012254 -37.21314122
OS 35.25705674 -37.23394382
OS 35.26399094 -37.2575201
OS 35.27231198 -37.28109638
OS 35.27924618 -37.30328582
OS 35.28479354 -37.32270158
OS 35.28618038 -37.3199279
OS 35.28756722 -37.3129937
OS 35.29172774 -37.30051214
OS 35.2972751 -37.28387006
OS 35.3042093 -37.26168062
OS 35.31391718 -37.23533066
OS 35.32362506 -37.20482018
OS 35.33610662 -37.16876234
OS 35.56632206 -36.50030546
OS 35.73690338 -36.50030546
OS 35.73690338 -37.45999874
OE
OB 34.61356298 -37.05504146 I
OS 34.61356298 -37.0564283
OS 34.61356298 -37.06197566
OS 34.61356298 -37.06890986
OS 34.61356298 -37.07861774
OS 34.61217614 -37.0910993
OS 34.61217614 -37.1049677
OS 34.6107893 -37.12160978
OS 34.60940246 -37.13825186
OS 34.60524194 -37.17569654
OS 34.59969458 -37.21452806
OS 34.59137354 -37.25197274
OS 34.58582618 -37.27000166
OS 34.58027882 -37.28664374
OS 34.58027882 -37.28803058
OS 34.57889198 -37.29080426
OS 34.5761183 -37.29496478
OS 34.57334462 -37.30051214
OS 34.56502358 -37.31576738
OS 34.55254202 -37.33518314
OS 34.53589994 -37.35737258
OS 34.51648418 -37.37956202
OS 34.49152106 -37.4031383
OS 34.46101058 -37.4239409
OS 34.45962374 -37.4239409
OS 34.45685006 -37.42671458
OS 34.45268954 -37.42810142
OS 34.44575534 -37.43226194
OS 34.4374343 -37.43642246
OS 34.42633958 -37.44058298
OS 34.41524486 -37.4447435
OS 34.40137646 -37.45029086
OS 34.38612122 -37.45583822
OS 34.36947914 -37.45999874
OS 34.35145022 -37.46415926
OS 34.33064762 -37.46831978
OS 34.30984502 -37.47109346
OS 34.28765558 -37.47386714
OS 34.23772934 -37.47664082
OS 34.22524778 -37.47664082
OS 34.2155399 -37.47525398
OS 34.20444518 -37.47525398
OS 34.19057678 -37.47386714
OS 34.17532154 -37.4724803
OS 34.1600663 -37.47109346
OS 34.1253953 -37.4655461
OS 34.08795062 -37.45722506
OS 34.05189278 -37.44613034
OS 34.01722178 -37.4308751
OS 34.01583494 -37.4308751
OS 34.01306126 -37.42810142
OS 34.00890074 -37.42532774
OS 34.00335338 -37.42255406
OS 33.98809814 -37.41145934
OS 33.97006922 -37.3962041
OS 33.94926662 -37.37678834
OS 33.92985086 -37.3545989
OS 33.9104351 -37.3268621
OS 33.89517986 -37.29635162
OS 33.89517986 -37.29496478
OS 33.89379302 -37.2921911
OS 33.89240618 -37.28664374
OS 33.8896325 -37.27970954
OS 33.88685882 -37.2713885
OS 33.88408514 -37.26029378
OS 33.87992462 -37.24781222
OS 33.87715094 -37.23255698
OS 33.87437726 -37.2159149
OS 33.87021674 -37.19788598
OS 33.86744306 -37.17847022
OS 33.86466938 -37.15766762
OS 33.8618957 -37.13409134
OS 33.86050886 -37.10912822
OS 33.85912202 -37.08277826
OS 33.85912202 -37.05504146
OS 33.85912202 -36.50030546
OS 33.9867113 -36.50030546
OS 33.9867113 -37.05504146
OS 33.9867113 -37.0564283
OS 33.9867113 -37.06058882
OS 33.9867113 -37.06752302
OS 33.9867113 -37.07584406
OS 33.98809814 -37.08555194
OS 33.98809814 -37.0980335
OS 33.98948498 -37.12438346
OS 33.99225866 -37.15489394
OS 33.99641918 -37.18540442
OS 34.00196654 -37.21452806
OS 34.00474022 -37.22700962
OS 34.00890074 -37.23949118
OS 34.01028758 -37.24226486
OS 34.01306126 -37.24919906
OS 34.01999546 -37.25890694
OS 34.0283165 -37.27277534
OS 34.03802438 -37.28664374
OS 34.05189278 -37.30189898
OS 34.06853486 -37.31715422
OS 34.08795062 -37.32963578
OS 34.0907243 -37.33102262
OS 34.0976585 -37.33518314
OS 34.11014006 -37.33934366
OS 34.12678214 -37.34489102
OS 34.1461979 -37.35182522
OS 34.17116102 -37.35598574
OS 34.19751098 -37.36014626
OS 34.22663462 -37.3615331
OS 34.24050302 -37.3615331
OS 34.24882406 -37.36014626
OS 34.26130562 -37.36014626
OS 34.27378718 -37.35875942
OS 34.30429766 -37.35321206
OS 34.33758182 -37.34627786
OS 34.36947914 -37.33518314
OS 34.39998962 -37.3199279
OS 34.41385802 -37.31022002
OS 34.42633958 -37.2991253
OS 34.42772642 -37.29773846
OS 34.42911326 -37.29635162
OS 34.43188694 -37.2921911
OS 34.43604746 -37.28664374
OS 34.44020798 -37.2783227
OS 34.44575534 -37.27000166
OS 34.4513027 -37.2575201
OS 34.45685006 -37.24503854
OS 34.46239742 -37.2297833
OS 34.46655794 -37.21175438
OS 34.4721053 -37.19095178
OS 34.47626582 -37.16876234
OS 34.48042634 -37.14379922
OS 34.48320002 -37.11744926
OS 34.4859737 -37.08693878
OS 34.4859737 -37.05504146
OS 34.4859737 -36.50030546
OS 34.61356298 -36.50030546
OS 34.61356298 -37.05504146
OE
OB 33.64416182 -37.45999874 I
OS 33.51241202 -37.45999874
OS 33.01037594 -36.70694462
OS 33.01037594 -37.45999874
OS 32.88833402 -37.45999874
OS 32.88833402 -36.50030546
OS 33.01869698 -36.50030546
OS 33.5221199 -37.25474642
OS 33.5221199 -36.50030546
OS 33.64416182 -36.50030546
OS 33.64416182 -37.45999874
OE
OB 38.19022334 -36.5016923 I
OS 38.2027049 -36.5016923
OS 38.23182854 -36.50307914
OS 38.26233902 -36.50723966
OS 38.29562318 -36.51140018
OS 38.32613366 -36.51833438
OS 38.3413889 -36.5224949
OS 38.35387046 -36.52665542
OS 38.3552573 -36.52665542
OS 38.35664414 -36.52804226
OS 38.36496518 -36.53220278
OS 38.37744674 -36.53775014
OS 38.39270198 -36.54745802
OS 38.40934406 -36.55993958
OS 38.42737298 -36.57658166
OS 38.44401506 -36.59599742
OS 38.46065714 -36.61818686
OS 38.46065714 -36.6195737
OS 38.46204398 -36.62096054
OS 38.46759134 -36.62928158
OS 38.4731387 -36.64314998
OS 38.48145974 -36.6611789
OS 38.48839394 -36.6819815
OS 38.49532814 -36.70694462
OS 38.49948866 -36.73329458
OS 38.5008755 -36.76241822
OS 38.5008755 -36.76380506
OS 38.5008755 -36.76657874
OS 38.5008755 -36.7721261
OS 38.49948866 -36.7790603
OS 38.49948866 -36.78876818
OS 38.49810182 -36.79847606
OS 38.49255446 -36.82205234
OS 38.48423342 -36.84978914
OS 38.4731387 -36.87891278
OS 38.45649662 -36.90803642
OS 38.4454019 -36.92190482
OS 38.43430718 -36.93577322
OS 38.43292034 -36.93716006
OS 38.4315335 -36.9385469
OS 38.42737298 -36.94270742
OS 38.42182562 -36.94686794
OS 38.41489142 -36.9524153
OS 38.40657038 -36.95796266
OS 38.39547566 -36.96489686
OS 38.38438094 -36.9732179
OS 38.37051254 -36.9801521
OS 38.3552573 -36.9870863
OS 38.33861522 -36.99540734
OS 38.3205863 -37.00234154
OS 38.2997837 -37.0078889
OS 38.2789811 -37.0148231
OS 38.25540482 -37.01898362
OS 38.2304417 -37.02314414
OS 38.23321538 -37.02453098
OS 38.23876274 -37.02730466
OS 38.24708378 -37.03285202
OS 38.2581785 -37.03839938
OS 38.28314162 -37.05365462
OS 38.29562318 -37.0633625
OS 38.3067179 -37.07168354
OS 38.30949158 -37.07445722
OS 38.31642578 -37.08139142
OS 38.3275205 -37.09248614
OS 38.3413889 -37.10635454
OS 38.35664414 -37.1257703
OS 38.37467306 -37.1465729
OS 38.39270198 -37.17153602
OS 38.41211774 -37.19927282
OS 38.5771517 -37.45999874
OS 38.41905194 -37.45999874
OS 38.2928495 -37.26029378
OS 38.2928495 -37.25890694
OS 38.29007582 -37.25613326
OS 38.28730214 -37.25197274
OS 38.28314162 -37.24642538
OS 38.27343374 -37.23117014
OS 38.26095218 -37.21175438
OS 38.24569694 -37.19095178
OS 38.2304417 -37.16876234
OS 38.21518646 -37.14795974
OS 38.20131806 -37.12854398
OS 38.19993122 -37.12715714
OS 38.1957707 -37.12160978
OS 38.1888365 -37.11328874
OS 38.17912862 -37.10358086
OS 38.15832602 -37.08277826
OS 38.1472313 -37.07307038
OS 38.13613658 -37.06474934
OS 38.13474974 -37.0633625
OS 38.13197606 -37.06197566
OS 38.1264287 -37.05920198
OS 38.11810766 -37.05504146
OS 38.10978662 -37.05088094
OS 38.10007874 -37.04672042
OS 38.0778893 -37.03978622
OS 38.07650246 -37.03978622
OS 38.07372878 -37.03839938
OS 38.06818142 -37.03839938
OS 38.06124722 -37.03701254
OS 38.05153934 -37.0356257
OS 38.04044462 -37.0356257
OS 38.02518938 -37.03423886
OS 37.86154226 -37.03423886
OS 37.86154226 -37.45999874
OS 37.73395298 -37.45999874
OS 37.73395298 -36.50030546
OS 38.17912862 -36.50030546
OS 38.19022334 -36.5016923
OE
OB 37.53424802 -36.61402634 I
OS 36.96703046 -36.61402634
OS 36.96703046 -36.90664958
OS 37.49819018 -36.90664958
OS 37.49819018 -37.02037046
OS 36.96703046 -37.02037046
OS 36.96703046 -37.34627786
OS 37.55643746 -37.34627786
OS 37.55643746 -37.45999874
OS 36.83944118 -37.45999874
OS 36.83944118 -36.50030546
OS 37.53424802 -36.50030546
OS 37.53424802 -36.61402634
OE
OB 36.32492354 -36.5016923 I
OS 36.33601826 -36.5016923
OS 36.36098138 -36.50446598
OS 36.38871818 -36.50723966
OS 36.41784182 -36.51278702
OS 36.44696546 -36.51972122
OS 36.47331542 -36.5294291
OS 36.47470226 -36.5294291
OS 36.4760891 -36.53081594
OS 36.48441014 -36.53497646
OS 36.4968917 -36.54191066
OS 36.5107601 -36.55161854
OS 36.52740218 -36.5641001
OS 36.5454311 -36.57935534
OS 36.56207318 -36.5987711
OS 36.57732842 -36.6195737
OS 36.57871526 -36.62234738
OS 36.58287578 -36.63066842
OS 36.58980998 -36.64176314
OS 36.59674418 -36.65840522
OS 36.60367838 -36.67782098
OS 36.61061258 -36.69862358
OS 36.6147731 -36.72219986
OS 36.61615994 -36.74577614
OS 36.61615994 -36.74854982
OS 36.61615994 -36.75548402
OS 36.6147731 -36.76796558
OS 36.61199942 -36.78322082
OS 36.6078389 -36.80124974
OS 36.6009047 -36.8206655
OS 36.59258366 -36.84008126
OS 36.58148894 -36.86088386
OS 36.5801021 -36.86365754
OS 36.57594158 -36.8692049
OS 36.56762054 -36.88029962
OS 36.55652582 -36.89139434
OS 36.54265742 -36.90526274
OS 36.52601534 -36.92051798
OS 36.50521274 -36.93438638
OS 36.48163646 -36.94825478
OS 36.4830233 -36.94825478
OS 36.48579698 -36.94964162
OS 36.4899575 -36.95102846
OS 36.49550486 -36.95380214
OS 36.51214694 -36.9593495
OS 36.5315627 -36.96905738
OS 36.5523653 -36.98153894
OS 36.57594158 -36.99679418
OS 36.59674418 -37.0148231
OS 36.61615994 -37.03701254
OS 36.61754678 -37.03978622
OS 36.62309414 -37.04810726
OS 36.63141518 -37.06058882
OS 36.63973622 -37.0772309
OS 36.64805726 -37.09942034
OS 36.6563783 -37.12299662
OS 36.66192566 -37.15073342
OS 36.6633125 -37.1812439
OS 36.6633125 -37.18263074
OS 36.6633125 -37.18401758
OS 36.6633125 -37.19233862
OS 36.66192566 -37.20620702
OS 36.65915198 -37.2228491
OS 36.6563783 -37.24226486
OS 36.65083094 -37.26306746
OS 36.64389674 -37.2852569
OS 36.63418886 -37.30744634
OS 36.63280202 -37.31022002
OS 36.6286415 -37.31715422
OS 36.62309414 -37.3268621
OS 36.6147731 -37.3407305
OS 36.60367838 -37.3545989
OS 36.59258366 -37.36985414
OS 36.57871526 -37.38510938
OS 36.56346002 -37.39759094
OS 36.56207318 -37.39897778
OS 36.55652582 -37.4031383
OS 36.54681794 -37.40868566
OS 36.53433638 -37.41423302
OS 36.51908114 -37.42255406
OS 36.50105222 -37.4308751
OS 36.48163646 -37.4378093
OS 36.45806018 -37.4447435
OS 36.4552865 -37.4447435
OS 36.44696546 -37.44751718
OS 36.43309706 -37.44890402
OS 36.41506814 -37.4516777
OS 36.3928787 -37.45445138
OS 36.36652874 -37.45722506
OS 36.3374051 -37.4586119
OS 36.30412094 -37.45999874
OS 35.93799518 -37.45999874
OS 35.93799518 -36.50030546
OS 36.31521566 -36.50030546
OS 36.32492354 -36.5016923
OE
OB 32.3849111 -36.61402634 I
OS 32.06871158 -36.61402634
OS 32.06871158 -37.45999874
OS 31.9411223 -37.45999874
OS 31.9411223 -36.61402634
OS 31.62492278 -36.61402634
OS 31.62492278 -36.50030546
OS 32.3849111 -36.50030546
OS 32.3849111 -36.61402634
OE
OB 30.62639798 -37.45999874 I
OS 30.48216662 -37.45999874
OS 30.36983258 -37.16876234
OS 29.96764898 -37.16876234
OS 29.86363598 -37.45999874
OS 29.7291125 -37.45999874
OS 30.09523826 -36.50030546
OS 30.23392226 -36.50030546
OS 30.62639798 -37.45999874
OE
OB 29.3546657 -36.5016923 I
OS 29.37824198 -36.50307914
OS 29.4032051 -36.50446598
OS 29.42678138 -36.50723966
OS 29.44758398 -36.51001334
OS 29.45035766 -36.51001334
OS 29.46006554 -36.51278702
OS 29.4725471 -36.5155607
OS 29.48918918 -36.51972122
OS 29.5072181 -36.52665542
OS 29.52663386 -36.53497646
OS 29.54743646 -36.54468434
OS 29.56546538 -36.55577906
OS 29.56823906 -36.5571659
OS 29.57378642 -36.56132642
OS 29.58210746 -36.56964746
OS 29.59320218 -36.57935534
OS 29.60568374 -36.5918369
OS 29.6181653 -36.60847898
OS 29.6320337 -36.6265079
OS 29.64312842 -36.6473105
OS 29.64451526 -36.65008418
OS 29.64728894 -36.65701838
OS 29.6528363 -36.66949994
OS 29.65838366 -36.68614202
OS 29.66254418 -36.70555778
OS 29.66809154 -36.72774722
OS 29.67086522 -36.75271034
OS 29.67225206 -36.7790603
OS 29.67225206 -36.78044714
OS 29.67225206 -36.78460766
OS 29.67225206 -36.79015502
OS 29.67086522 -36.7998629
OS 29.66947838 -36.80957078
OS 29.66809154 -36.82205234
OS 29.66531786 -36.83592074
OS 29.66254418 -36.85117598
OS 29.6528363 -36.8830733
OS 29.64728894 -36.89971538
OS 29.6389679 -36.9177443
OS 29.62926002 -36.93577322
OS 29.61955214 -36.9524153
OS 29.60707058 -36.96905738
OS 29.59320218 -36.98569946
OS 29.59181534 -36.9870863
OS 29.58904166 -36.98985998
OS 29.58488114 -36.9940205
OS 29.57794694 -36.99818102
OS 29.5696259 -37.00511522
OS 29.55853118 -37.01204942
OS 29.54466278 -37.02037046
OS 29.52940754 -37.02730466
OS 29.51137862 -37.0356257
OS 29.49057602 -37.04394674
OS 29.46838658 -37.05088094
OS 29.44203662 -37.0564283
OS 29.41429982 -37.06197566
OS 29.38378934 -37.06613618
OS 29.34911834 -37.06890986
OS 29.3130605 -37.0702967
OS 29.06758982 -37.0702967
OS 29.06758982 -37.45999874
OS 28.94000054 -37.45999874
OS 28.94000054 -36.50030546
OS 29.3338631 -36.50030546
OS 29.3546657 -36.5016923
OE
OB 31.18668134 -36.5016923 I
OS 31.1991629 -36.5016923
OS 31.22828654 -36.50307914
OS 31.25879702 -36.50723966
OS 31.29208118 -36.51140018
OS 31.32259166 -36.51833438
OS 31.3378469 -36.5224949
OS 31.35032846 -36.52665542
OS 31.3517153 -36.52665542
OS 31.35310214 -36.52804226
OS 31.36142318 -36.53220278
OS 31.37390474 -36.53775014
OS 31.38915998 -36.54745802
OS 31.40580206 -36.55993958
OS 31.42383098 -36.57658166
OS 31.44047306 -36.59599742
OS 31.45711514 -36.61818686
OS 31.45711514 -36.6195737
OS 31.45850198 -36.62096054
OS 31.46404934 -36.62928158
OS 31.4695967 -36.64314998
OS 31.47791774 -36.6611789
OS 31.48485194 -36.6819815
OS 31.49178614 -36.70694462
OS 31.49594666 -36.73329458
OS 31.4973335 -36.76241822
OS 31.4973335 -36.76380506
OS 31.4973335 -36.76657874
OS 31.4973335 -36.7721261
OS 31.49594666 -36.7790603
OS 31.49594666 -36.78876818
OS 31.49455982 -36.79847606
OS 31.48901246 -36.82205234
OS 31.48069142 -36.84978914
OS 31.4695967 -36.87891278
OS 31.45295462 -36.90803642
OS 31.4418599 -36.92190482
OS 31.43076518 -36.93577322
OS 31.42937834 -36.93716006
OS 31.4279915 -36.9385469
OS 31.42383098 -36.94270742
OS 31.41828362 -36.94686794
OS 31.41134942 -36.9524153
OS 31.40302838 -36.95796266
OS 31.39193366 -36.96489686
OS 31.38083894 -36.9732179
OS 31.36697054 -36.9801521
OS 31.3517153 -36.9870863
OS 31.33507322 -36.99540734
OS 31.3170443 -37.00234154
OS 31.2962417 -37.0078889
OS 31.2754391 -37.0148231
OS 31.25186282 -37.01898362
OS 31.2268997 -37.02314414
OS 31.22967338 -37.02453098
OS 31.23522074 -37.02730466
OS 31.24354178 -37.03285202
OS 31.2546365 -37.03839938
OS 31.27959962 -37.05365462
OS 31.29208118 -37.0633625
OS 31.3031759 -37.07168354
OS 31.30594958 -37.07445722
OS 31.31288378 -37.08139142
OS 31.3239785 -37.09248614
OS 31.3378469 -37.10635454
OS 31.35310214 -37.1257703
OS 31.37113106 -37.1465729
OS 31.38915998 -37.17153602
OS 31.40857574 -37.19927282
OS 31.5736097 -37.45999874
OS 31.41550994 -37.45999874
OS 31.2893075 -37.26029378
OS 31.2893075 -37.25890694
OS 31.28653382 -37.25613326
OS 31.28376014 -37.25197274
OS 31.27959962 -37.24642538
OS 31.26989174 -37.23117014
OS 31.25741018 -37.21175438
OS 31.24215494 -37.19095178
OS 31.2268997 -37.16876234
OS 31.21164446 -37.14795974
OS 31.19777606 -37.12854398
OS 31.19638922 -37.12715714
OS 31.1922287 -37.12160978
OS 31.1852945 -37.11328874
OS 31.17558662 -37.10358086
OS 31.15478402 -37.08277826
OS 31.1436893 -37.07307038
OS 31.13259458 -37.06474934
OS 31.13120774 -37.0633625
OS 31.12843406 -37.06197566
OS 31.1228867 -37.05920198
OS 31.11456566 -37.05504146
OS 31.10624462 -37.05088094
OS 31.09653674 -37.04672042
OS 31.0743473 -37.03978622
OS 31.07296046 -37.03978622
OS 31.07018678 -37.03839938
OS 31.06463942 -37.03839938
OS 31.05770522 -37.03701254
OS 31.04799734 -37.0356257
OS 31.03690262 -37.0356257
OS 31.02164738 -37.03423886
OS 30.85800026 -37.03423886
OS 30.85800026 -37.45999874
OS 30.73041098 -37.45999874
OS 30.73041098 -36.50030546
OS 31.17558662 -36.50030546
OS 31.18668134 -36.5016923
OE
OB 38.16387338 -36.60709214 H
OS 37.86154226 -36.60709214
OS 37.86154226 -36.9246785
OS 38.1472313 -36.9246785
OS 38.16387338 -36.92329166
OS 38.18328914 -36.92190482
OS 38.20547858 -36.92051798
OS 38.22766802 -36.9177443
OS 38.24985746 -36.91358378
OS 38.26927322 -36.90803642
OS 38.2720469 -36.90664958
OS 38.27759426 -36.9038759
OS 38.2859153 -36.89971538
OS 38.29701002 -36.89416802
OS 38.30949158 -36.88584698
OS 38.32197314 -36.8761391
OS 38.3344547 -36.86365754
OS 38.34416258 -36.84978914
OS 38.34554942 -36.8484023
OS 38.3483231 -36.84285494
OS 38.35248362 -36.8345339
OS 38.35803098 -36.82343918
OS 38.3621915 -36.81095762
OS 38.36635202 -36.79708922
OS 38.3691257 -36.78044714
OS 38.37051254 -36.76380506
OS 38.37051254 -36.76241822
OS 38.37051254 -36.76103138
OS 38.3691257 -36.75271034
OS 38.36773886 -36.74022878
OS 38.36496518 -36.7235867
OS 38.35803098 -36.70694462
OS 38.34970994 -36.68752886
OS 38.33722838 -36.66949994
OS 38.3205863 -36.65147102
OS 38.31781262 -36.65008418
OS 38.31087842 -36.64453682
OS 38.2997837 -36.63760262
OS 38.28175478 -36.62928158
OS 38.26095218 -36.62096054
OS 38.23321538 -36.61402634
OS 38.20131806 -36.60847898
OS 38.16387338 -36.60709214
OE
OB 29.34218414 -36.61402634 H
OS 29.06758982 -36.61402634
OS 29.06758982 -36.95657582
OS 29.32554206 -36.95657582
OS 29.33524994 -36.95518898
OS 29.34495782 -36.95518898
OS 29.35605254 -36.95380214
OS 29.3824025 -36.95102846
OS 29.41152614 -36.9454811
OS 29.44064978 -36.93716006
OS 29.46699974 -36.92606534
OS 29.4794813 -36.91913114
OS 29.48918918 -36.9108101
OS 29.49196286 -36.90803642
OS 29.49751022 -36.90248906
OS 29.50583126 -36.89139434
OS 29.51553914 -36.87752594
OS 29.52524702 -36.85949702
OS 29.53356806 -36.83730758
OS 29.53911542 -36.81234446
OS 29.5418891 -36.78322082
OS 29.5418891 -36.78183398
OS 29.5418891 -36.78044714
OS 29.5418891 -36.77351294
OS 29.54050226 -36.76103138
OS 29.53772858 -36.74716298
OS 29.5349549 -36.73190774
OS 29.52940754 -36.71387882
OS 29.5210865 -36.69723674
OS 29.51137862 -36.68059466
OS 29.50999178 -36.67920782
OS 29.50583126 -36.67366046
OS 29.49889706 -36.66672626
OS 29.49057602 -36.65701838
OS 29.47809446 -36.6473105
OS 29.46422606 -36.63898946
OS 29.44897082 -36.63066842
OS 29.4309419 -36.62373422
OS 29.42955506 -36.62373422
OS 29.4240077 -36.62234738
OS 29.41568666 -36.62096054
OS 29.40459194 -36.61818686
OS 29.38794986 -36.61680002
OS 29.36714726 -36.61541318
OS 29.34218414 -36.61402634
OE
OB 30.16180658 -36.60015794 H
OS 30.16180658 -36.60154478
OS 30.16041974 -36.60431846
OS 30.16041974 -36.60986582
OS 30.15764606 -36.61541318
OS 30.15625922 -36.62512106
OS 30.15348554 -36.63482894
OS 30.14793818 -36.65840522
OS 30.14100398 -36.68614202
OS 30.1312961 -36.7166525
OS 30.12158822 -36.74993666
OS 30.10910666 -36.78460766
OS 30.00509366 -37.06474934
OS 30.32961422 -37.06474934
OS 30.22976174 -36.80124974
OS 30.22976174 -36.7998629
OS 30.2283749 -36.79570238
OS 30.22560122 -36.78876818
OS 30.22282754 -36.78044714
OS 30.21866702 -36.77073926
OS 30.2145065 -36.7582577
OS 30.21034598 -36.7443893
OS 30.20479862 -36.7305209
OS 30.1937039 -36.69862358
OS 30.18260918 -36.66533942
OS 30.17151446 -36.63205526
OS 30.16180658 -36.60015794
OE
OB 31.16033138 -36.60709214 H
OS 30.85800026 -36.60709214
OS 30.85800026 -36.9246785
OS 31.1436893 -36.9246785
OS 31.16033138 -36.92329166
OS 31.17974714 -36.92190482
OS 31.20193658 -36.92051798
OS 31.22412602 -36.9177443
OS 31.24631546 -36.91358378
OS 31.26573122 -36.90803642
OS 31.2685049 -36.90664958
OS 31.27405226 -36.9038759
OS 31.2823733 -36.89971538
OS 31.29346802 -36.89416802
OS 31.30594958 -36.88584698
OS 31.31843114 -36.8761391
OS 31.3309127 -36.86365754
OS 31.34062058 -36.84978914
OS 31.34200742 -36.8484023
OS 31.3447811 -36.84285494
OS 31.34894162 -36.8345339
OS 31.35448898 -36.82343918
OS 31.3586495 -36.81095762
OS 31.36281002 -36.79708922
OS 31.3655837 -36.78044714
OS 31.36697054 -36.76380506
OS 31.36697054 -36.76241822
OS 31.36697054 -36.76103138
OS 31.3655837 -36.75271034
OS 31.36419686 -36.74022878
OS 31.36142318 -36.7235867
OS 31.35448898 -36.70694462
OS 31.34616794 -36.68752886
OS 31.33368638 -36.66949994
OS 31.3170443 -36.65147102
OS 31.31427062 -36.65008418
OS 31.30733642 -36.64453682
OS 31.2962417 -36.63760262
OS 31.27821278 -36.62928158
OS 31.25741018 -36.62096054
OS 31.22967338 -36.61402634
OS 31.19777606 -36.60847898
OS 31.16033138 -36.60709214
OE
OB 36.29302622 -36.61402634 H
OS 36.06558446 -36.61402634
OS 36.06558446 -36.90248906
OS 36.30134726 -36.90248906
OS 36.31937618 -36.90110222
OS 36.33879194 -36.89971538
OS 36.3582077 -36.89832854
OS 36.37762346 -36.89555486
OS 36.3928787 -36.89278118
OS 36.39565238 -36.89139434
OS 36.40119974 -36.8900075
OS 36.40952078 -36.88584698
OS 36.4206155 -36.88029962
OS 36.43171022 -36.87475226
OS 36.44419178 -36.86643122
OS 36.45667334 -36.8553365
OS 36.46638122 -36.84424178
OS 36.46776806 -36.84285494
OS 36.47054174 -36.83869442
OS 36.47470226 -36.83037338
OS 36.47886278 -36.8206655
OS 36.4830233 -36.80957078
OS 36.48718382 -36.79570238
OS 36.4899575 -36.7790603
OS 36.49134434 -36.76103138
OS 36.49134434 -36.7582577
OS 36.49134434 -36.75271034
OS 36.4899575 -36.7443893
OS 36.48857066 -36.73329458
OS 36.48579698 -36.71942618
OS 36.48163646 -36.70555778
OS 36.4760891 -36.69168938
OS 36.46776806 -36.67782098
OS 36.46638122 -36.67643414
OS 36.46360754 -36.67227362
OS 36.45806018 -36.66533942
OS 36.45112598 -36.65840522
OS 36.4414181 -36.65008418
OS 36.43032338 -36.64176314
OS 36.41645498 -36.6334421
OS 36.40119974 -36.62789474
OS 36.3998129 -36.62789474
OS 36.3928787 -36.62512106
OS 36.38317082 -36.62373422
OS 36.36791558 -36.62096054
OS 36.34711298 -36.61818686
OS 36.3235367 -36.61680002
OS 36.29302622 -36.61402634
OE
OB 36.31798934 -37.01620994 H
OS 36.06558446 -37.01620994
OS 36.06558446 -37.34627786
OS 36.33879194 -37.34627786
OS 36.36791558 -37.34489102
OS 36.38039714 -37.34350418
OS 36.39149186 -37.34211734
OS 36.3928787 -37.34211734
OS 36.39842606 -37.3407305
OS 36.4067471 -37.33934366
OS 36.41645498 -37.33656998
OS 36.44003126 -37.32824894
OS 36.46360754 -37.31715422
OS 36.46499438 -37.31576738
OS 36.4691549 -37.3129937
OS 36.47470226 -37.30883318
OS 36.48163646 -37.30328582
OS 36.48857066 -37.29496478
OS 36.49827854 -37.28664374
OS 36.50521274 -37.27554902
OS 36.51353378 -37.26306746
OS 36.51492062 -37.26168062
OS 36.51630746 -37.2575201
OS 36.51908114 -37.24919906
OS 36.52324166 -37.23949118
OS 36.52740218 -37.22839646
OS 36.53017586 -37.21452806
OS 36.5315627 -37.19788598
OS 36.53294954 -37.1812439
OS 36.53294954 -37.17847022
OS 36.53294954 -37.17292286
OS 36.5315627 -37.16182814
OS 36.52878902 -37.14934658
OS 36.52601534 -37.13547818
OS 36.52046798 -37.12022294
OS 36.51353378 -37.1049677
OS 36.5038259 -37.08971246
OS 36.50243906 -37.08832562
OS 36.49827854 -37.08277826
OS 36.49273118 -37.07584406
OS 36.48441014 -37.06752302
OS 36.47331542 -37.05781514
OS 36.45944702 -37.04810726
OS 36.44419178 -37.03978622
OS 36.42616286 -37.03285202
OS 36.42338918 -37.03146518
OS 36.41784182 -37.03007834
OS 36.40536026 -37.02730466
OS 36.39010502 -37.02453098
OS 36.37068926 -37.0217573
OS 36.34711298 -37.01898362
OS 36.31798934 -37.01620994
OE
SE
S P 0
OB 40.9056459 -38.32112732 I
OS 40.92136342 -38.32205188
OS 40.9380055 -38.32297644
OS 40.95372302 -38.32482556
OS 40.96759142 -38.32667468
OS 40.96944054 -38.32667468
OS 40.97591246 -38.3285238
OS 40.9842335 -38.33037292
OS 40.99532822 -38.3331466
OS 41.0073475 -38.3377694
OS 41.02029134 -38.34331676
OS 41.03415974 -38.34978868
OS 41.04617902 -38.35718516
OS 41.04802814 -38.35810972
OS 41.05172638 -38.3608834
OS 41.05727374 -38.36643076
OS 41.06467022 -38.37290268
OS 41.07299126 -38.38122372
OS 41.0813123 -38.39231844
OS 41.0905579 -38.40433772
OS 41.09795438 -38.41820612
OS 41.09887894 -38.42005524
OS 41.10072806 -38.42467804
OS 41.1044263 -38.43299908
OS 41.10812454 -38.4440938
OS 41.11089822 -38.45703764
OS 41.11459646 -38.4718306
OS 41.11644558 -38.48847268
OS 41.11737014 -38.50603932
OS 41.11737014 -38.50696388
OS 41.11737014 -38.50973756
OS 41.11737014 -38.5134358
OS 41.11644558 -38.51990772
OS 41.11552102 -38.52637964
OS 41.11459646 -38.53470068
OS 41.11274734 -38.54394628
OS 41.11089822 -38.55411644
OS 41.1044263 -38.57538132
OS 41.10072806 -38.58647604
OS 41.0951807 -38.59849532
OS 41.08870878 -38.6105146
OS 41.08223686 -38.62160932
OS 41.07391582 -38.63270404
OS 41.06467022 -38.64379876
OS 41.06374566 -38.64472332
OS 41.06189654 -38.64657244
OS 41.05912286 -38.64934612
OS 41.05450006 -38.6521198
OS 41.0489527 -38.6567426
OS 41.04155622 -38.6613654
OS 41.03231062 -38.66691276
OS 41.02214046 -38.67153556
OS 41.01012118 -38.67708292
OS 40.99625278 -38.68263028
OS 40.98145982 -38.68725308
OS 40.96389318 -38.69095132
OS 40.94540198 -38.69464956
OS 40.92506166 -38.69742324
OS 40.90194766 -38.69927236
OS 40.8779091 -38.70019692
OS 40.71426198 -38.70019692
OS 40.71426198 -38.95999828
OS 40.62920246 -38.95999828
OS 40.62920246 -38.32020276
OS 40.8917775 -38.32020276
OS 40.9056459 -38.32112732
OE
OB 40.49791494 -38.98403684 I
OS 40.49791494 -38.9849614
OS 40.49791494 -38.98773508
OS 40.49791494 -38.99235788
OS 40.49791494 -38.99790524
OS 40.49699038 -39.00530172
OS 40.49699038 -39.0126982
OS 40.49514126 -39.0311894
OS 40.49236758 -39.05060516
OS 40.48866934 -39.07094548
OS 40.48312198 -39.08851212
OS 40.47942374 -39.09683316
OS 40.4757255 -39.10330508
OS 40.4757255 -39.10422964
OS 40.47480094 -39.1051542
OS 40.47017814 -39.109777
OS 40.46278166 -39.11717348
OS 40.45353606 -39.12549452
OS 40.44059222 -39.13381556
OS 40.42395014 -39.14028748
OS 40.40453438 -39.14583484
OS 40.39343966 -39.1467594
OS 40.38142038 -39.14768396
OS 40.37587302 -39.14768396
OS 40.37032566 -39.1467594
OS 40.36200462 -39.1467594
OS 40.35275902 -39.14583484
OS 40.34258886 -39.14398572
OS 40.32039942 -39.13843836
OS 40.33519238 -39.07187004
OS 40.33611694 -39.07187004
OS 40.33889062 -39.0727946
OS 40.34351342 -39.07371916
OS 40.34813622 -39.07464372
OS 40.3601555 -39.0774174
OS 40.36570286 -39.07834196
OS 40.37494846 -39.07834196
OS 40.37957126 -39.0774174
OS 40.38511862 -39.07649284
OS 40.39066598 -39.07464372
OS 40.39621334 -39.07094548
OS 40.40268526 -39.06724724
OS 40.40730806 -39.06169988
OS 40.40823262 -39.06077532
OS 40.40915718 -39.05800164
OS 40.4110063 -39.05337884
OS 40.41377998 -39.04598236
OS 40.4156291 -39.0358122
OS 40.41655366 -39.02841572
OS 40.41747822 -39.0219438
OS 40.41840278 -39.01362276
OS 40.41840278 -39.0034526
OS 40.41932734 -38.99328244
OS 40.41932734 -38.98218772
OS 40.41932734 -38.49586916
OS 40.49791494 -38.49586916
OS 40.49791494 -38.98403684
OE
OB 41.51770462 -38.3100326 I
OS 41.52602566 -38.31095716
OS 41.53619582 -38.31188172
OS 41.54636598 -38.31280628
OS 41.55838526 -38.31557996
OS 41.58334838 -38.32112732
OS 41.61108518 -38.32944836
OS 41.62495358 -38.33499572
OS 41.63789742 -38.34146764
OS 41.65084126 -38.34978868
OS 41.6637851 -38.35810972
OS 41.66470966 -38.35903428
OS 41.66655878 -38.35995884
OS 41.67025702 -38.36273252
OS 41.67487982 -38.36735532
OS 41.67950262 -38.37197812
OS 41.68597454 -38.37845004
OS 41.69244646 -38.38584652
OS 41.69984294 -38.393243
OS 41.70723942 -38.4024886
OS 41.7146359 -38.41358332
OS 41.72295694 -38.42467804
OS 41.73035342 -38.43669732
OS 41.73682534 -38.45056572
OS 41.74422182 -38.46443412
OS 41.74976918 -38.47922708
OS 41.75531654 -38.49586916
OS 41.67210614 -38.51528492
OS 41.67210614 -38.51436036
OS 41.67118158 -38.51251124
OS 41.66933246 -38.508813
OS 41.66748334 -38.5041902
OS 41.66563422 -38.49864284
OS 41.66286054 -38.49124636
OS 41.65546406 -38.4764534
OS 41.64621846 -38.45981132
OS 41.63512374 -38.44316924
OS 41.62125534 -38.42745172
OS 41.60646238 -38.41358332
OS 41.60461326 -38.4117342
OS 41.5990659 -38.40803596
OS 41.5898203 -38.40341316
OS 41.57780102 -38.39694124
OS 41.5620835 -38.39139388
OS 41.54451686 -38.38584652
OS 41.52325198 -38.38214828
OS 41.50013798 -38.38122372
OS 41.4927415 -38.38122372
OS 41.4881187 -38.38214828
OS 41.48164678 -38.38214828
OS 41.4742503 -38.38307284
OS 41.45668366 -38.38584652
OS 41.4372679 -38.38954476
OS 41.41692758 -38.39601668
OS 41.3956627 -38.40526228
OS 41.37624694 -38.41728156
OS 41.37532238 -38.41728156
OS 41.37439782 -38.41913068
OS 41.3679259 -38.42375348
OS 41.35960486 -38.43114996
OS 41.3494347 -38.44224468
OS 41.33741542 -38.45611308
OS 41.3263207 -38.4718306
OS 41.31615054 -38.49124636
OS 41.30690494 -38.51251124
OS 41.30690494 -38.5134358
OS 41.30598038 -38.51528492
OS 41.30505582 -38.5180586
OS 41.30413126 -38.5226814
OS 41.30228214 -38.52822876
OS 41.30043302 -38.53470068
OS 41.29765934 -38.5504182
OS 41.2939611 -38.5689094
OS 41.29026286 -38.58924972
OS 41.28841374 -38.61143916
OS 41.28748918 -38.63547772
OS 41.28748918 -38.63640228
OS 41.28748918 -38.63917596
OS 41.28748918 -38.64379876
OS 41.28748918 -38.64934612
OS 41.28841374 -38.65581804
OS 41.28841374 -38.66413908
OS 41.2893383 -38.67338468
OS 41.29026286 -38.68355484
OS 41.29303654 -38.70574428
OS 41.29765934 -38.72978284
OS 41.3032067 -38.7538214
OS 41.31060318 -38.77785996
OS 41.31060318 -38.77878452
OS 41.31152774 -38.78063364
OS 41.31337686 -38.78340732
OS 41.31522598 -38.78803012
OS 41.32077334 -38.79912484
OS 41.32909438 -38.81206868
OS 41.33926454 -38.82686164
OS 41.35220838 -38.84257916
OS 41.36700134 -38.85644756
OS 41.38456798 -38.8693914
OS 41.38549254 -38.8693914
OS 41.38734166 -38.87031596
OS 41.39011534 -38.87216508
OS 41.39381358 -38.8740142
OS 41.39843638 -38.87586332
OS 41.40398374 -38.878637
OS 41.41692758 -38.88418436
OS 41.43356966 -38.88973172
OS 41.45206086 -38.89435452
OS 41.47240118 -38.89805276
OS 41.49366606 -38.89897732
OS 41.50013798 -38.89897732
OS 41.50568534 -38.89805276
OS 41.51215726 -38.89805276
OS 41.51862918 -38.8971282
OS 41.53527126 -38.89342996
OS 41.55468702 -38.88880716
OS 41.57410278 -38.88141068
OS 41.5944431 -38.87124052
OS 41.60461326 -38.86569316
OS 41.61385886 -38.85829668
OS 41.61478342 -38.85737212
OS 41.61570798 -38.85644756
OS 41.61848166 -38.85367388
OS 41.6221799 -38.8509002
OS 41.62587814 -38.8462774
OS 41.63050094 -38.84073004
OS 41.6360483 -38.83518268
OS 41.6406711 -38.8277862
OS 41.64621846 -38.81946516
OS 41.65269038 -38.81021956
OS 41.65823774 -38.80097396
OS 41.6637851 -38.78987924
OS 41.6684079 -38.77785996
OS 41.6730307 -38.76491612
OS 41.6776535 -38.75104772
OS 41.68135174 -38.73625476
OS 41.76641126 -38.75751964
OS 41.76641126 -38.7584442
OS 41.7654867 -38.76214244
OS 41.76363758 -38.7676898
OS 41.7608639 -38.77508628
OS 41.75809022 -38.78340732
OS 41.75439198 -38.79357748
OS 41.74976918 -38.8046722
OS 41.74422182 -38.81669148
OS 41.73127798 -38.84257916
OS 41.7146359 -38.86846684
OS 41.70446574 -38.88141068
OS 41.69429558 -38.89435452
OS 41.68320086 -38.90544924
OS 41.67025702 -38.91654396
OS 41.66933246 -38.91746852
OS 41.66748334 -38.91931764
OS 41.66286054 -38.92116676
OS 41.65823774 -38.924865
OS 41.65084126 -38.9294878
OS 41.64344478 -38.9341106
OS 41.63327462 -38.9387334
OS 41.62310446 -38.9433562
OS 41.61108518 -38.94890356
OS 41.59814134 -38.95352636
OS 41.58427294 -38.95814916
OS 41.56947998 -38.96277196
OS 41.55376246 -38.9664702
OS 41.53712038 -38.96831932
OS 41.51955374 -38.97016844
OS 41.50106254 -38.971093
OS 41.49089238 -38.971093
OS 41.4834959 -38.97016844
OS 41.47517486 -38.97016844
OS 41.4650047 -38.96924388
OS 41.45390998 -38.96739476
OS 41.44096614 -38.96554564
OS 41.4141539 -38.96092284
OS 41.3864171 -38.95352636
OS 41.3586803 -38.9433562
OS 41.34573646 -38.93688428
OS 41.33279262 -38.9294878
OS 41.33186806 -38.92856324
OS 41.33001894 -38.92763868
OS 41.3263207 -38.924865
OS 41.32262246 -38.92116676
OS 41.3170751 -38.91746852
OS 41.31060318 -38.91192116
OS 41.3032067 -38.90544924
OS 41.29581022 -38.89805276
OS 41.28841374 -38.88973172
OS 41.2800927 -38.88141068
OS 41.26345062 -38.8601458
OS 41.2477331 -38.83518268
OS 41.2338647 -38.80744588
OS 41.2338647 -38.80652132
OS 41.23201558 -38.80374764
OS 41.23109102 -38.79912484
OS 41.22831734 -38.79357748
OS 41.22646822 -38.786181
OS 41.22369454 -38.7769354
OS 41.2199963 -38.76676524
OS 41.21722262 -38.75567052
OS 41.21444894 -38.74365124
OS 41.2107507 -38.72978284
OS 41.2061279 -38.70112148
OS 41.20242966 -38.66876188
OS 41.20058054 -38.63547772
OS 41.20058054 -38.63455316
OS 41.20058054 -38.63085492
OS 41.20058054 -38.62530756
OS 41.2015051 -38.61883564
OS 41.2015051 -38.60959004
OS 41.20242966 -38.60034444
OS 41.20335422 -38.58832516
OS 41.20520334 -38.57630588
OS 41.20982614 -38.54949364
OS 41.21629806 -38.51990772
OS 41.22554366 -38.4903218
OS 41.2384875 -38.46166044
OS 41.23941206 -38.46073588
OS 41.24033662 -38.4579622
OS 41.24218574 -38.45426396
OS 41.24588398 -38.44964116
OS 41.24958222 -38.44316924
OS 41.25420502 -38.43577276
OS 41.2662243 -38.41913068
OS 41.28194182 -38.40063948
OS 41.30043302 -38.38214828
OS 41.3216979 -38.36365708
OS 41.34666102 -38.34793956
OS 41.34758558 -38.347015
OS 41.35035926 -38.34609044
OS 41.3540575 -38.34424132
OS 41.3586803 -38.34146764
OS 41.36607678 -38.33869396
OS 41.37347326 -38.33592028
OS 41.38271886 -38.33222204
OS 41.39288902 -38.3285238
OS 41.40398374 -38.32482556
OS 41.41600302 -38.32112732
OS 41.4418907 -38.31557996
OS 41.47147662 -38.31095716
OS 41.5019871 -38.30910804
OS 41.5112327 -38.30910804
OS 41.51770462 -38.3100326
OE
OB 42.90454462 -39.1375138 I
OS 42.38401734 -39.1375138
OS 42.38401734 -39.08111564
OS 42.90454462 -39.08111564
OS 42.90454462 -39.1375138
OE
OB 42.12514054 -38.32112732 I
OS 42.13253702 -38.32112732
OS 42.1491791 -38.32297644
OS 42.1676703 -38.32482556
OS 42.18708606 -38.3285238
OS 42.20650182 -38.3331466
OS 42.22406846 -38.33961852
OS 42.22499302 -38.33961852
OS 42.22591758 -38.34054308
OS 42.23146494 -38.34331676
OS 42.23978598 -38.34793956
OS 42.24903158 -38.35441148
OS 42.2601263 -38.36273252
OS 42.27214558 -38.37290268
OS 42.2832403 -38.38584652
OS 42.29341046 -38.39971492
OS 42.29433502 -38.40156404
OS 42.2971087 -38.4071114
OS 42.3017315 -38.41450788
OS 42.3063543 -38.4256026
OS 42.3109771 -38.43854644
OS 42.3155999 -38.45241484
OS 42.31837358 -38.46813236
OS 42.31929814 -38.48384988
OS 42.31929814 -38.485699
OS 42.31929814 -38.4903218
OS 42.31837358 -38.49864284
OS 42.31652446 -38.508813
OS 42.31375078 -38.52083228
OS 42.30912798 -38.53377612
OS 42.30358062 -38.54671996
OS 42.29618414 -38.56058836
OS 42.29525958 -38.56243748
OS 42.2924859 -38.56613572
OS 42.28693854 -38.5735322
OS 42.27954206 -38.58092868
OS 42.27029646 -38.59017428
OS 42.25920174 -38.60034444
OS 42.24533334 -38.60959004
OS 42.22961582 -38.61883564
OS 42.23054038 -38.61883564
OS 42.2323895 -38.6197602
OS 42.23516318 -38.62068476
OS 42.23886142 -38.62253388
OS 42.24995614 -38.62623212
OS 42.26289998 -38.63270404
OS 42.27676838 -38.64102508
OS 42.2924859 -38.65119524
OS 42.3063543 -38.66321452
OS 42.31929814 -38.67800748
OS 42.3202227 -38.6798566
OS 42.32392094 -38.68540396
OS 42.3294683 -38.693725
OS 42.33501566 -38.70481972
OS 42.34056302 -38.71961268
OS 42.34611038 -38.7353302
OS 42.34980862 -38.7538214
OS 42.35073318 -38.77416172
OS 42.35073318 -38.77508628
OS 42.35073318 -38.77601084
OS 42.35073318 -38.7815582
OS 42.34980862 -38.7908038
OS 42.3479595 -38.80189852
OS 42.34611038 -38.81484236
OS 42.34241214 -38.82871076
OS 42.33778934 -38.84350372
OS 42.33131742 -38.85829668
OS 42.33039286 -38.8601458
OS 42.32761918 -38.8647686
OS 42.32392094 -38.87124052
OS 42.31837358 -38.88048612
OS 42.3109771 -38.88973172
OS 42.30358062 -38.89990188
OS 42.29433502 -38.91007204
OS 42.28416486 -38.91839308
OS 42.2832403 -38.91931764
OS 42.27954206 -38.92209132
OS 42.27307014 -38.92578956
OS 42.2647491 -38.9294878
OS 42.25457894 -38.93503516
OS 42.24255966 -38.94058252
OS 42.22961582 -38.94520532
OS 42.2138983 -38.94982812
OS 42.21204918 -38.94982812
OS 42.20650182 -38.95167724
OS 42.19725622 -38.9526018
OS 42.18523694 -38.95445092
OS 42.17044398 -38.95630004
OS 42.15287734 -38.95814916
OS 42.13346158 -38.95907372
OS 42.11127214 -38.95999828
OS 41.8671883 -38.95999828
OS 41.8671883 -38.32020276
OS 42.11866862 -38.32020276
OS 42.12514054 -38.32112732
OE
OB 40.30745558 -38.48662356 I
OS 40.31762574 -38.48847268
OS 40.32964502 -38.49217092
OS 40.34258886 -38.49679372
OS 40.35738182 -38.50326564
OS 40.37309934 -38.51158668
OS 40.34443798 -38.58370236
OS 40.34351342 -38.5827778
OS 40.33981518 -38.58092868
OS 40.33426782 -38.578155
OS 40.32687134 -38.57538132
OS 40.3185503 -38.57260764
OS 40.30838014 -38.56983396
OS 40.29820998 -38.56798484
OS 40.28803982 -38.56706028
OS 40.28341702 -38.56706028
OS 40.27879422 -38.56798484
OS 40.2723223 -38.5689094
OS 40.26585038 -38.57075852
OS 40.25752934 -38.5735322
OS 40.2492083 -38.57723044
OS 40.24181182 -38.5827778
OS 40.24088726 -38.58370236
OS 40.23811358 -38.58555148
OS 40.2353399 -38.58924972
OS 40.2307171 -38.59387252
OS 40.2260943 -38.60034444
OS 40.2214715 -38.60774092
OS 40.2168487 -38.61606196
OS 40.21315046 -38.62623212
OS 40.2122259 -38.62808124
OS 40.21130134 -38.6336286
OS 40.20945222 -38.64194964
OS 40.20667854 -38.65304436
OS 40.20390486 -38.66691276
OS 40.20205574 -38.68263028
OS 40.20113118 -38.69927236
OS 40.20020662 -38.71776356
OS 40.20020662 -38.95999828
OS 40.12161902 -38.95999828
OS 40.12161902 -38.49586916
OS 40.19281014 -38.49586916
OS 40.19281014 -38.56613572
OS 40.1937347 -38.56521116
OS 40.19743294 -38.55873924
OS 40.20205574 -38.5504182
OS 40.20945222 -38.54024804
OS 40.2168487 -38.53007788
OS 40.22516974 -38.51898316
OS 40.23349078 -38.50973756
OS 40.24181182 -38.50234108
OS 40.24273638 -38.50141652
OS 40.24551006 -38.4995674
OS 40.25105742 -38.49679372
OS 40.25660478 -38.49402004
OS 40.26400126 -38.49124636
OS 40.27324686 -38.48847268
OS 40.28249246 -38.48662356
OS 40.29266262 -38.485699
OS 40.29913454 -38.485699
OS 40.30745558 -38.48662356
OE
OB 39.48829542 -38.95999828 I
OS 39.3986131 -38.95999828
OS 39.3986131 -38.87031596
OS 39.48829542 -38.87031596
OS 39.48829542 -38.95999828
OE
OB 38.6404739 -38.95999828 I
OS 38.55171614 -38.95999828
OS 38.30393406 -38.32020276
OS 38.39639006 -38.32020276
OS 38.56281086 -38.78525644
OS 38.56281086 -38.786181
OS 38.56373542 -38.78803012
OS 38.56465998 -38.7908038
OS 38.5665091 -38.79450204
OS 38.56743366 -38.8000494
OS 38.56928278 -38.80559676
OS 38.57390558 -38.81946516
OS 38.57945294 -38.83518268
OS 38.5850003 -38.85274932
OS 38.59609502 -38.88973172
OS 38.59609502 -38.88880716
OS 38.59701958 -38.88695804
OS 38.59794414 -38.88418436
OS 38.5988687 -38.88048612
OS 38.60164238 -38.87031596
OS 38.60626518 -38.85644756
OS 38.61088798 -38.84073004
OS 38.61643534 -38.8231634
OS 38.62290726 -38.8046722
OS 38.63030374 -38.78525644
OS 38.80412102 -38.32020276
OS 38.8901051 -38.32020276
OS 38.6404739 -38.95999828
OE
OB 39.27564662 -38.42745172 I
OS 39.25438174 -38.54671996
OS 39.20538006 -38.54671996
OS 39.1859643 -38.42745172
OS 39.1859643 -38.32020276
OS 39.27564662 -38.32020276
OS 39.27564662 -38.42745172
OE
OB 40.49791494 -38.4117342 I
OS 40.41932734 -38.4117342
OS 40.41932734 -38.32020276
OS 40.49791494 -38.32020276
OS 40.49791494 -38.4117342
OE
OB 39.84517558 -38.48662356 I
OS 39.8516475 -38.48754812
OS 39.8655159 -38.48939724
OS 39.88215798 -38.49309548
OS 39.89972462 -38.49864284
OS 39.91729126 -38.50696388
OS 39.9348579 -38.51713404
OS 39.93578246 -38.51713404
OS 39.93670702 -38.51898316
OS 39.94225438 -38.5226814
OS 39.95057542 -38.53007788
OS 39.96074558 -38.53932348
OS 39.9718403 -38.55134276
OS 39.98293502 -38.56613572
OS 39.99402974 -38.58370236
OS 40.00327534 -38.60311812
OS 40.00327534 -38.60404268
OS 40.0041999 -38.6058918
OS 40.00512446 -38.60866548
OS 40.00697358 -38.61236372
OS 40.0088227 -38.61791108
OS 40.01067182 -38.624383
OS 40.01529462 -38.63917596
OS 40.01991742 -38.65766716
OS 40.02361566 -38.67800748
OS 40.02638934 -38.70112148
OS 40.0273139 -38.72516004
OS 40.0273139 -38.7260846
OS 40.0273139 -38.72793372
OS 40.0273139 -38.73163196
OS 40.0273139 -38.73717932
OS 40.02638934 -38.74365124
OS 40.02638934 -38.75104772
OS 40.02454022 -38.7676898
OS 40.02084198 -38.78803012
OS 40.01621918 -38.809295
OS 40.00974726 -38.83148444
OS 40.00142622 -38.85367388
OS 40.00142622 -38.85459844
OS 40.00050166 -38.85644756
OS 39.99865254 -38.85922124
OS 39.99680342 -38.86291948
OS 39.9903315 -38.87308964
OS 39.98201046 -38.88603348
OS 39.9718403 -38.89990188
OS 39.95889646 -38.91377028
OS 39.9441035 -38.92763868
OS 39.92653686 -38.94058252
OS 39.9256123 -38.94058252
OS 39.92468774 -38.94150708
OS 39.92191406 -38.9433562
OS 39.91821582 -38.94520532
OS 39.90897022 -38.94982812
OS 39.89602638 -38.95537548
OS 39.88030886 -38.96092284
OS 39.86366678 -38.96554564
OS 39.84425102 -38.96924388
OS 39.82483526 -38.97016844
OS 39.81836334 -38.97016844
OS 39.81096686 -38.96924388
OS 39.80172126 -38.96831932
OS 39.79062654 -38.9664702
OS 39.77860726 -38.96369652
OS 39.76658798 -38.95999828
OS 39.7545687 -38.95445092
OS 39.75364414 -38.95352636
OS 39.74902134 -38.95167724
OS 39.74347398 -38.947979
OS 39.7360775 -38.94243164
OS 39.72868102 -38.93688428
OS 39.71943542 -38.9294878
OS 39.71111438 -38.92116676
OS 39.7037179 -38.91192116
OS 39.7037179 -39.1375138
OS 39.6251303 -39.1375138
OS 39.6251303 -38.49586916
OS 39.69632142 -38.49586916
OS 39.69632142 -38.55689012
OS 39.69724598 -38.555041
OS 39.70094422 -38.55134276
OS 39.70556702 -38.54487084
OS 39.7129635 -38.53747436
OS 39.72128454 -38.52822876
OS 39.73053014 -38.51990772
OS 39.74162486 -38.51158668
OS 39.75271958 -38.5041902
OS 39.7545687 -38.50326564
OS 39.75826694 -38.50141652
OS 39.76566342 -38.49864284
OS 39.77490902 -38.4949446
OS 39.78600374 -38.49124636
OS 39.79894758 -38.48847268
OS 39.81374054 -38.48662356
OS 39.83038262 -38.485699
OS 39.84055278 -38.485699
OS 39.84517558 -38.48662356
OE
OB 44.92193454 -38.40988508 I
OS 44.84334694 -38.40988508
OS 44.84334694 -38.32020276
OS 44.92193454 -38.32020276
OS 44.92193454 -38.40988508
OE
OB 45.24553054 -38.48662356 I
OS 45.25385158 -38.48754812
OS 45.26309718 -38.48939724
OS 45.27326734 -38.49124636
OS 45.28528662 -38.49309548
OS 45.31024974 -38.50141652
OS 45.32319358 -38.50603932
OS 45.33613742 -38.51251124
OS 45.34908126 -38.51898316
OS 45.3620251 -38.52822876
OS 45.37404438 -38.53747436
OS 45.38606366 -38.54856908
OS 45.38698822 -38.54949364
OS 45.38883734 -38.55134276
OS 45.39161102 -38.555041
OS 45.39530926 -38.5596638
OS 45.39993206 -38.56613572
OS 45.40547942 -38.57445676
OS 45.41102678 -38.58370236
OS 45.41657414 -38.59387252
OS 45.4221215 -38.60496724
OS 45.42766886 -38.61883564
OS 45.43321622 -38.63270404
OS 45.43783902 -38.64842156
OS 45.44153726 -38.66506364
OS 45.44431094 -38.68263028
OS 45.44616006 -38.70112148
OS 45.44708462 -38.7214618
OS 45.44708462 -38.72238636
OS 45.44708462 -38.72516004
OS 45.44708462 -38.72978284
OS 45.44708462 -38.73625476
OS 45.44616006 -38.74365124
OS 45.4452355 -38.75289684
OS 45.4452355 -38.76214244
OS 45.44338638 -38.7723126
OS 45.4406127 -38.7954266
OS 45.43506534 -38.8185406
OS 45.42859342 -38.8416546
OS 45.41934782 -38.86291948
OS 45.41934782 -38.86384404
OS 45.41842326 -38.8647686
OS 45.41657414 -38.86754228
OS 45.41472502 -38.87124052
OS 45.4082531 -38.88048612
OS 45.39993206 -38.89158084
OS 45.38883734 -38.90452468
OS 45.37496894 -38.91746852
OS 45.35925142 -38.93041236
OS 45.34076022 -38.94243164
OS 45.33983566 -38.94243164
OS 45.3389111 -38.9433562
OS 45.33613742 -38.94520532
OS 45.33151462 -38.94705444
OS 45.32689182 -38.94890356
OS 45.32134446 -38.95075268
OS 45.30747606 -38.95630004
OS 45.29175854 -38.96092284
OS 45.27234278 -38.96554564
OS 45.25200246 -38.96924388
OS 45.22981302 -38.97016844
OS 45.22056742 -38.97016844
OS 45.21317094 -38.96924388
OS 45.2048499 -38.96831932
OS 45.1956043 -38.9664702
OS 45.18450958 -38.96462108
OS 45.17341486 -38.96277196
OS 45.14845174 -38.95537548
OS 45.13458334 -38.94982812
OS 45.1216395 -38.94428076
OS 45.10869566 -38.93688428
OS 45.09575182 -38.92856324
OS 45.08373254 -38.91931764
OS 45.07171326 -38.90822292
OS 45.0707887 -38.90729836
OS 45.06893958 -38.90544924
OS 45.0661659 -38.901751
OS 45.06246766 -38.89620364
OS 45.05784486 -38.88973172
OS 45.05322206 -38.88233524
OS 45.0476747 -38.87308964
OS 45.04212734 -38.86199492
OS 45.03657998 -38.84997564
OS 45.03103262 -38.83610724
OS 45.02640982 -38.82131428
OS 45.02178702 -38.80559676
OS 45.01808878 -38.78803012
OS 45.0153151 -38.76953892
OS 45.01346598 -38.7491986
OS 45.01254142 -38.72793372
OS 45.01254142 -38.7260846
OS 45.01254142 -38.72238636
OS 45.01346598 -38.71591444
OS 45.01346598 -38.70666884
OS 45.01439054 -38.69649868
OS 45.01623966 -38.68355484
OS 45.01808878 -38.670611
OS 45.02178702 -38.65581804
OS 45.02548526 -38.64102508
OS 45.03010806 -38.62530756
OS 45.03565542 -38.60866548
OS 45.0430519 -38.59294796
OS 45.05044838 -38.578155
OS 45.06061854 -38.56336204
OS 45.0707887 -38.54949364
OS 45.08373254 -38.53747436
OS 45.0846571 -38.5365498
OS 45.08650622 -38.53562524
OS 45.09020446 -38.53285156
OS 45.09482726 -38.52915332
OS 45.10037462 -38.52545508
OS 45.1077711 -38.52083228
OS 45.11516758 -38.51620948
OS 45.12441318 -38.51158668
OS 45.13458334 -38.50696388
OS 45.14567806 -38.50234108
OS 45.17064118 -38.49402004
OS 45.19930254 -38.48754812
OS 45.2140955 -38.48662356
OS 45.22981302 -38.485699
OS 45.23905862 -38.485699
OS 45.24553054 -38.48662356
OE
OB 44.92193454 -38.95999828 I
OS 44.84334694 -38.95999828
OS 44.84334694 -38.49586916
OS 44.92193454 -38.49586916
OS 44.92193454 -38.95999828
OE
OB 46.10722046 -38.42745172 I
OS 46.08595558 -38.54671996
OS 46.0369539 -38.54671996
OS 46.01753814 -38.42745172
OS 46.01753814 -38.32020276
OS 46.10722046 -38.32020276
OS 46.10722046 -38.42745172
OE
OB 45.77160518 -38.48662356 I
OS 45.78177534 -38.48754812
OS 45.79379462 -38.48939724
OS 45.80673846 -38.49217092
OS 45.82060686 -38.49586916
OS 45.8335507 -38.50141652
OS 45.83539982 -38.50234108
OS 45.83909806 -38.5041902
OS 45.84556998 -38.50696388
OS 45.85296646 -38.51158668
OS 45.86221206 -38.51713404
OS 45.8705331 -38.52453052
OS 45.87885414 -38.531927
OS 45.88625062 -38.5411726
OS 45.88717518 -38.54209716
OS 45.8890243 -38.5457954
OS 45.89179798 -38.5504182
OS 45.89642078 -38.55689012
OS 45.90011902 -38.56613572
OS 45.90381726 -38.57538132
OS 45.90844006 -38.58647604
OS 45.91121374 -38.59849532
OS 45.91121374 -38.59941988
OS 45.9121383 -38.60311812
OS 45.91306286 -38.60866548
OS 45.91398742 -38.61606196
OS 45.91398742 -38.62715668
OS 45.91491198 -38.64010052
OS 45.91583654 -38.65581804
OS 45.91583654 -38.6752338
OS 45.91583654 -38.95999828
OS 45.83724894 -38.95999828
OS 45.83724894 -38.67893204
OS 45.83724894 -38.67800748
OS 45.83724894 -38.67708292
OS 45.83724894 -38.670611
OS 45.83724894 -38.66228996
OS 45.83632438 -38.6521198
OS 45.83539982 -38.64010052
OS 45.8335507 -38.62808124
OS 45.83077702 -38.61698652
OS 45.82800334 -38.60681636
OS 45.82800334 -38.6058918
OS 45.82615422 -38.60311812
OS 45.82338054 -38.59849532
OS 45.82060686 -38.59294796
OS 45.81598406 -38.5874006
OS 45.8104367 -38.58092868
OS 45.80304022 -38.57445676
OS 45.79471918 -38.5689094
OS 45.79379462 -38.56798484
OS 45.79102094 -38.56613572
OS 45.78547358 -38.5642866
OS 45.77900166 -38.56151292
OS 45.77160518 -38.55873924
OS 45.76235958 -38.55596556
OS 45.75126486 -38.555041
OS 45.74017014 -38.55411644
OS 45.73554734 -38.55411644
OS 45.7318491 -38.555041
OS 45.7226035 -38.55596556
OS 45.71058422 -38.55781468
OS 45.69764038 -38.56243748
OS 45.68284742 -38.56798484
OS 45.66805446 -38.57538132
OS 45.65418606 -38.58647604
OS 45.65233694 -38.58832516
OS 45.6486387 -38.59294796
OS 45.64586502 -38.5966462
OS 45.64309134 -38.601269
OS 45.6393931 -38.60681636
OS 45.63661942 -38.61328828
OS 45.63292118 -38.62068476
OS 45.62922294 -38.62993036
OS 45.62644926 -38.64010052
OS 45.62367558 -38.65119524
OS 45.62182646 -38.66321452
OS 45.61997734 -38.67615836
OS 45.61812822 -38.69187588
OS 45.61812822 -38.7075934
OS 45.61812822 -38.95999828
OS 45.53954062 -38.95999828
OS 45.53954062 -38.49586916
OS 45.60980718 -38.49586916
OS 45.60980718 -38.56243748
OS 45.61073174 -38.56151292
OS 45.61258086 -38.55873924
OS 45.61535454 -38.555041
OS 45.61905278 -38.5504182
OS 45.62460014 -38.54487084
OS 45.63107206 -38.53839892
OS 45.63846854 -38.53100244
OS 45.64771414 -38.52360596
OS 45.65695974 -38.51713404
OS 45.66805446 -38.50973756
OS 45.68007374 -38.50326564
OS 45.69301758 -38.49771828
OS 45.70781054 -38.49309548
OS 45.7226035 -38.48939724
OS 45.73924558 -38.48662356
OS 45.75681222 -38.485699
OS 45.7642087 -38.485699
OS 45.77160518 -38.48662356
OE
OB 44.2756671 -38.95999828 I
OS 44.1970795 -38.95999828
OS 44.1970795 -38.49586916
OS 44.2756671 -38.49586916
OS 44.2756671 -38.95999828
OE
OB 43.4574315 -38.48662356 I
OS 43.46482798 -38.48754812
OS 43.47407358 -38.48939724
OS 43.48424374 -38.49124636
OS 43.49626302 -38.49402004
OS 43.50735774 -38.49679372
OS 43.52030158 -38.50141652
OS 43.53232086 -38.50603932
OS 43.5452647 -38.51251124
OS 43.55820854 -38.51990772
OS 43.57115238 -38.52822876
OS 43.58317166 -38.53839892
OS 43.59426638 -38.54949364
OS 43.59519094 -38.5504182
OS 43.59704006 -38.55226732
OS 43.59981374 -38.55596556
OS 43.60351198 -38.56151292
OS 43.60813478 -38.56798484
OS 43.61275758 -38.57538132
OS 43.61830494 -38.58462692
OS 43.6238523 -38.59572164
OS 43.62939966 -38.60774092
OS 43.63494702 -38.62068476
OS 43.63956982 -38.63547772
OS 43.64419262 -38.65119524
OS 43.64789086 -38.66876188
OS 43.65066454 -38.68725308
OS 43.65251366 -38.70666884
OS 43.65343822 -38.72793372
OS 43.65343822 -38.72885828
OS 43.65343822 -38.73255652
OS 43.65343822 -38.73902844
OS 43.65251366 -38.74827404
OS 43.30580366 -38.74827404
OS 43.30580366 -38.7491986
OS 43.30580366 -38.75197228
OS 43.30672822 -38.75567052
OS 43.30672822 -38.76121788
OS 43.30765278 -38.7676898
OS 43.3095019 -38.77508628
OS 43.31227558 -38.79172836
OS 43.31782294 -38.81021956
OS 43.32521942 -38.83055988
OS 43.33538958 -38.84905108
OS 43.34833342 -38.86569316
OS 43.34925798 -38.86569316
OS 43.35018254 -38.86754228
OS 43.3557299 -38.87216508
OS 43.36405094 -38.878637
OS 43.37514566 -38.88510892
OS 43.38993862 -38.8925054
OS 43.4065807 -38.89897732
OS 43.4250719 -38.90360012
OS 43.43524206 -38.90452468
OS 43.44633678 -38.90544924
OS 43.45373326 -38.90544924
OS 43.4620543 -38.90452468
OS 43.47222446 -38.90267556
OS 43.48331918 -38.89990188
OS 43.49626302 -38.89620364
OS 43.5082823 -38.89065628
OS 43.52030158 -38.8832598
OS 43.52122614 -38.88233524
OS 43.52584894 -38.878637
OS 43.5313963 -38.87308964
OS 43.53786822 -38.86569316
OS 43.5452647 -38.855523
OS 43.55358574 -38.84257916
OS 43.56190678 -38.8277862
OS 43.56930326 -38.81021956
OS 43.65066454 -38.82038972
OS 43.65066454 -38.82131428
OS 43.64973998 -38.8231634
OS 43.64881542 -38.82686164
OS 43.6469663 -38.832409
OS 43.64419262 -38.83795636
OS 43.64141894 -38.84535284
OS 43.63402246 -38.86107036
OS 43.62477686 -38.878637
OS 43.61183302 -38.8971282
OS 43.59704006 -38.91469484
OS 43.57854886 -38.93133692
OS 43.5776243 -38.93133692
OS 43.57577518 -38.93318604
OS 43.5730015 -38.93503516
OS 43.56930326 -38.93780884
OS 43.5637559 -38.94058252
OS 43.55820854 -38.9433562
OS 43.55081206 -38.94705444
OS 43.54249102 -38.95075268
OS 43.53324542 -38.95445092
OS 43.52399982 -38.95814916
OS 43.50088582 -38.96369652
OS 43.47499814 -38.96831932
OS 43.44633678 -38.97016844
OS 43.43616662 -38.97016844
OS 43.4296947 -38.96924388
OS 43.42137366 -38.96831932
OS 43.4112035 -38.9664702
OS 43.40010878 -38.96462108
OS 43.3880895 -38.96277196
OS 43.36220182 -38.95537548
OS 43.34833342 -38.94982812
OS 43.33538958 -38.94428076
OS 43.32152118 -38.93688428
OS 43.30857734 -38.92856324
OS 43.29655806 -38.91931764
OS 43.28453878 -38.90822292
OS 43.28361422 -38.90729836
OS 43.2817651 -38.90544924
OS 43.27899142 -38.901751
OS 43.27529318 -38.89620364
OS 43.27067038 -38.88973172
OS 43.26604758 -38.88233524
OS 43.26050022 -38.87308964
OS 43.25495286 -38.86291948
OS 43.2494055 -38.8509002
OS 43.24385814 -38.83795636
OS 43.23923534 -38.8231634
OS 43.23461254 -38.80744588
OS 43.2309143 -38.7908038
OS 43.22814062 -38.7723126
OS 43.2262915 -38.75289684
OS 43.22536694 -38.73255652
OS 43.22536694 -38.73163196
OS 43.22536694 -38.72700916
OS 43.22536694 -38.7214618
OS 43.2262915 -38.71314076
OS 43.22721606 -38.7029706
OS 43.22814062 -38.69187588
OS 43.22998974 -38.67893204
OS 43.23276342 -38.6659882
OS 43.2401599 -38.63640228
OS 43.2447827 -38.62160932
OS 43.25033006 -38.6058918
OS 43.25772654 -38.59109884
OS 43.26604758 -38.57723044
OS 43.27529318 -38.56336204
OS 43.28546334 -38.5504182
OS 43.2863879 -38.54949364
OS 43.28823702 -38.54764452
OS 43.29193526 -38.54487084
OS 43.29655806 -38.54024804
OS 43.30210542 -38.53562524
OS 43.3095019 -38.53007788
OS 43.31782294 -38.52360596
OS 43.3279931 -38.5180586
OS 43.33816326 -38.51158668
OS 43.35018254 -38.50603932
OS 43.36312638 -38.50049196
OS 43.37699478 -38.49586916
OS 43.39178774 -38.49124636
OS 43.40750526 -38.48847268
OS 43.42414734 -38.48662356
OS 43.44171398 -38.485699
OS 43.45095958 -38.485699
OS 43.4574315 -38.48662356
OE
OB 43.13938286 -38.48662356 I
OS 43.14955302 -38.48847268
OS 43.1615723 -38.49217092
OS 43.17451614 -38.49679372
OS 43.1893091 -38.50326564
OS 43.20502662 -38.51158668
OS 43.17636526 -38.58370236
OS 43.1754407 -38.5827778
OS 43.17174246 -38.58092868
OS 43.1661951 -38.578155
OS 43.15879862 -38.57538132
OS 43.15047758 -38.57260764
OS 43.14030742 -38.56983396
OS 43.13013726 -38.56798484
OS 43.1199671 -38.56706028
OS 43.1153443 -38.56706028
OS 43.1107215 -38.56798484
OS 43.10424958 -38.5689094
OS 43.09777766 -38.57075852
OS 43.08945662 -38.5735322
OS 43.08113558 -38.57723044
OS 43.0737391 -38.5827778
OS 43.07281454 -38.58370236
OS 43.07004086 -38.58555148
OS 43.06726718 -38.58924972
OS 43.06264438 -38.59387252
OS 43.05802158 -38.60034444
OS 43.05339878 -38.60774092
OS 43.04877598 -38.61606196
OS 43.04507774 -38.62623212
OS 43.04415318 -38.62808124
OS 43.04322862 -38.6336286
OS 43.0413795 -38.64194964
OS 43.03860582 -38.65304436
OS 43.03583214 -38.66691276
OS 43.03398302 -38.68263028
OS 43.03305846 -38.69927236
OS 43.0321339 -38.71776356
OS 43.0321339 -38.95999828
OS 42.9535463 -38.95999828
OS 42.9535463 -38.49586916
OS 43.02473742 -38.49586916
OS 43.02473742 -38.56613572
OS 43.02566198 -38.56521116
OS 43.02936022 -38.55873924
OS 43.03398302 -38.5504182
OS 43.0413795 -38.54024804
OS 43.04877598 -38.53007788
OS 43.05709702 -38.51898316
OS 43.06541806 -38.50973756
OS 43.0737391 -38.50234108
OS 43.07466366 -38.50141652
OS 43.07743734 -38.4995674
OS 43.0829847 -38.49679372
OS 43.08853206 -38.49402004
OS 43.09592854 -38.49124636
OS 43.10517414 -38.48847268
OS 43.11441974 -38.48662356
OS 43.1245899 -38.485699
OS 43.13106182 -38.485699
OS 43.13938286 -38.48662356
OE
OB 43.95022198 -38.95999828 I
OS 43.87533262 -38.95999828
OS 43.70059078 -38.49586916
OS 43.78380118 -38.49586916
OS 43.88365366 -38.77416172
OS 43.88365366 -38.77508628
OS 43.88457822 -38.77601084
OS 43.88550278 -38.77878452
OS 43.88642734 -38.7815582
OS 43.88920102 -38.7908038
OS 43.89289926 -38.80282308
OS 43.89752206 -38.81669148
OS 43.90306942 -38.832409
OS 43.90769222 -38.84997564
OS 43.91323958 -38.86754228
OS 43.91416414 -38.86569316
OS 43.9150887 -38.86107036
OS 43.91786238 -38.85367388
OS 43.92063606 -38.84257916
OS 43.92525886 -38.83055988
OS 43.92988166 -38.81484236
OS 43.93635358 -38.79820028
OS 43.9428255 -38.77970908
OS 44.04545166 -38.49586916
OS 44.12681294 -38.49586916
OS 43.95022198 -38.95999828
OE
OB 44.2756671 -38.40988508 I
OS 44.1970795 -38.40988508
OS 44.1970795 -38.32020276
OS 44.2756671 -38.32020276
OS 44.2756671 -38.40988508
OE
OB 44.5669035 -38.48662356 I
OS 44.5807719 -38.48754812
OS 44.59556486 -38.48939724
OS 44.61128238 -38.49309548
OS 44.62792446 -38.49679372
OS 44.64364198 -38.50234108
OS 44.64456654 -38.50234108
OS 44.6454911 -38.50326564
OS 44.6501139 -38.50511476
OS 44.65751038 -38.508813
OS 44.66675598 -38.5134358
OS 44.67692614 -38.51990772
OS 44.6870963 -38.5273042
OS 44.6963419 -38.53562524
OS 44.70466294 -38.54487084
OS 44.7055875 -38.5457954
OS 44.70743662 -38.54949364
OS 44.71113486 -38.55596556
OS 44.71575766 -38.56336204
OS 44.72038046 -38.57445676
OS 44.72500326 -38.58647604
OS 44.7287015 -38.60034444
OS 44.73239974 -38.61606196
OS 44.65566126 -38.62623212
OS 44.65566126 -38.624383
OS 44.6547367 -38.62068476
OS 44.65288758 -38.61421284
OS 44.6501139 -38.6058918
OS 44.6454911 -38.59757076
OS 44.63994374 -38.58832516
OS 44.63347182 -38.57907956
OS 44.62422622 -38.57075852
OS 44.62330166 -38.56983396
OS 44.61960342 -38.56798484
OS 44.61405606 -38.5642866
OS 44.60573502 -38.56058836
OS 44.59648942 -38.55689012
OS 44.58447014 -38.55319188
OS 44.56967718 -38.55134276
OS 44.55395966 -38.5504182
OS 44.54471406 -38.5504182
OS 44.53546846 -38.55134276
OS 44.52344918 -38.55226732
OS 44.5114299 -38.555041
OS 44.49848606 -38.55781468
OS 44.48646678 -38.56243748
OS 44.47629662 -38.5689094
OS 44.47537206 -38.56983396
OS 44.47259838 -38.57168308
OS 44.46890014 -38.57538132
OS 44.4652019 -38.58092868
OS 44.4605791 -38.58647604
OS 44.45688086 -38.59387252
OS 44.45410718 -38.60219356
OS 44.45318262 -38.6105146
OS 44.45318262 -38.61143916
OS 44.45318262 -38.61328828
OS 44.45410718 -38.61606196
OS 44.45410718 -38.6197602
OS 44.45688086 -38.6290058
OS 44.46242822 -38.6382514
OS 44.46335278 -38.63917596
OS 44.46427734 -38.64010052
OS 44.46612646 -38.6428742
OS 44.4698247 -38.64564788
OS 44.47352294 -38.64842156
OS 44.4790703 -38.6521198
OS 44.48554222 -38.65489348
OS 44.4929387 -38.65859172
OS 44.49386326 -38.65859172
OS 44.49571238 -38.65951628
OS 44.49941062 -38.66044084
OS 44.50588254 -38.66321452
OS 44.51512814 -38.6659882
OS 44.52714742 -38.66876188
OS 44.5345439 -38.67153556
OS 44.54286494 -38.67338468
OS 44.55211054 -38.67615836
OS 44.5622807 -38.67893204
OS 44.56320526 -38.67893204
OS 44.56597894 -38.6798566
OS 44.57060174 -38.68078116
OS 44.5761491 -38.68263028
OS 44.58262102 -38.6844794
OS 44.59094206 -38.68632852
OS 44.6085087 -38.69187588
OS 44.62792446 -38.69742324
OS 44.64734022 -38.70389516
OS 44.66490686 -38.71036708
OS 44.67230334 -38.71314076
OS 44.67877526 -38.71591444
OS 44.68062438 -38.716839
OS 44.68432262 -38.71868812
OS 44.68986998 -38.7214618
OS 44.69819102 -38.7260846
OS 44.70651206 -38.73163196
OS 44.7148331 -38.73902844
OS 44.72315414 -38.74734948
OS 44.73055062 -38.75659508
OS 44.73147518 -38.75751964
OS 44.7333243 -38.76121788
OS 44.73702254 -38.76676524
OS 44.74072078 -38.77508628
OS 44.74349446 -38.78525644
OS 44.7471927 -38.79635116
OS 44.74904182 -38.809295
OS 44.74996638 -38.82408796
OS 44.74996638 -38.82593708
OS 44.74996638 -38.83055988
OS 44.74904182 -38.83795636
OS 44.7471927 -38.84812652
OS 44.74441902 -38.85922124
OS 44.73979622 -38.87124052
OS 44.73424886 -38.88510892
OS 44.72685238 -38.89805276
OS 44.72592782 -38.89990188
OS 44.72222958 -38.90360012
OS 44.71760678 -38.91007204
OS 44.7102103 -38.91746852
OS 44.70004014 -38.92578956
OS 44.68894542 -38.93503516
OS 44.67600158 -38.9433562
OS 44.66028406 -38.95167724
OS 44.6593595 -38.95167724
OS 44.65843494 -38.9526018
OS 44.65288758 -38.95445092
OS 44.64364198 -38.9572246
OS 44.6316227 -38.96092284
OS 44.61682974 -38.96462108
OS 44.60018766 -38.96739476
OS 44.58262102 -38.96924388
OS 44.5622807 -38.97016844
OS 44.55395966 -38.97016844
OS 44.54748774 -38.96924388
OS 44.54009126 -38.96924388
OS 44.53084566 -38.96831932
OS 44.52160006 -38.96739476
OS 44.5114299 -38.96554564
OS 44.48924046 -38.96092284
OS 44.46612646 -38.95445092
OS 44.44393702 -38.94520532
OS 44.43376686 -38.93965796
OS 44.42452126 -38.93318604
OS 44.4235967 -38.93226148
OS 44.42267214 -38.93133692
OS 44.41712478 -38.92578956
OS 44.40880374 -38.91746852
OS 44.39955814 -38.90452468
OS 44.38938798 -38.88880716
OS 44.37921782 -38.87031596
OS 44.37089678 -38.84720196
OS 44.36442486 -38.82131428
OS 44.4420879 -38.809295
OS 44.4420879 -38.81021956
OS 44.4420879 -38.81114412
OS 44.44393702 -38.81669148
OS 44.44578614 -38.82593708
OS 44.44948438 -38.83610724
OS 44.45410718 -38.84720196
OS 44.45965454 -38.85922124
OS 44.46797558 -38.87124052
OS 44.47814574 -38.88141068
OS 44.47999486 -38.88233524
OS 44.4836931 -38.88510892
OS 44.49108958 -38.88880716
OS 44.50033518 -38.89342996
OS 44.51235446 -38.89805276
OS 44.52622286 -38.901751
OS 44.54286494 -38.90452468
OS 44.5622807 -38.90544924
OS 44.5715263 -38.90544924
OS 44.5807719 -38.90452468
OS 44.59279118 -38.90267556
OS 44.60573502 -38.89990188
OS 44.61960342 -38.89620364
OS 44.6316227 -38.89158084
OS 44.64271742 -38.88418436
OS 44.64364198 -38.8832598
OS 44.64734022 -38.88048612
OS 44.65103846 -38.87586332
OS 44.65658582 -38.8693914
OS 44.66120862 -38.86199492
OS 44.66583142 -38.85274932
OS 44.6686051 -38.84350372
OS 44.66952966 -38.832409
OS 44.66952966 -38.83148444
OS 44.66952966 -38.8277862
OS 44.6686051 -38.8231634
OS 44.66675598 -38.81669148
OS 44.6639823 -38.81021956
OS 44.6593595 -38.80374764
OS 44.65381214 -38.79635116
OS 44.6454911 -38.7908038
OS 44.64456654 -38.78987924
OS 44.64179286 -38.78895468
OS 44.63717006 -38.786181
OS 44.62977358 -38.78340732
OS 44.61867886 -38.77970908
OS 44.61220694 -38.7769354
OS 44.60481046 -38.77508628
OS 44.59648942 -38.7723126
OS 44.58724382 -38.76953892
OS 44.57707366 -38.76676524
OS 44.56505438 -38.76399156
OS 44.56412982 -38.76399156
OS 44.56135614 -38.763067
OS 44.55673334 -38.76214244
OS 44.55118598 -38.76029332
OS 44.5437895 -38.7584442
OS 44.53546846 -38.75567052
OS 44.51790182 -38.75104772
OS 44.4975615 -38.7445758
OS 44.47814574 -38.73902844
OS 44.45965454 -38.73255652
OS 44.4513335 -38.72885828
OS 44.44486158 -38.7260846
OS 44.44301246 -38.72516004
OS 44.43931422 -38.72331092
OS 44.43376686 -38.71961268
OS 44.42637038 -38.71498988
OS 44.41804934 -38.70851796
OS 44.4097283 -38.70112148
OS 44.40140726 -38.69280044
OS 44.39401078 -38.68263028
OS 44.39308622 -38.68170572
OS 44.3912371 -38.67800748
OS 44.38846342 -38.67153556
OS 44.38568974 -38.66413908
OS 44.38291606 -38.65489348
OS 44.38014238 -38.64379876
OS 44.37829326 -38.63270404
OS 44.3773687 -38.6197602
OS 44.3773687 -38.61791108
OS 44.3773687 -38.61421284
OS 44.37829326 -38.60866548
OS 44.37921782 -38.60034444
OS 44.38106694 -38.5920234
OS 44.38291606 -38.58185324
OS 44.3866143 -38.57260764
OS 44.3912371 -38.56243748
OS 44.39216166 -38.56151292
OS 44.39401078 -38.55781468
OS 44.39678446 -38.55319188
OS 44.40140726 -38.54671996
OS 44.40695462 -38.54024804
OS 44.41342654 -38.531927
OS 44.42082302 -38.52453052
OS 44.43006862 -38.5180586
OS 44.43099318 -38.51713404
OS 44.43376686 -38.51620948
OS 44.4374651 -38.5134358
OS 44.44301246 -38.51066212
OS 44.45040894 -38.50696388
OS 44.45872998 -38.50326564
OS 44.46890014 -38.4995674
OS 44.47999486 -38.49586916
OS 44.48184398 -38.4949446
OS 44.48554222 -38.49402004
OS 44.49201414 -38.49217092
OS 44.50033518 -38.4903218
OS 44.51050534 -38.48847268
OS 44.52160006 -38.48754812
OS 44.5345439 -38.485699
OS 44.55673334 -38.485699
OS 44.5669035 -38.48662356
OE
OB 33.15968222 -38.32112732 I
OS 33.17539974 -38.32205188
OS 33.19204182 -38.32297644
OS 33.20775934 -38.32482556
OS 33.22162774 -38.32667468
OS 33.22347686 -38.32667468
OS 33.22994878 -38.3285238
OS 33.23826982 -38.33037292
OS 33.24936454 -38.3331466
OS 33.26138382 -38.3377694
OS 33.27432766 -38.34331676
OS 33.28819606 -38.34978868
OS 33.30021534 -38.35718516
OS 33.30206446 -38.35810972
OS 33.3057627 -38.3608834
OS 33.31131006 -38.36643076
OS 33.31870654 -38.37290268
OS 33.32702758 -38.38122372
OS 33.33534862 -38.39231844
OS 33.34459422 -38.40433772
OS 33.3519907 -38.41820612
OS 33.35291526 -38.42005524
OS 33.35476438 -38.42467804
OS 33.35846262 -38.43299908
OS 33.36216086 -38.4440938
OS 33.36493454 -38.45703764
OS 33.36863278 -38.4718306
OS 33.3704819 -38.48847268
OS 33.37140646 -38.50603932
OS 33.37140646 -38.50696388
OS 33.37140646 -38.50973756
OS 33.37140646 -38.5134358
OS 33.3704819 -38.51990772
OS 33.36955734 -38.52637964
OS 33.36863278 -38.53470068
OS 33.36678366 -38.54394628
OS 33.36493454 -38.55411644
OS 33.35846262 -38.57538132
OS 33.35476438 -38.58647604
OS 33.34921702 -38.59849532
OS 33.3427451 -38.6105146
OS 33.33627318 -38.62160932
OS 33.32795214 -38.63270404
OS 33.31870654 -38.64379876
OS 33.31778198 -38.64472332
OS 33.31593286 -38.64657244
OS 33.31315918 -38.64934612
OS 33.30853638 -38.6521198
OS 33.30298902 -38.6567426
OS 33.29559254 -38.6613654
OS 33.28634694 -38.66691276
OS 33.27617678 -38.67153556
OS 33.2641575 -38.67708292
OS 33.2502891 -38.68263028
OS 33.23549614 -38.68725308
OS 33.2179295 -38.69095132
OS 33.1994383 -38.69464956
OS 33.17909798 -38.69742324
OS 33.15598398 -38.69927236
OS 33.13194542 -38.70019692
OS 32.9682983 -38.70019692
OS 32.9682983 -38.95999828
OS 32.88323878 -38.95999828
OS 32.88323878 -38.32020276
OS 33.14581382 -38.32020276
OS 33.15968222 -38.32112732
OE
OB 32.75195126 -38.98403684 I
OS 32.75195126 -38.9849614
OS 32.75195126 -38.98773508
OS 32.75195126 -38.99235788
OS 32.75195126 -38.99790524
OS 32.7510267 -39.00530172
OS 32.7510267 -39.0126982
OS 32.74917758 -39.0311894
OS 32.7464039 -39.05060516
OS 32.74270566 -39.07094548
OS 32.7371583 -39.08851212
OS 32.73346006 -39.09683316
OS 32.72976182 -39.10330508
OS 32.72976182 -39.10422964
OS 32.72883726 -39.1051542
OS 32.72421446 -39.109777
OS 32.71681798 -39.11717348
OS 32.70757238 -39.12549452
OS 32.69462854 -39.13381556
OS 32.67798646 -39.14028748
OS 32.6585707 -39.14583484
OS 32.64747598 -39.1467594
OS 32.6354567 -39.14768396
OS 32.62990934 -39.14768396
OS 32.62436198 -39.1467594
OS 32.61604094 -39.1467594
OS 32.60679534 -39.14583484
OS 32.59662518 -39.14398572
OS 32.57443574 -39.13843836
OS 32.5892287 -39.07187004
OS 32.59015326 -39.07187004
OS 32.59292694 -39.0727946
OS 32.59754974 -39.07371916
OS 32.60217254 -39.07464372
OS 32.61419182 -39.0774174
OS 32.61973918 -39.07834196
OS 32.62898478 -39.07834196
OS 32.63360758 -39.0774174
OS 32.63915494 -39.07649284
OS 32.6447023 -39.07464372
OS 32.65024966 -39.07094548
OS 32.65672158 -39.06724724
OS 32.66134438 -39.06169988
OS 32.66226894 -39.06077532
OS 32.6631935 -39.05800164
OS 32.66504262 -39.05337884
OS 32.6678163 -39.04598236
OS 32.66966542 -39.0358122
OS 32.67058998 -39.02841572
OS 32.67151454 -39.0219438
OS 32.6724391 -39.01362276
OS 32.6724391 -39.0034526
OS 32.67336366 -38.99328244
OS 32.67336366 -38.98218772
OS 32.67336366 -38.49586916
OS 32.75195126 -38.49586916
OS 32.75195126 -38.98403684
OE
OB 33.77174094 -38.3100326 I
OS 33.78006198 -38.31095716
OS 33.79023214 -38.31188172
OS 33.8004023 -38.31280628
OS 33.81242158 -38.31557996
OS 33.8373847 -38.32112732
OS 33.8651215 -38.32944836
OS 33.8789899 -38.33499572
OS 33.89193374 -38.34146764
OS 33.90487758 -38.34978868
OS 33.91782142 -38.35810972
OS 33.91874598 -38.35903428
OS 33.9205951 -38.35995884
OS 33.92429334 -38.36273252
OS 33.92891614 -38.36735532
OS 33.93353894 -38.37197812
OS 33.94001086 -38.37845004
OS 33.94648278 -38.38584652
OS 33.95387926 -38.393243
OS 33.96127574 -38.4024886
OS 33.96867222 -38.41358332
OS 33.97699326 -38.42467804
OS 33.98438974 -38.43669732
OS 33.99086166 -38.45056572
OS 33.99825814 -38.46443412
OS 34.0038055 -38.47922708
OS 34.00935286 -38.49586916
OS 33.92614246 -38.51528492
OS 33.92614246 -38.51436036
OS 33.9252179 -38.51251124
OS 33.92336878 -38.508813
OS 33.92151966 -38.5041902
OS 33.91967054 -38.49864284
OS 33.91689686 -38.49124636
OS 33.90950038 -38.4764534
OS 33.90025478 -38.45981132
OS 33.88916006 -38.44316924
OS 33.87529166 -38.42745172
OS 33.8604987 -38.41358332
OS 33.85864958 -38.4117342
OS 33.85310222 -38.40803596
OS 33.84385662 -38.40341316
OS 33.83183734 -38.39694124
OS 33.81611982 -38.39139388
OS 33.79855318 -38.38584652
OS 33.7772883 -38.38214828
OS 33.7541743 -38.38122372
OS 33.74677782 -38.38122372
OS 33.74215502 -38.38214828
OS 33.7356831 -38.38214828
OS 33.72828662 -38.38307284
OS 33.71071998 -38.38584652
OS 33.69130422 -38.38954476
OS 33.6709639 -38.39601668
OS 33.64969902 -38.40526228
OS 33.63028326 -38.41728156
OS 33.6293587 -38.41728156
OS 33.62843414 -38.41913068
OS 33.62196222 -38.42375348
OS 33.61364118 -38.43114996
OS 33.60347102 -38.44224468
OS 33.59145174 -38.45611308
OS 33.58035702 -38.4718306
OS 33.57018686 -38.49124636
OS 33.56094126 -38.51251124
OS 33.56094126 -38.5134358
OS 33.5600167 -38.51528492
OS 33.55909214 -38.5180586
OS 33.55816758 -38.5226814
OS 33.55631846 -38.52822876
OS 33.55446934 -38.53470068
OS 33.55169566 -38.5504182
OS 33.54799742 -38.5689094
OS 33.54429918 -38.58924972
OS 33.54245006 -38.61143916
OS 33.5415255 -38.63547772
OS 33.5415255 -38.63640228
OS 33.5415255 -38.63917596
OS 33.5415255 -38.64379876
OS 33.5415255 -38.64934612
OS 33.54245006 -38.65581804
OS 33.54245006 -38.66413908
OS 33.54337462 -38.67338468
OS 33.54429918 -38.68355484
OS 33.54707286 -38.70574428
OS 33.55169566 -38.72978284
OS 33.55724302 -38.7538214
OS 33.5646395 -38.77785996
OS 33.5646395 -38.77878452
OS 33.56556406 -38.78063364
OS 33.56741318 -38.78340732
OS 33.5692623 -38.78803012
OS 33.57480966 -38.79912484
OS 33.5831307 -38.81206868
OS 33.59330086 -38.82686164
OS 33.6062447 -38.84257916
OS 33.62103766 -38.85644756
OS 33.6386043 -38.8693914
OS 33.63952886 -38.8693914
OS 33.64137798 -38.87031596
OS 33.64415166 -38.87216508
OS 33.6478499 -38.8740142
OS 33.6524727 -38.87586332
OS 33.65802006 -38.878637
OS 33.6709639 -38.88418436
OS 33.68760598 -38.88973172
OS 33.70609718 -38.89435452
OS 33.7264375 -38.89805276
OS 33.74770238 -38.89897732
OS 33.7541743 -38.89897732
OS 33.75972166 -38.89805276
OS 33.76619358 -38.89805276
OS 33.7726655 -38.8971282
OS 33.78930758 -38.89342996
OS 33.80872334 -38.88880716
OS 33.8281391 -38.88141068
OS 33.84847942 -38.87124052
OS 33.85864958 -38.86569316
OS 33.86789518 -38.85829668
OS 33.86881974 -38.85737212
OS 33.8697443 -38.85644756
OS 33.87251798 -38.85367388
OS 33.87621622 -38.8509002
OS 33.87991446 -38.8462774
OS 33.88453726 -38.84073004
OS 33.89008462 -38.83518268
OS 33.89470742 -38.8277862
OS 33.90025478 -38.81946516
OS 33.9067267 -38.81021956
OS 33.91227406 -38.80097396
OS 33.91782142 -38.78987924
OS 33.92244422 -38.77785996
OS 33.92706702 -38.76491612
OS 33.93168982 -38.75104772
OS 33.93538806 -38.73625476
OS 34.02044758 -38.75751964
OS 34.02044758 -38.7584442
OS 34.01952302 -38.76214244
OS 34.0176739 -38.7676898
OS 34.01490022 -38.77508628
OS 34.01212654 -38.78340732
OS 34.0084283 -38.79357748
OS 34.0038055 -38.8046722
OS 33.99825814 -38.81669148
OS 33.9853143 -38.84257916
OS 33.96867222 -38.86846684
OS 33.95850206 -38.88141068
OS 33.9483319 -38.89435452
OS 33.93723718 -38.90544924
OS 33.92429334 -38.91654396
OS 33.92336878 -38.91746852
OS 33.92151966 -38.91931764
OS 33.91689686 -38.92116676
OS 33.91227406 -38.924865
OS 33.90487758 -38.9294878
OS 33.8974811 -38.9341106
OS 33.88731094 -38.9387334
OS 33.87714078 -38.9433562
OS 33.8651215 -38.94890356
OS 33.85217766 -38.95352636
OS 33.83830926 -38.95814916
OS 33.8235163 -38.96277196
OS 33.80779878 -38.9664702
OS 33.7911567 -38.96831932
OS 33.77359006 -38.97016844
OS 33.75509886 -38.971093
OS 33.7449287 -38.971093
OS 33.73753222 -38.97016844
OS 33.72921118 -38.97016844
OS 33.71904102 -38.96924388
OS 33.7079463 -38.96739476
OS 33.69500246 -38.96554564
OS 33.66819022 -38.96092284
OS 33.64045342 -38.95352636
OS 33.61271662 -38.9433562
OS 33.59977278 -38.93688428
OS 33.58682894 -38.9294878
OS 33.58590438 -38.92856324
OS 33.58405526 -38.92763868
OS 33.58035702 -38.924865
OS 33.57665878 -38.92116676
OS 33.57111142 -38.91746852
OS 33.5646395 -38.91192116
OS 33.55724302 -38.90544924
OS 33.54984654 -38.89805276
OS 33.54245006 -38.88973172
OS 33.53412902 -38.88141068
OS 33.51748694 -38.8601458
OS 33.50176942 -38.83518268
OS 33.48790102 -38.80744588
OS 33.48790102 -38.80652132
OS 33.4860519 -38.80374764
OS 33.48512734 -38.79912484
OS 33.48235366 -38.79357748
OS 33.48050454 -38.786181
OS 33.47773086 -38.7769354
OS 33.47403262 -38.76676524
OS 33.47125894 -38.75567052
OS 33.46848526 -38.74365124
OS 33.46478702 -38.72978284
OS 33.46016422 -38.70112148
OS 33.45646598 -38.66876188
OS 33.45461686 -38.63547772
OS 33.45461686 -38.63455316
OS 33.45461686 -38.63085492
OS 33.45461686 -38.62530756
OS 33.45554142 -38.61883564
OS 33.45554142 -38.60959004
OS 33.45646598 -38.60034444
OS 33.45739054 -38.58832516
OS 33.45923966 -38.57630588
OS 33.46386246 -38.54949364
OS 33.47033438 -38.51990772
OS 33.47957998 -38.4903218
OS 33.49252382 -38.46166044
OS 33.49344838 -38.46073588
OS 33.49437294 -38.4579622
OS 33.49622206 -38.45426396
OS 33.4999203 -38.44964116
OS 33.50361854 -38.44316924
OS 33.50824134 -38.43577276
OS 33.52026062 -38.41913068
OS 33.53597814 -38.40063948
OS 33.55446934 -38.38214828
OS 33.57573422 -38.36365708
OS 33.60069734 -38.34793956
OS 33.6016219 -38.347015
OS 33.60439558 -38.34609044
OS 33.60809382 -38.34424132
OS 33.61271662 -38.34146764
OS 33.6201131 -38.33869396
OS 33.62750958 -38.33592028
OS 33.63675518 -38.33222204
OS 33.64692534 -38.3285238
OS 33.65802006 -38.32482556
OS 33.67003934 -38.32112732
OS 33.69592702 -38.31557996
OS 33.72551294 -38.31095716
OS 33.75602342 -38.30910804
OS 33.76526902 -38.30910804
OS 33.77174094 -38.3100326
OE
OB 35.15858094 -39.1375138 I
OS 34.63805366 -39.1375138
OS 34.63805366 -39.08111564
OS 35.15858094 -39.08111564
OS 35.15858094 -39.1375138
OE
OB 34.37917686 -38.32112732 I
OS 34.38657334 -38.32112732
OS 34.40321542 -38.32297644
OS 34.42170662 -38.32482556
OS 34.44112238 -38.3285238
OS 34.46053814 -38.3331466
OS 34.47810478 -38.33961852
OS 34.47902934 -38.33961852
OS 34.4799539 -38.34054308
OS 34.48550126 -38.34331676
OS 34.4938223 -38.34793956
OS 34.5030679 -38.35441148
OS 34.51416262 -38.36273252
OS 34.5261819 -38.37290268
OS 34.53727662 -38.38584652
OS 34.54744678 -38.39971492
OS 34.54837134 -38.40156404
OS 34.55114502 -38.4071114
OS 34.55576782 -38.41450788
OS 34.56039062 -38.4256026
OS 34.56501342 -38.43854644
OS 34.56963622 -38.45241484
OS 34.5724099 -38.46813236
OS 34.57333446 -38.48384988
OS 34.57333446 -38.485699
OS 34.57333446 -38.4903218
OS 34.5724099 -38.49864284
OS 34.57056078 -38.508813
OS 34.5677871 -38.52083228
OS 34.5631643 -38.53377612
OS 34.55761694 -38.54671996
OS 34.55022046 -38.56058836
OS 34.5492959 -38.56243748
OS 34.54652222 -38.56613572
OS 34.54097486 -38.5735322
OS 34.53357838 -38.58092868
OS 34.52433278 -38.59017428
OS 34.51323806 -38.60034444
OS 34.49936966 -38.60959004
OS 34.48365214 -38.61883564
OS 34.4845767 -38.61883564
OS 34.48642582 -38.6197602
OS 34.4891995 -38.62068476
OS 34.49289774 -38.62253388
OS 34.50399246 -38.62623212
OS 34.5169363 -38.63270404
OS 34.5308047 -38.64102508
OS 34.54652222 -38.65119524
OS 34.56039062 -38.66321452
OS 34.57333446 -38.67800748
OS 34.57425902 -38.6798566
OS 34.57795726 -38.68540396
OS 34.58350462 -38.693725
OS 34.58905198 -38.70481972
OS 34.59459934 -38.71961268
OS 34.6001467 -38.7353302
OS 34.60384494 -38.7538214
OS 34.6047695 -38.77416172
OS 34.6047695 -38.77508628
OS 34.6047695 -38.77601084
OS 34.6047695 -38.7815582
OS 34.60384494 -38.7908038
OS 34.60199582 -38.80189852
OS 34.6001467 -38.81484236
OS 34.59644846 -38.82871076
OS 34.59182566 -38.84350372
OS 34.58535374 -38.85829668
OS 34.58442918 -38.8601458
OS 34.5816555 -38.8647686
OS 34.57795726 -38.87124052
OS 34.5724099 -38.88048612
OS 34.56501342 -38.88973172
OS 34.55761694 -38.89990188
OS 34.54837134 -38.91007204
OS 34.53820118 -38.91839308
OS 34.53727662 -38.91931764
OS 34.53357838 -38.92209132
OS 34.52710646 -38.92578956
OS 34.51878542 -38.9294878
OS 34.50861526 -38.93503516
OS 34.49659598 -38.94058252
OS 34.48365214 -38.94520532
OS 34.46793462 -38.94982812
OS 34.4660855 -38.94982812
OS 34.46053814 -38.95167724
OS 34.45129254 -38.9526018
OS 34.43927326 -38.95445092
OS 34.4244803 -38.95630004
OS 34.40691366 -38.95814916
OS 34.3874979 -38.95907372
OS 34.36530846 -38.95999828
OS 34.12122462 -38.95999828
OS 34.12122462 -38.32020276
OS 34.37270494 -38.32020276
OS 34.37917686 -38.32112732
OE
OB 31.74233174 -38.95999828 I
OS 31.65264942 -38.95999828
OS 31.65264942 -38.87031596
OS 31.74233174 -38.87031596
OS 31.74233174 -38.95999828
OE
OB 31.52968294 -38.42745172 I
OS 31.50841806 -38.54671996
OS 31.45941638 -38.54671996
OS 31.44000062 -38.42745172
OS 31.44000062 -38.32020276
OS 31.52968294 -38.32020276
OS 31.52968294 -38.42745172
OE
OB 32.0992119 -38.48662356 I
OS 32.10568382 -38.48754812
OS 32.11955222 -38.48939724
OS 32.1361943 -38.49309548
OS 32.15376094 -38.49864284
OS 32.17132758 -38.50696388
OS 32.18889422 -38.51713404
OS 32.18981878 -38.51713404
OS 32.19074334 -38.51898316
OS 32.1962907 -38.5226814
OS 32.20461174 -38.53007788
OS 32.2147819 -38.53932348
OS 32.22587662 -38.55134276
OS 32.23697134 -38.56613572
OS 32.24806606 -38.58370236
OS 32.25731166 -38.60311812
OS 32.25731166 -38.60404268
OS 32.25823622 -38.6058918
OS 32.25916078 -38.60866548
OS 32.2610099 -38.61236372
OS 32.26285902 -38.61791108
OS 32.26470814 -38.624383
OS 32.26933094 -38.63917596
OS 32.27395374 -38.65766716
OS 32.27765198 -38.67800748
OS 32.28042566 -38.70112148
OS 32.28135022 -38.72516004
OS 32.28135022 -38.7260846
OS 32.28135022 -38.72793372
OS 32.28135022 -38.73163196
OS 32.28135022 -38.73717932
OS 32.28042566 -38.74365124
OS 32.28042566 -38.75104772
OS 32.27857654 -38.7676898
OS 32.2748783 -38.78803012
OS 32.2702555 -38.809295
OS 32.26378358 -38.83148444
OS 32.25546254 -38.85367388
OS 32.25546254 -38.85459844
OS 32.25453798 -38.85644756
OS 32.25268886 -38.85922124
OS 32.25083974 -38.86291948
OS 32.24436782 -38.87308964
OS 32.23604678 -38.88603348
OS 32.22587662 -38.89990188
OS 32.21293278 -38.91377028
OS 32.19813982 -38.92763868
OS 32.18057318 -38.94058252
OS 32.17964862 -38.94058252
OS 32.17872406 -38.94150708
OS 32.17595038 -38.9433562
OS 32.17225214 -38.94520532
OS 32.16300654 -38.94982812
OS 32.1500627 -38.95537548
OS 32.13434518 -38.96092284
OS 32.1177031 -38.96554564
OS 32.09828734 -38.96924388
OS 32.07887158 -38.97016844
OS 32.07239966 -38.97016844
OS 32.06500318 -38.96924388
OS 32.05575758 -38.96831932
OS 32.04466286 -38.9664702
OS 32.03264358 -38.96369652
OS 32.0206243 -38.95999828
OS 32.00860502 -38.95445092
OS 32.00768046 -38.95352636
OS 32.00305766 -38.95167724
OS 31.9975103 -38.947979
OS 31.99011382 -38.94243164
OS 31.98271734 -38.93688428
OS 31.97347174 -38.9294878
OS 31.9651507 -38.92116676
OS 31.95775422 -38.91192116
OS 31.95775422 -39.1375138
OS 31.87916662 -39.1375138
OS 31.87916662 -38.49586916
OS 31.95035774 -38.49586916
OS 31.95035774 -38.55689012
OS 31.9512823 -38.555041
OS 31.95498054 -38.55134276
OS 31.95960334 -38.54487084
OS 31.96699982 -38.53747436
OS 31.97532086 -38.52822876
OS 31.98456646 -38.51990772
OS 31.99566118 -38.51158668
OS 32.0067559 -38.5041902
OS 32.00860502 -38.50326564
OS 32.01230326 -38.50141652
OS 32.01969974 -38.49864284
OS 32.02894534 -38.4949446
OS 32.04004006 -38.49124636
OS 32.0529839 -38.48847268
OS 32.06777686 -38.48662356
OS 32.08441894 -38.485699
OS 32.0945891 -38.485699
OS 32.0992119 -38.48662356
OE
OB 32.5614919 -38.48662356 I
OS 32.57166206 -38.48847268
OS 32.58368134 -38.49217092
OS 32.59662518 -38.49679372
OS 32.61141814 -38.50326564
OS 32.62713566 -38.51158668
OS 32.5984743 -38.58370236
OS 32.59754974 -38.5827778
OS 32.5938515 -38.58092868
OS 32.58830414 -38.578155
OS 32.58090766 -38.57538132
OS 32.57258662 -38.57260764
OS 32.56241646 -38.56983396
OS 32.5522463 -38.56798484
OS 32.54207614 -38.56706028
OS 32.53745334 -38.56706028
OS 32.53283054 -38.56798484
OS 32.52635862 -38.5689094
OS 32.5198867 -38.57075852
OS 32.51156566 -38.5735322
OS 32.50324462 -38.57723044
OS 32.49584814 -38.5827778
OS 32.49492358 -38.58370236
OS 32.4921499 -38.58555148
OS 32.48937622 -38.58924972
OS 32.48475342 -38.59387252
OS 32.48013062 -38.60034444
OS 32.47550782 -38.60774092
OS 32.47088502 -38.61606196
OS 32.46718678 -38.62623212
OS 32.46626222 -38.62808124
OS 32.46533766 -38.6336286
OS 32.46348854 -38.64194964
OS 32.46071486 -38.65304436
OS 32.45794118 -38.66691276
OS 32.45609206 -38.68263028
OS 32.4551675 -38.69927236
OS 32.45424294 -38.71776356
OS 32.45424294 -38.95999828
OS 32.37565534 -38.95999828
OS 32.37565534 -38.49586916
OS 32.44684646 -38.49586916
OS 32.44684646 -38.56613572
OS 32.44777102 -38.56521116
OS 32.45146926 -38.55873924
OS 32.45609206 -38.5504182
OS 32.46348854 -38.54024804
OS 32.47088502 -38.53007788
OS 32.47920606 -38.51898316
OS 32.4875271 -38.50973756
OS 32.49584814 -38.50234108
OS 32.4967727 -38.50141652
OS 32.49954638 -38.4995674
OS 32.50509374 -38.49679372
OS 32.5106411 -38.49402004
OS 32.51803758 -38.49124636
OS 32.52728318 -38.48847268
OS 32.53652878 -38.48662356
OS 32.54669894 -38.485699
OS 32.55317086 -38.485699
OS 32.5614919 -38.48662356
OE
OB 32.75195126 -38.4117342 I
OS 32.67336366 -38.4117342
OS 32.67336366 -38.32020276
OS 32.75195126 -38.32020276
OS 32.75195126 -38.4117342
OE
OB 36.56668582 -38.95999828 I
OS 36.47885262 -38.95999828
OS 36.1441619 -38.4579622
OS 36.1441619 -38.95999828
OS 36.06280062 -38.95999828
OS 36.06280062 -38.32020276
OS 36.14970926 -38.32020276
OS 36.48532454 -38.8231634
OS 36.48532454 -38.32020276
OS 36.56668582 -38.32020276
OS 36.56668582 -38.95999828
OE
OB 35.74382742 -38.32112732 I
OS 35.75954494 -38.32205188
OS 35.77618702 -38.32297644
OS 35.79190454 -38.32482556
OS 35.80577294 -38.32667468
OS 35.80762206 -38.32667468
OS 35.81409398 -38.3285238
OS 35.82241502 -38.33037292
OS 35.83350974 -38.3331466
OS 35.84552902 -38.3377694
OS 35.85847286 -38.34331676
OS 35.87234126 -38.34978868
OS 35.88436054 -38.35718516
OS 35.88620966 -38.35810972
OS 35.8899079 -38.3608834
OS 35.89545526 -38.36643076
OS 35.90285174 -38.37290268
OS 35.91117278 -38.38122372
OS 35.91949382 -38.39231844
OS 35.92873942 -38.40433772
OS 35.9361359 -38.41820612
OS 35.93706046 -38.42005524
OS 35.93890958 -38.42467804
OS 35.94260782 -38.43299908
OS 35.94630606 -38.4440938
OS 35.94907974 -38.45703764
OS 35.95277798 -38.4718306
OS 35.9546271 -38.48847268
OS 35.95555166 -38.50603932
OS 35.95555166 -38.50696388
OS 35.95555166 -38.50973756
OS 35.95555166 -38.5134358
OS 35.9546271 -38.51990772
OS 35.95370254 -38.52637964
OS 35.95277798 -38.53470068
OS 35.95092886 -38.54394628
OS 35.94907974 -38.55411644
OS 35.94260782 -38.57538132
OS 35.93890958 -38.58647604
OS 35.93336222 -38.59849532
OS 35.9268903 -38.6105146
OS 35.92041838 -38.62160932
OS 35.91209734 -38.63270404
OS 35.90285174 -38.64379876
OS 35.90192718 -38.64472332
OS 35.90007806 -38.64657244
OS 35.89730438 -38.64934612
OS 35.89268158 -38.6521198
OS 35.88713422 -38.6567426
OS 35.87973774 -38.6613654
OS 35.87049214 -38.66691276
OS 35.86032198 -38.67153556
OS 35.8483027 -38.67708292
OS 35.8344343 -38.68263028
OS 35.81964134 -38.68725308
OS 35.8020747 -38.69095132
OS 35.7835835 -38.69464956
OS 35.76324318 -38.69742324
OS 35.74012918 -38.69927236
OS 35.71609062 -38.70019692
OS 35.5524435 -38.70019692
OS 35.5524435 -38.95999828
OS 35.46738398 -38.95999828
OS 35.46738398 -38.32020276
OS 35.72995902 -38.32020276
OS 35.74382742 -38.32112732
OE
OB 36.76916446 -38.42745172 I
OS 36.74789958 -38.54671996
OS 36.6988979 -38.54671996
OS 36.67948214 -38.42745172
OS 36.67948214 -38.32020276
OS 36.76916446 -38.32020276
OS 36.76916446 -38.42745172
OE
OB 38.2382903 -38.39601668 I
OS 37.86014526 -38.39601668
OS 37.86014526 -38.59109884
OS 38.21425174 -38.59109884
OS 38.21425174 -38.66691276
OS 37.86014526 -38.66691276
OS 37.86014526 -38.88418436
OS 38.25308326 -38.88418436
OS 38.25308326 -38.95999828
OS 37.77508574 -38.95999828
OS 37.77508574 -38.32020276
OS 38.2382903 -38.32020276
OS 38.2382903 -38.39601668
OE
OB 37.4339231 -38.32112732 I
OS 37.44224414 -38.32112732
OS 37.4616599 -38.32205188
OS 37.48200022 -38.32482556
OS 37.50418966 -38.32759924
OS 37.52452998 -38.33222204
OS 37.53470014 -38.33499572
OS 37.54302118 -38.3377694
OS 37.54394574 -38.3377694
OS 37.5448703 -38.33869396
OS 37.55041766 -38.34146764
OS 37.5587387 -38.34516588
OS 37.56890886 -38.3516378
OS 37.58000358 -38.35995884
OS 37.59202286 -38.37105356
OS 37.60311758 -38.3839974
OS 37.6142123 -38.39879036
OS 37.6142123 -38.39971492
OS 37.61513686 -38.40063948
OS 37.6188351 -38.40618684
OS 37.62253334 -38.41543244
OS 37.6280807 -38.42745172
OS 37.6327035 -38.44132012
OS 37.6373263 -38.4579622
OS 37.64009998 -38.47552884
OS 37.64102454 -38.4949446
OS 37.64102454 -38.49586916
OS 37.64102454 -38.49771828
OS 37.64102454 -38.50141652
OS 37.64009998 -38.50603932
OS 37.64009998 -38.51251124
OS 37.63917542 -38.51898316
OS 37.63547718 -38.53470068
OS 37.62992982 -38.55319188
OS 37.62253334 -38.57260764
OS 37.61143862 -38.5920234
OS 37.60404214 -38.601269
OS 37.59664566 -38.6105146
OS 37.5957211 -38.61143916
OS 37.59479654 -38.61236372
OS 37.59202286 -38.6151374
OS 37.58832462 -38.61791108
OS 37.58370182 -38.62160932
OS 37.57815446 -38.62530756
OS 37.57075798 -38.62993036
OS 37.5633615 -38.63547772
OS 37.5541159 -38.64010052
OS 37.54394574 -38.64472332
OS 37.53285102 -38.65027068
OS 37.52083174 -38.65489348
OS 37.50696334 -38.65859172
OS 37.49309494 -38.66321452
OS 37.47737742 -38.6659882
OS 37.46073534 -38.66876188
OS 37.46258446 -38.66968644
OS 37.4662827 -38.67153556
OS 37.47183006 -38.6752338
OS 37.47922654 -38.67893204
OS 37.49586862 -38.6891022
OS 37.50418966 -38.69557412
OS 37.51158614 -38.70112148
OS 37.51343526 -38.7029706
OS 37.51805806 -38.7075934
OS 37.52545454 -38.71498988
OS 37.53470014 -38.72423548
OS 37.5448703 -38.73717932
OS 37.55688958 -38.75104772
OS 37.56890886 -38.7676898
OS 37.5818527 -38.786181
OS 37.69187534 -38.95999828
OS 37.5864755 -38.95999828
OS 37.50234054 -38.82686164
OS 37.50234054 -38.82593708
OS 37.50049142 -38.82408796
OS 37.4986423 -38.82131428
OS 37.49586862 -38.81761604
OS 37.4893967 -38.80744588
OS 37.48107566 -38.79450204
OS 37.4709055 -38.78063364
OS 37.46073534 -38.76584068
OS 37.45056518 -38.75197228
OS 37.44131958 -38.73902844
OS 37.44039502 -38.73810388
OS 37.43762134 -38.73440564
OS 37.43299854 -38.72885828
OS 37.42652662 -38.72238636
OS 37.41265822 -38.70851796
OS 37.40526174 -38.70204604
OS 37.39786526 -38.69649868
OS 37.3969407 -38.69557412
OS 37.39509158 -38.69464956
OS 37.39139334 -38.69280044
OS 37.38584598 -38.69002676
OS 37.38029862 -38.68725308
OS 37.3738267 -38.6844794
OS 37.35903374 -38.6798566
OS 37.35810918 -38.6798566
OS 37.35626006 -38.67893204
OS 37.35256182 -38.67893204
OS 37.34793902 -38.67800748
OS 37.3414671 -38.67708292
OS 37.33407062 -38.67708292
OS 37.32390046 -38.67615836
OS 37.21480238 -38.67615836
OS 37.21480238 -38.95999828
OS 37.12974286 -38.95999828
OS 37.12974286 -38.32020276
OS 37.42652662 -38.32020276
OS 37.4339231 -38.32112732
OE
OB 35.31760526 -38.95999828 I
OS 35.23254574 -38.95999828
OS 35.23254574 -38.32020276
OS 35.31760526 -38.32020276
OS 35.31760526 -38.95999828
OE
OB 42.12051774 -38.66413908 H
OS 41.95224782 -38.66413908
OS 41.95224782 -38.88418436
OS 42.13438614 -38.88418436
OS 42.1538019 -38.8832598
OS 42.16212294 -38.88233524
OS 42.16951942 -38.88141068
OS 42.17044398 -38.88141068
OS 42.17414222 -38.88048612
OS 42.17968958 -38.87956156
OS 42.1861615 -38.87771244
OS 42.20187902 -38.87216508
OS 42.21759654 -38.8647686
OS 42.2185211 -38.86384404
OS 42.22129478 -38.86199492
OS 42.22499302 -38.85922124
OS 42.22961582 -38.855523
OS 42.23423862 -38.84997564
OS 42.24071054 -38.84442828
OS 42.24533334 -38.8370318
OS 42.2508807 -38.82871076
OS 42.25180526 -38.8277862
OS 42.25272982 -38.82501252
OS 42.25457894 -38.81946516
OS 42.25735262 -38.81299324
OS 42.2601263 -38.80559676
OS 42.26197542 -38.79635116
OS 42.26289998 -38.78525644
OS 42.26382454 -38.77416172
OS 42.26382454 -38.7723126
OS 42.26382454 -38.76861436
OS 42.26289998 -38.76121788
OS 42.26105086 -38.75289684
OS 42.25920174 -38.74365124
OS 42.2555035 -38.73348108
OS 42.2508807 -38.72331092
OS 42.24440878 -38.71314076
OS 42.24348422 -38.7122162
OS 42.24071054 -38.70851796
OS 42.2370123 -38.70389516
OS 42.23146494 -38.6983478
OS 42.22406846 -38.69187588
OS 42.21482286 -38.68540396
OS 42.2046527 -38.6798566
OS 42.19263342 -38.6752338
OS 42.1907843 -38.67430924
OS 42.18708606 -38.67338468
OS 42.17876502 -38.67153556
OS 42.16859486 -38.66968644
OS 42.15565102 -38.66783732
OS 42.1399335 -38.6659882
OS 42.12051774 -38.66413908
OE
OB 45.22981302 -38.5504182 H
OS 45.22426566 -38.5504182
OS 45.21964286 -38.55134276
OS 45.2094727 -38.55226732
OS 45.1956043 -38.55596556
OS 45.17988678 -38.56151292
OS 45.1632447 -38.5689094
OS 45.14752718 -38.58000412
OS 45.13920614 -38.5874006
OS 45.13180966 -38.59479708
OS 45.13180966 -38.59572164
OS 45.12996054 -38.5966462
OS 45.12811142 -38.59941988
OS 45.12533774 -38.60311812
OS 45.12256406 -38.60774092
OS 45.11979038 -38.61328828
OS 45.11609214 -38.62068476
OS 45.1123939 -38.62808124
OS 45.10869566 -38.63732684
OS 45.10499742 -38.64657244
OS 45.10222374 -38.65766716
OS 45.09945006 -38.66968644
OS 45.09667638 -38.68263028
OS 45.09482726 -38.69649868
OS 45.0939027 -38.7122162
OS 45.09297814 -38.72793372
OS 45.09297814 -38.72885828
OS 45.09297814 -38.73163196
OS 45.09297814 -38.73625476
OS 45.0939027 -38.74272668
OS 45.0939027 -38.75012316
OS 45.09482726 -38.7584442
OS 45.09760094 -38.77785996
OS 45.10222374 -38.8000494
OS 45.10962022 -38.82223884
OS 45.11886582 -38.84350372
OS 45.12533774 -38.85274932
OS 45.13180966 -38.86199492
OS 45.13273422 -38.86199492
OS 45.13365878 -38.86384404
OS 45.13920614 -38.86846684
OS 45.14752718 -38.87586332
OS 45.1586219 -38.8832598
OS 45.1724903 -38.89158084
OS 45.18913238 -38.89897732
OS 45.20854814 -38.90360012
OS 45.2187183 -38.90452468
OS 45.22981302 -38.90544924
OS 45.23536038 -38.90544924
OS 45.23998318 -38.90452468
OS 45.25015334 -38.90267556
OS 45.26402174 -38.89990188
OS 45.2788147 -38.89435452
OS 45.29545678 -38.88695804
OS 45.3111743 -38.87586332
OS 45.31949534 -38.86846684
OS 45.32689182 -38.86107036
OS 45.32781638 -38.8601458
OS 45.32874094 -38.85922124
OS 45.33059006 -38.85644756
OS 45.33336374 -38.85274932
OS 45.33613742 -38.84812652
OS 45.33983566 -38.84257916
OS 45.3435339 -38.83518268
OS 45.34723214 -38.8277862
OS 45.35093038 -38.8185406
OS 45.35370406 -38.80837044
OS 45.3574023 -38.79727572
OS 45.36017598 -38.78525644
OS 45.36294966 -38.77138804
OS 45.36479878 -38.75751964
OS 45.3666479 -38.74180212
OS 45.3666479 -38.72516004
OS 45.3666479 -38.72423548
OS 45.3666479 -38.7214618
OS 45.3666479 -38.716839
OS 45.36572334 -38.71129164
OS 45.36572334 -38.70389516
OS 45.36479878 -38.69557412
OS 45.3620251 -38.67615836
OS 45.3574023 -38.65581804
OS 45.35000582 -38.6336286
OS 45.33983566 -38.61328828
OS 45.3342883 -38.60311812
OS 45.32689182 -38.59479708
OS 45.32689182 -38.59387252
OS 45.3250427 -38.59294796
OS 45.31949534 -38.5874006
OS 45.3111743 -38.58092868
OS 45.30007958 -38.57260764
OS 45.28621118 -38.5642866
OS 45.2695691 -38.55689012
OS 45.2510779 -38.55226732
OS 45.24090774 -38.55134276
OS 45.22981302 -38.5504182
OE
OB 32.07702246 -38.54764452 H
OS 32.07239966 -38.54764452
OS 32.06870142 -38.54856908
OS 32.05945582 -38.5504182
OS 32.04743654 -38.55319188
OS 32.03356814 -38.55873924
OS 32.01877518 -38.56706028
OS 32.01045414 -38.57260764
OS 32.00305766 -38.57907956
OS 31.99566118 -38.58647604
OS 31.9882647 -38.59479708
OS 31.9882647 -38.59572164
OS 31.98641558 -38.5966462
OS 31.98456646 -38.59941988
OS 31.98271734 -38.60311812
OS 31.97994366 -38.60866548
OS 31.97624542 -38.61421284
OS 31.97254718 -38.62160932
OS 31.9697735 -38.6290058
OS 31.96607526 -38.6382514
OS 31.96237702 -38.64842156
OS 31.95960334 -38.65951628
OS 31.9559051 -38.67153556
OS 31.95405598 -38.68540396
OS 31.95220686 -38.69927236
OS 31.95035774 -38.71406532
OS 31.95035774 -38.7307074
OS 31.95035774 -38.73163196
OS 31.95035774 -38.73440564
OS 31.95035774 -38.73902844
OS 31.9512823 -38.74550036
OS 31.9512823 -38.75289684
OS 31.95220686 -38.76121788
OS 31.95498054 -38.78063364
OS 31.95960334 -38.80282308
OS 31.9651507 -38.82408796
OS 31.9743963 -38.84535284
OS 31.97994366 -38.85459844
OS 31.98641558 -38.86291948
OS 31.9882647 -38.8647686
OS 31.9928875 -38.8693914
OS 32.00028398 -38.87678788
OS 32.01045414 -38.88418436
OS 32.02339798 -38.89158084
OS 32.03819094 -38.89897732
OS 32.05483302 -38.90360012
OS 32.06407862 -38.90452468
OS 32.07332422 -38.90544924
OS 32.07887158 -38.90544924
OS 32.08256982 -38.90452468
OS 32.09181542 -38.90267556
OS 32.10475926 -38.89990188
OS 32.11862766 -38.89435452
OS 32.13342062 -38.88695804
OS 32.14821358 -38.87586332
OS 32.15561006 -38.8693914
OS 32.16300654 -38.86199492
OS 32.16300654 -38.86107036
OS 32.16485566 -38.8601458
OS 32.16670478 -38.85737212
OS 32.1685539 -38.85367388
OS 32.17225214 -38.84905108
OS 32.17502582 -38.84257916
OS 32.17872406 -38.83610724
OS 32.1824223 -38.8277862
OS 32.18519598 -38.81946516
OS 32.18889422 -38.80837044
OS 32.19259246 -38.79727572
OS 32.19536614 -38.78525644
OS 32.19721526 -38.77138804
OS 32.19906438 -38.75659508
OS 32.2009135 -38.74087756
OS 32.2009135 -38.72423548
OS 32.2009135 -38.72331092
OS 32.2009135 -38.72053724
OS 32.2009135 -38.71591444
OS 32.19998894 -38.70944252
OS 32.19998894 -38.70204604
OS 32.19906438 -38.693725
OS 32.1962907 -38.67430924
OS 32.1916679 -38.65304436
OS 32.18519598 -38.63177948
OS 32.17595038 -38.6105146
OS 32.17040302 -38.60034444
OS 32.1639311 -38.5920234
OS 32.1639311 -38.59109884
OS 32.16208198 -38.59017428
OS 32.15745918 -38.58462692
OS 32.1500627 -38.578155
OS 32.13989254 -38.56983396
OS 32.1269487 -38.56151292
OS 32.11215574 -38.55411644
OS 32.09551366 -38.54949364
OS 32.08626806 -38.54856908
OS 32.07702246 -38.54764452
OE
OB 42.10387566 -38.39601668 H
OS 41.95224782 -38.39601668
OS 41.95224782 -38.58832516
OS 42.10942302 -38.58832516
OS 42.1214423 -38.5874006
OS 42.13438614 -38.58647604
OS 42.14732998 -38.58555148
OS 42.16027382 -38.58370236
OS 42.17044398 -38.58185324
OS 42.1722931 -38.58092868
OS 42.17599134 -38.58000412
OS 42.1815387 -38.57723044
OS 42.18893518 -38.5735322
OS 42.19633166 -38.56983396
OS 42.2046527 -38.5642866
OS 42.21297374 -38.55689012
OS 42.21944566 -38.54949364
OS 42.22037022 -38.54856908
OS 42.22221934 -38.5457954
OS 42.22499302 -38.54024804
OS 42.2277667 -38.53377612
OS 42.23054038 -38.52637964
OS 42.23331406 -38.51713404
OS 42.23516318 -38.50603932
OS 42.23608774 -38.49402004
OS 42.23608774 -38.49217092
OS 42.23608774 -38.48847268
OS 42.23516318 -38.48292532
OS 42.23423862 -38.47552884
OS 42.2323895 -38.46628324
OS 42.22961582 -38.45703764
OS 42.22591758 -38.44779204
OS 42.22037022 -38.43854644
OS 42.21944566 -38.43762188
OS 42.21759654 -38.4348482
OS 42.2138983 -38.4302254
OS 42.2092755 -38.4256026
OS 42.20280358 -38.42005524
OS 42.1954071 -38.41450788
OS 42.1861615 -38.40896052
OS 42.17599134 -38.40526228
OS 42.17506678 -38.40526228
OS 42.17044398 -38.40341316
OS 42.16397206 -38.4024886
OS 42.1538019 -38.40063948
OS 42.1399335 -38.39879036
OS 42.12421598 -38.3978658
OS 42.10387566 -38.39601668
OE
OB 37.41635646 -38.39139388 H
OS 37.21480238 -38.39139388
OS 37.21480238 -38.60311812
OS 37.40526174 -38.60311812
OS 37.41635646 -38.60219356
OS 37.4293003 -38.601269
OS 37.44409326 -38.60034444
OS 37.45888622 -38.59849532
OS 37.47367918 -38.59572164
OS 37.48662302 -38.5920234
OS 37.48847214 -38.59109884
OS 37.49217038 -38.58924972
OS 37.49771774 -38.58647604
OS 37.50511422 -38.5827778
OS 37.51343526 -38.57723044
OS 37.5217563 -38.57075852
OS 37.53007734 -38.56243748
OS 37.53654926 -38.55319188
OS 37.53747382 -38.55226732
OS 37.53932294 -38.54856908
OS 37.54209662 -38.54302172
OS 37.54579486 -38.53562524
OS 37.54856854 -38.5273042
OS 37.55134222 -38.5180586
OS 37.55319134 -38.50696388
OS 37.5541159 -38.49586916
OS 37.5541159 -38.4949446
OS 37.5541159 -38.49402004
OS 37.55319134 -38.48847268
OS 37.55226678 -38.48015164
OS 37.55041766 -38.46905692
OS 37.54579486 -38.4579622
OS 37.5402475 -38.44501836
OS 37.53192646 -38.43299908
OS 37.52083174 -38.4209798
OS 37.51898262 -38.42005524
OS 37.51435982 -38.416357
OS 37.50696334 -38.4117342
OS 37.49494406 -38.40618684
OS 37.48107566 -38.40063948
OS 37.46258446 -38.39601668
OS 37.44131958 -38.39231844
OS 37.41635646 -38.39139388
OE
OB 39.82298614 -38.54764452 H
OS 39.81836334 -38.54764452
OS 39.8146651 -38.54856908
OS 39.8054195 -38.5504182
OS 39.79340022 -38.55319188
OS 39.77953182 -38.55873924
OS 39.76473886 -38.56706028
OS 39.75641782 -38.57260764
OS 39.74902134 -38.57907956
OS 39.74162486 -38.58647604
OS 39.73422838 -38.59479708
OS 39.73422838 -38.59572164
OS 39.73237926 -38.5966462
OS 39.73053014 -38.59941988
OS 39.72868102 -38.60311812
OS 39.72590734 -38.60866548
OS 39.7222091 -38.61421284
OS 39.71851086 -38.62160932
OS 39.71573718 -38.6290058
OS 39.71203894 -38.6382514
OS 39.7083407 -38.64842156
OS 39.70556702 -38.65951628
OS 39.70186878 -38.67153556
OS 39.70001966 -38.68540396
OS 39.69817054 -38.69927236
OS 39.69632142 -38.71406532
OS 39.69632142 -38.7307074
OS 39.69632142 -38.73163196
OS 39.69632142 -38.73440564
OS 39.69632142 -38.73902844
OS 39.69724598 -38.74550036
OS 39.69724598 -38.75289684
OS 39.69817054 -38.76121788
OS 39.70094422 -38.78063364
OS 39.70556702 -38.80282308
OS 39.71111438 -38.82408796
OS 39.72035998 -38.84535284
OS 39.72590734 -38.85459844
OS 39.73237926 -38.86291948
OS 39.73422838 -38.8647686
OS 39.73885118 -38.8693914
OS 39.74624766 -38.87678788
OS 39.75641782 -38.88418436
OS 39.76936166 -38.89158084
OS 39.78415462 -38.89897732
OS 39.8007967 -38.90360012
OS 39.8100423 -38.90452468
OS 39.8192879 -38.90544924
OS 39.82483526 -38.90544924
OS 39.8285335 -38.90452468
OS 39.8377791 -38.90267556
OS 39.85072294 -38.89990188
OS 39.86459134 -38.89435452
OS 39.8793843 -38.88695804
OS 39.89417726 -38.87586332
OS 39.90157374 -38.8693914
OS 39.90897022 -38.86199492
OS 39.90897022 -38.86107036
OS 39.91081934 -38.8601458
OS 39.91266846 -38.85737212
OS 39.91451758 -38.85367388
OS 39.91821582 -38.84905108
OS 39.9209895 -38.84257916
OS 39.92468774 -38.83610724
OS 39.92838598 -38.8277862
OS 39.93115966 -38.81946516
OS 39.9348579 -38.80837044
OS 39.93855614 -38.79727572
OS 39.94132982 -38.78525644
OS 39.94317894 -38.77138804
OS 39.94502806 -38.75659508
OS 39.94687718 -38.74087756
OS 39.94687718 -38.72423548
OS 39.94687718 -38.72331092
OS 39.94687718 -38.72053724
OS 39.94687718 -38.71591444
OS 39.94595262 -38.70944252
OS 39.94595262 -38.70204604
OS 39.94502806 -38.693725
OS 39.94225438 -38.67430924
OS 39.93763158 -38.65304436
OS 39.93115966 -38.63177948
OS 39.92191406 -38.6105146
OS 39.9163667 -38.60034444
OS 39.90989478 -38.5920234
OS 39.90989478 -38.59109884
OS 39.90804566 -38.59017428
OS 39.90342286 -38.58462692
OS 39.89602638 -38.578155
OS 39.88585622 -38.56983396
OS 39.87291238 -38.56151292
OS 39.85811942 -38.55411644
OS 39.84147734 -38.54949364
OS 39.83223174 -38.54856908
OS 39.82298614 -38.54764452
OE
OB 35.73550638 -38.39601668 H
OS 35.5524435 -38.39601668
OS 35.5524435 -38.624383
OS 35.72441166 -38.624383
OS 35.73088358 -38.62345844
OS 35.7373555 -38.62345844
OS 35.74475198 -38.62253388
OS 35.76231862 -38.62068476
OS 35.78173438 -38.61698652
OS 35.80115014 -38.61143916
OS 35.81871678 -38.60404268
OS 35.82703782 -38.59941988
OS 35.83350974 -38.59387252
OS 35.83535886 -38.5920234
OS 35.8390571 -38.58832516
OS 35.84460446 -38.58092868
OS 35.85107638 -38.57168308
OS 35.8575483 -38.5596638
OS 35.86309566 -38.54487084
OS 35.8667939 -38.52822876
OS 35.86864302 -38.508813
OS 35.86864302 -38.50788844
OS 35.86864302 -38.50696388
OS 35.86864302 -38.50234108
OS 35.86771846 -38.49402004
OS 35.86586934 -38.48477444
OS 35.86402022 -38.47460428
OS 35.86032198 -38.462585
OS 35.85477462 -38.45149028
OS 35.8483027 -38.44039556
OS 35.84737814 -38.439471
OS 35.84460446 -38.43577276
OS 35.83998166 -38.43114996
OS 35.8344343 -38.42467804
OS 35.82611326 -38.41820612
OS 35.81686766 -38.41265876
OS 35.8066975 -38.4071114
OS 35.79467822 -38.4024886
OS 35.79375366 -38.4024886
OS 35.79005542 -38.40156404
OS 35.78450806 -38.40063948
OS 35.77711158 -38.39879036
OS 35.76601686 -38.3978658
OS 35.75214846 -38.39694124
OS 35.73550638 -38.39601668
OE
OB 43.44263854 -38.5504182 H
OS 43.43709118 -38.5504182
OS 43.43339294 -38.55134276
OS 43.42322278 -38.55226732
OS 43.4112035 -38.555041
OS 43.39641054 -38.5596638
OS 43.38069302 -38.56613572
OS 43.36590006 -38.57538132
OS 43.3511071 -38.5874006
OS 43.34925798 -38.58924972
OS 43.34555974 -38.59387252
OS 43.33908782 -38.60219356
OS 43.3326159 -38.61328828
OS 43.32521942 -38.62623212
OS 43.3187475 -38.6428742
OS 43.31320014 -38.66228996
OS 43.31042646 -38.68355484
OS 43.57022782 -38.68355484
OS 43.57022782 -38.68263028
OS 43.57022782 -38.68078116
OS 43.56930326 -38.67800748
OS 43.56930326 -38.67430924
OS 43.56745414 -38.66321452
OS 43.56468046 -38.65119524
OS 43.56005766 -38.63640228
OS 43.55543486 -38.62253388
OS 43.54803838 -38.60866548
OS 43.53971734 -38.5966462
OS 43.53971734 -38.59572164
OS 43.53786822 -38.59479708
OS 43.53324542 -38.58924972
OS 43.52492438 -38.58185324
OS 43.51382966 -38.5735322
OS 43.49996126 -38.56521116
OS 43.48331918 -38.55781468
OS 43.46390342 -38.55226732
OS 43.45373326 -38.55134276
OS 43.44263854 -38.5504182
OE
OB 34.35791198 -38.39601668 H
OS 34.20628414 -38.39601668
OS 34.20628414 -38.58832516
OS 34.36345934 -38.58832516
OS 34.37547862 -38.5874006
OS 34.38842246 -38.58647604
OS 34.4013663 -38.58555148
OS 34.41431014 -38.58370236
OS 34.4244803 -38.58185324
OS 34.42632942 -38.58092868
OS 34.43002766 -38.58000412
OS 34.43557502 -38.57723044
OS 34.4429715 -38.5735322
OS 34.45036798 -38.56983396
OS 34.45868902 -38.5642866
OS 34.46701006 -38.55689012
OS 34.47348198 -38.54949364
OS 34.47440654 -38.54856908
OS 34.47625566 -38.5457954
OS 34.47902934 -38.54024804
OS 34.48180302 -38.53377612
OS 34.4845767 -38.52637964
OS 34.48735038 -38.51713404
OS 34.4891995 -38.50603932
OS 34.49012406 -38.49402004
OS 34.49012406 -38.49217092
OS 34.49012406 -38.48847268
OS 34.4891995 -38.48292532
OS 34.48827494 -38.47552884
OS 34.48642582 -38.46628324
OS 34.48365214 -38.45703764
OS 34.4799539 -38.44779204
OS 34.47440654 -38.43854644
OS 34.47348198 -38.43762188
OS 34.47163286 -38.4348482
OS 34.46793462 -38.4302254
OS 34.46331182 -38.4256026
OS 34.4568399 -38.42005524
OS 34.44944342 -38.41450788
OS 34.44019782 -38.40896052
OS 34.43002766 -38.40526228
OS 34.4291031 -38.40526228
OS 34.4244803 -38.40341316
OS 34.41800838 -38.4024886
OS 34.40783822 -38.40063948
OS 34.39396982 -38.39879036
OS 34.3782523 -38.3978658
OS 34.35791198 -38.39601668
OE
OB 40.89732486 -38.39601668 H
OS 40.71426198 -38.39601668
OS 40.71426198 -38.624383
OS 40.88623014 -38.624383
OS 40.89270206 -38.62345844
OS 40.89917398 -38.62345844
OS 40.90657046 -38.62253388
OS 40.9241371 -38.62068476
OS 40.94355286 -38.61698652
OS 40.96296862 -38.61143916
OS 40.98053526 -38.60404268
OS 40.9888563 -38.59941988
OS 40.99532822 -38.59387252
OS 40.99717734 -38.5920234
OS 41.00087558 -38.58832516
OS 41.00642294 -38.58092868
OS 41.01289486 -38.57168308
OS 41.01936678 -38.5596638
OS 41.02491414 -38.54487084
OS 41.02861238 -38.52822876
OS 41.0304615 -38.508813
OS 41.0304615 -38.50788844
OS 41.0304615 -38.50696388
OS 41.0304615 -38.50234108
OS 41.02953694 -38.49402004
OS 41.02768782 -38.48477444
OS 41.0258387 -38.47460428
OS 41.02214046 -38.462585
OS 41.0165931 -38.45149028
OS 41.01012118 -38.44039556
OS 41.00919662 -38.439471
OS 41.00642294 -38.43577276
OS 41.00180014 -38.43114996
OS 40.99625278 -38.42467804
OS 40.98793174 -38.41820612
OS 40.97868614 -38.41265876
OS 40.96851598 -38.4071114
OS 40.9564967 -38.4024886
OS 40.95557214 -38.4024886
OS 40.9518739 -38.40156404
OS 40.94632654 -38.40063948
OS 40.93893006 -38.39879036
OS 40.92783534 -38.3978658
OS 40.91396694 -38.39694124
OS 40.89732486 -38.39601668
OE
OB 33.15136118 -38.39601668 H
OS 32.9682983 -38.39601668
OS 32.9682983 -38.624383
OS 33.14026646 -38.624383
OS 33.14673838 -38.62345844
OS 33.1532103 -38.62345844
OS 33.16060678 -38.62253388
OS 33.17817342 -38.62068476
OS 33.19758918 -38.61698652
OS 33.21700494 -38.61143916
OS 33.23457158 -38.60404268
OS 33.24289262 -38.59941988
OS 33.24936454 -38.59387252
OS 33.25121366 -38.5920234
OS 33.2549119 -38.58832516
OS 33.26045926 -38.58092868
OS 33.26693118 -38.57168308
OS 33.2734031 -38.5596638
OS 33.27895046 -38.54487084
OS 33.2826487 -38.52822876
OS 33.28449782 -38.508813
OS 33.28449782 -38.50788844
OS 33.28449782 -38.50696388
OS 33.28449782 -38.50234108
OS 33.28357326 -38.49402004
OS 33.28172414 -38.48477444
OS 33.27987502 -38.47460428
OS 33.27617678 -38.462585
OS 33.27062942 -38.45149028
OS 33.2641575 -38.44039556
OS 33.26323294 -38.439471
OS 33.26045926 -38.43577276
OS 33.25583646 -38.43114996
OS 33.2502891 -38.42467804
OS 33.24196806 -38.41820612
OS 33.23272246 -38.41265876
OS 33.2225523 -38.4071114
OS 33.21053302 -38.4024886
OS 33.20960846 -38.4024886
OS 33.20591022 -38.40156404
OS 33.20036286 -38.40063948
OS 33.19296638 -38.39879036
OS 33.18187166 -38.3978658
OS 33.16800326 -38.39694124
OS 33.15136118 -38.39601668
OE
OB 34.37455406 -38.66413908 H
OS 34.20628414 -38.66413908
OS 34.20628414 -38.88418436
OS 34.38842246 -38.88418436
OS 34.40783822 -38.8832598
OS 34.41615926 -38.88233524
OS 34.42355574 -38.88141068
OS 34.4244803 -38.88141068
OS 34.42817854 -38.88048612
OS 34.4337259 -38.87956156
OS 34.44019782 -38.87771244
OS 34.45591534 -38.87216508
OS 34.47163286 -38.8647686
OS 34.47255742 -38.86384404
OS 34.4753311 -38.86199492
OS 34.47902934 -38.85922124
OS 34.48365214 -38.855523
OS 34.48827494 -38.84997564
OS 34.49474686 -38.84442828
OS 34.49936966 -38.8370318
OS 34.50491702 -38.82871076
OS 34.50584158 -38.8277862
OS 34.50676614 -38.82501252
OS 34.50861526 -38.81946516
OS 34.51138894 -38.81299324
OS 34.51416262 -38.80559676
OS 34.51601174 -38.79635116
OS 34.5169363 -38.78525644
OS 34.51786086 -38.77416172
OS 34.51786086 -38.7723126
OS 34.51786086 -38.76861436
OS 34.5169363 -38.76121788
OS 34.51508718 -38.75289684
OS 34.51323806 -38.74365124
OS 34.50953982 -38.73348108
OS 34.50491702 -38.72331092
OS 34.4984451 -38.71314076
OS 34.49752054 -38.7122162
OS 34.49474686 -38.70851796
OS 34.49104862 -38.70389516
OS 34.48550126 -38.6983478
OS 34.47810478 -38.69187588
OS 34.46885918 -38.68540396
OS 34.45868902 -38.6798566
OS 34.44666974 -38.6752338
OS 34.44482062 -38.67430924
OS 34.44112238 -38.67338468
OS 34.43280134 -38.67153556
OS 34.42263118 -38.66968644
OS 34.40968734 -38.66783732
OS 34.39396982 -38.6659882
OS 34.37455406 -38.66413908
OE
SE
S P 0
OB 48.49040086 -36.61402634 I
OS 48.17420134 -36.61402634
OS 48.17420134 -37.45999874
OS 48.04661206 -37.45999874
OS 48.04661206 -36.61402634
OS 47.73041254 -36.61402634
OS 47.73041254 -36.50030546
OS 48.49040086 -36.50030546
OS 48.49040086 -36.61402634
OE
OB 47.69990206 -37.45999874 I
OS 47.5556707 -37.45999874
OS 47.44333666 -37.16876234
OS 47.04115306 -37.16876234
OS 46.93714006 -37.45999874
OS 46.80261658 -37.45999874
OS 47.16874234 -36.50030546
OS 47.30742634 -36.50030546
OS 47.69990206 -37.45999874
OE
OB 49.31834434 -36.61402634 I
OS 48.75112678 -36.61402634
OS 48.75112678 -36.90664958
OS 49.2822865 -36.90664958
OS 49.2822865 -37.02037046
OS 48.75112678 -37.02037046
OS 48.75112678 -37.34627786
OS 49.34053378 -37.34627786
OS 49.34053378 -37.45999874
OS 48.6235375 -37.45999874
OS 48.6235375 -36.50030546
OS 49.31834434 -36.50030546
OS 49.31834434 -36.61402634
OE
OB 46.33386466 -36.5016923 I
OS 46.36160146 -36.50307914
OS 46.38933826 -36.50585282
OS 46.41707506 -36.51001334
OS 46.44065134 -36.51417386
OS 46.44203818 -36.51417386
OS 46.44481186 -36.5155607
OS 46.44897238 -36.5155607
OS 46.45451974 -36.51833438
OS 46.46977498 -36.5224949
OS 46.48919074 -36.5294291
OS 46.51138018 -36.53913698
OS 46.53495646 -36.55161854
OS 46.55853274 -36.56548694
OS 46.58072218 -36.58351586
OS 46.58210902 -36.5849027
OS 46.58349586 -36.58628954
OS 46.58765638 -36.59045006
OS 46.59320374 -36.59461058
OS 46.60707214 -36.60847898
OS 46.62371422 -36.62789474
OS 46.64174314 -36.65147102
OS 46.6611589 -36.67920782
OS 46.67918782 -36.71110514
OS 46.69444306 -36.74716298
OS 46.69444306 -36.74854982
OS 46.6958299 -36.7513235
OS 46.69860358 -36.75687086
OS 46.69999042 -36.7651919
OS 46.70415094 -36.77489978
OS 46.70692462 -36.7859945
OS 46.7096983 -36.79847606
OS 46.71385882 -36.8137313
OS 46.71801934 -36.82898654
OS 46.72079302 -36.84701546
OS 46.72772722 -36.88584698
OS 46.73188774 -36.92883902
OS 46.73327458 -36.97599158
OS 46.73327458 -36.97737842
OS 46.73327458 -36.9801521
OS 46.73327458 -36.9870863
OS 46.73327458 -36.9940205
OS 46.73188774 -37.00372838
OS 46.73188774 -37.0148231
OS 46.7305009 -37.04117306
OS 46.72634038 -37.07168354
OS 46.72217986 -37.10358086
OS 46.71524566 -37.13686502
OS 46.70692462 -37.17014918
OS 46.70692462 -37.17153602
OS 46.70553778 -37.1743097
OS 46.70415094 -37.17847022
OS 46.7027641 -37.18401758
OS 46.69721674 -37.19927282
OS 46.6888957 -37.21868858
OS 46.68057466 -37.24087802
OS 46.66947994 -37.26306746
OS 46.65561154 -37.28664374
OS 46.64174314 -37.30883318
OS 46.6403563 -37.31160686
OS 46.63480894 -37.31854106
OS 46.6264879 -37.32824894
OS 46.61539318 -37.3407305
OS 46.60291162 -37.3545989
OS 46.58765638 -37.3684673
OS 46.57240114 -37.38372254
OS 46.55437222 -37.3962041
OS 46.55159854 -37.39759094
OS 46.54605118 -37.40175146
OS 46.5363433 -37.40729882
OS 46.5224749 -37.41423302
OS 46.50583282 -37.42255406
OS 46.48641706 -37.42948826
OS 46.46422762 -37.4378093
OS 46.4392645 -37.4447435
OS 46.43649082 -37.4447435
OS 46.4323303 -37.44613034
OS 46.42816978 -37.44751718
OS 46.41430138 -37.44890402
OS 46.39488562 -37.4516777
OS 46.37269618 -37.45445138
OS 46.34634622 -37.45722506
OS 46.31722258 -37.4586119
OS 46.28532526 -37.45999874
OS 45.9400021 -37.45999874
OS 45.9400021 -36.50030546
OS 46.30890154 -36.50030546
OS 46.33386466 -36.5016923
OE
OB 46.28948578 -36.61402634 H
OS 46.06759138 -36.61402634
OS 46.06759138 -37.34627786
OS 46.29503314 -37.34627786
OS 46.30474102 -37.34489102
OS 46.32554362 -37.34350418
OS 46.3491199 -37.34211734
OS 46.37408302 -37.33934366
OS 46.39904614 -37.33518314
OS 46.41984874 -37.32963578
OS 46.42262242 -37.32824894
OS 46.42955662 -37.3268621
OS 46.4392645 -37.32270158
OS 46.45174606 -37.31715422
OS 46.46561446 -37.30883318
OS 46.47948286 -37.30051214
OS 46.49335126 -37.29080426
OS 46.50721966 -37.27970954
OS 46.5086065 -37.27693586
OS 46.51415386 -37.2713885
OS 46.5224749 -37.26168062
OS 46.53218278 -37.24781222
OS 46.5432775 -37.2297833
OS 46.55575906 -37.2089807
OS 46.56685378 -37.18540442
OS 46.57656166 -37.15905446
OS 46.57656166 -37.15766762
OS 46.5779485 -37.15489394
OS 46.57933534 -37.15073342
OS 46.58072218 -37.14518606
OS 46.58210902 -37.13825186
OS 46.5848827 -37.12854398
OS 46.58765638 -37.1188361
OS 46.59043006 -37.10774138
OS 46.59459058 -37.08000458
OS 46.5987511 -37.04810726
OS 46.60152478 -37.01204942
OS 46.60291162 -36.9732179
OS 46.60291162 -36.97183106
OS 46.60291162 -36.9662837
OS 46.60291162 -36.9593495
OS 46.60152478 -36.94825478
OS 46.60152478 -36.93577322
OS 46.60013794 -36.92190482
OS 46.5987511 -36.90526274
OS 46.59736426 -36.88862066
OS 46.59043006 -36.85117598
OS 46.58210902 -36.81234446
OS 46.56962746 -36.77628662
OS 46.56130642 -36.7582577
OS 46.55298538 -36.74300246
OS 46.55298538 -36.74161562
OS 46.5502117 -36.73884194
OS 46.54743802 -36.73468142
OS 46.54466434 -36.72913406
OS 46.53356962 -36.71526566
OS 46.51970122 -36.69862358
OS 46.5016723 -36.68059466
OS 46.4808697 -36.66256574
OS 46.45729342 -36.6473105
OS 46.4323303 -36.63482894
OS 46.42955662 -36.6334421
OS 46.42262242 -36.63205526
OS 46.41014086 -36.62789474
OS 46.39211194 -36.62373422
OS 46.3699225 -36.62096054
OS 46.3421857 -36.61680002
OS 46.32554362 -36.61541318
OS 46.3075147 -36.61541318
OS 46.28948578 -36.61402634
OE
OB 47.23531066 -36.60015794 H
OS 47.23531066 -36.60154478
OS 47.23392382 -36.60431846
OS 47.23392382 -36.60986582
OS 47.23115014 -36.61541318
OS 47.2297633 -36.62512106
OS 47.22698962 -36.63482894
OS 47.22144226 -36.65840522
OS 47.21450806 -36.68614202
OS 47.20480018 -36.7166525
OS 47.1950923 -36.74993666
OS 47.18261074 -36.78460766
OS 47.07859774 -37.06474934
OS 47.4031183 -37.06474934
OS 47.30326582 -36.80124974
OS 47.30326582 -36.7998629
OS 47.30187898 -36.79570238
OS 47.2991053 -36.78876818
OS 47.29633162 -36.78044714
OS 47.2921711 -36.77073926
OS 47.28801058 -36.7582577
OS 47.28385006 -36.7443893
OS 47.2783027 -36.7305209
OS 47.26720798 -36.69862358
OS 47.25611326 -36.66533942
OS 47.24501854 -36.63205526
OS 47.23531066 -36.60015794
OE
SE
S P 0
OB 53.57408132 -38.30725892 I
OS 53.5861006 -38.30910804
OS 53.60089356 -38.31188172
OS 53.61753564 -38.31650452
OS 53.63417772 -38.32205188
OS 53.6508198 -38.32944836
OS 53.65174436 -38.32944836
OS 53.65266892 -38.33037292
OS 53.65821628 -38.3331466
OS 53.66653732 -38.33869396
OS 53.67578292 -38.34516588
OS 53.68687764 -38.35441148
OS 53.69797236 -38.36458164
OS 53.70906708 -38.37660092
OS 53.71831268 -38.39046932
OS 53.71923724 -38.39231844
OS 53.72201092 -38.39694124
OS 53.72570916 -38.40526228
OS 53.73033196 -38.41543244
OS 53.73495476 -38.42745172
OS 53.738653 -38.44132012
OS 53.74142668 -38.45703764
OS 53.74235124 -38.47275516
OS 53.74235124 -38.47460428
OS 53.74235124 -38.48015164
OS 53.74142668 -38.48754812
OS 53.73957756 -38.49771828
OS 53.73680388 -38.50973756
OS 53.73218108 -38.5226814
OS 53.72663372 -38.53562524
OS 53.71923724 -38.54856908
OS 53.71831268 -38.5504182
OS 53.715539 -38.55411644
OS 53.70999164 -38.56058836
OS 53.70259516 -38.56798484
OS 53.69334956 -38.57630588
OS 53.68225484 -38.58555148
OS 53.669311 -38.59387252
OS 53.65359348 -38.60219356
OS 53.65451804 -38.60219356
OS 53.65636716 -38.60311812
OS 53.65914084 -38.60404268
OS 53.66283908 -38.60496724
OS 53.67300924 -38.60866548
OS 53.68595308 -38.61421284
OS 53.70074604 -38.62160932
OS 53.715539 -38.63085492
OS 53.7294074 -38.6428742
OS 53.74235124 -38.6567426
OS 53.7432758 -38.65859172
OS 53.74697404 -38.66413908
OS 53.7525214 -38.67338468
OS 53.75806876 -38.68540396
OS 53.76361612 -38.70019692
OS 53.76916348 -38.71776356
OS 53.77286172 -38.73810388
OS 53.77378628 -38.76029332
OS 53.77378628 -38.76121788
OS 53.77378628 -38.76399156
OS 53.77378628 -38.76861436
OS 53.77286172 -38.77416172
OS 53.77193716 -38.7815582
OS 53.77008804 -38.78987924
OS 53.76823892 -38.79912484
OS 53.7663898 -38.809295
OS 53.75899332 -38.83148444
OS 53.75344596 -38.84350372
OS 53.7478986 -38.85459844
OS 53.74050212 -38.86661772
OS 53.73218108 -38.878637
OS 53.72293548 -38.89065628
OS 53.71184076 -38.901751
OS 53.7109162 -38.90267556
OS 53.70906708 -38.90452468
OS 53.70536884 -38.90729836
OS 53.70074604 -38.9109966
OS 53.69519868 -38.9156194
OS 53.6878022 -38.9202422
OS 53.67948116 -38.92578956
OS 53.669311 -38.93041236
OS 53.65914084 -38.93595972
OS 53.64712156 -38.94150708
OS 53.63510228 -38.94612988
OS 53.62123388 -38.95075268
OS 53.60644092 -38.95445092
OS 53.5907234 -38.9572246
OS 53.57500588 -38.95907372
OS 53.55743924 -38.95999828
OS 53.5491182 -38.95999828
OS 53.54357084 -38.95907372
OS 53.53617436 -38.95814916
OS 53.52785332 -38.9572246
OS 53.51860772 -38.95537548
OS 53.50843756 -38.95352636
OS 53.48624812 -38.947979
OS 53.46313412 -38.9387334
OS 53.45111484 -38.93318604
OS 53.44002012 -38.92671412
OS 53.4289254 -38.91839308
OS 53.41783068 -38.91007204
OS 53.41690612 -38.90914748
OS 53.415057 -38.90729836
OS 53.41228332 -38.90452468
OS 53.40950964 -38.90082644
OS 53.40488684 -38.89620364
OS 53.40026404 -38.88973172
OS 53.39471668 -38.8832598
OS 53.38916932 -38.87493876
OS 53.38362196 -38.86569316
OS 53.3780746 -38.85644756
OS 53.36790444 -38.83425812
OS 53.3595834 -38.80837044
OS 53.35680972 -38.79450204
OS 53.3549606 -38.77970908
OS 53.4335482 -38.76953892
OS 53.4335482 -38.77046348
OS 53.43447276 -38.7723126
OS 53.43539732 -38.77601084
OS 53.43632188 -38.78063364
OS 53.43724644 -38.786181
OS 53.43909556 -38.79265292
OS 53.44371836 -38.80652132
OS 53.45019028 -38.8231634
OS 53.45851132 -38.83888092
OS 53.46775692 -38.85367388
OS 53.47885164 -38.86661772
OS 53.48070076 -38.86754228
OS 53.484399 -38.87124052
OS 53.49179548 -38.87586332
OS 53.50104108 -38.88048612
OS 53.5121358 -38.88603348
OS 53.5260042 -38.89065628
OS 53.54172172 -38.89435452
OS 53.5583638 -38.89527908
OS 53.56391116 -38.89527908
OS 53.5676094 -38.89435452
OS 53.57777956 -38.89342996
OS 53.5907234 -38.89065628
OS 53.60551636 -38.88603348
OS 53.62123388 -38.87956156
OS 53.6369514 -38.87031596
OS 53.65174436 -38.85737212
OS 53.65359348 -38.855523
OS 53.65821628 -38.84997564
OS 53.66376364 -38.8416546
OS 53.67116012 -38.83055988
OS 53.6785566 -38.81669148
OS 53.68410396 -38.80097396
OS 53.68872676 -38.78248276
OS 53.69057588 -38.76214244
OS 53.69057588 -38.76121788
OS 53.69057588 -38.75936876
OS 53.69057588 -38.75659508
OS 53.68965132 -38.75289684
OS 53.68872676 -38.74272668
OS 53.68595308 -38.7307074
OS 53.68225484 -38.71591444
OS 53.67578292 -38.70112148
OS 53.66653732 -38.68632852
OS 53.65451804 -38.67246012
OS 53.65266892 -38.670611
OS 53.64804612 -38.66691276
OS 53.64064964 -38.6613654
OS 53.63047948 -38.65489348
OS 53.61753564 -38.64842156
OS 53.60181812 -38.6428742
OS 53.58425148 -38.63917596
OS 53.56483572 -38.63732684
OS 53.55651468 -38.63732684
OS 53.55004276 -38.6382514
OS 53.54172172 -38.63917596
OS 53.53247612 -38.64102508
OS 53.5213814 -38.6428742
OS 53.50936212 -38.64564788
OS 53.51860772 -38.57630588
OS 53.52323052 -38.57630588
OS 53.52692876 -38.57723044
OS 53.53894804 -38.57723044
OS 53.5491182 -38.57538132
OS 53.56113748 -38.5735322
OS 53.57500588 -38.57075852
OS 53.5907234 -38.56613572
OS 53.60551636 -38.5596638
OS 53.62123388 -38.55134276
OS 53.62215844 -38.55134276
OS 53.623083 -38.5504182
OS 53.6277058 -38.54671996
OS 53.63417772 -38.54024804
OS 53.6415742 -38.531927
OS 53.64897068 -38.51990772
OS 53.6554426 -38.50603932
OS 53.6600654 -38.4903218
OS 53.66191452 -38.4810762
OS 53.66191452 -38.47090604
OS 53.66191452 -38.46998148
OS 53.66191452 -38.46905692
OS 53.66191452 -38.46350956
OS 53.6600654 -38.45611308
OS 53.65821628 -38.44594292
OS 53.65451804 -38.4348482
OS 53.64989524 -38.42282892
OS 53.64249876 -38.41080964
OS 53.6323286 -38.39971492
OS 53.63140404 -38.39879036
OS 53.62678124 -38.39509212
OS 53.62030932 -38.39046932
OS 53.61198828 -38.38492196
OS 53.60089356 -38.38029916
OS 53.58794972 -38.37567636
OS 53.57315676 -38.37197812
OS 53.55651468 -38.37105356
OS 53.5491182 -38.37105356
OS 53.54079716 -38.37290268
OS 53.52970244 -38.3747518
OS 53.51768316 -38.37845004
OS 53.50566388 -38.38307284
OS 53.49272004 -38.39046932
OS 53.48070076 -38.39971492
OS 53.4797762 -38.40063948
OS 53.47607796 -38.40526228
OS 53.4705306 -38.4117342
OS 53.46405868 -38.4209798
OS 53.45758676 -38.43299908
OS 53.45111484 -38.44779204
OS 53.44556748 -38.46535868
OS 53.44186924 -38.485699
OS 53.36328164 -38.4718306
OS 53.36328164 -38.47090604
OS 53.3642062 -38.46813236
OS 53.36513076 -38.46443412
OS 53.36605532 -38.45888676
OS 53.36790444 -38.45241484
OS 53.37067812 -38.44501836
OS 53.37622548 -38.42745172
OS 53.38547108 -38.4071114
OS 53.3965658 -38.38677108
OS 53.4104342 -38.36735532
OS 53.42800084 -38.34978868
OS 53.4289254 -38.34886412
OS 53.43077452 -38.34793956
OS 53.4335482 -38.34609044
OS 53.43724644 -38.34331676
OS 53.44186924 -38.33961852
OS 53.44834116 -38.33592028
OS 53.45481308 -38.33222204
OS 53.46313412 -38.32759924
OS 53.48162532 -38.32020276
OS 53.5028902 -38.31280628
OS 53.52785332 -38.30818348
OS 53.54079716 -38.30633436
OS 53.56391116 -38.30633436
OS 53.57408132 -38.30725892
OE
OB 54.07889108 -38.30725892 I
OS 54.09091036 -38.30910804
OS 54.10477876 -38.31188172
OS 54.11957172 -38.31557996
OS 54.13528924 -38.32020276
OS 54.1500822 -38.32759924
OS 54.15100676 -38.32759924
OS 54.15193132 -38.3285238
OS 54.15655412 -38.33129748
OS 54.1639506 -38.33592028
OS 54.1731962 -38.3423922
OS 54.18336636 -38.3516378
OS 54.19446108 -38.36180796
OS 54.20463124 -38.37382724
OS 54.2148014 -38.38769564
OS 54.21572596 -38.38954476
OS 54.2194242 -38.39416756
OS 54.22312244 -38.4024886
OS 54.22959436 -38.41450788
OS 54.23514172 -38.42837628
OS 54.2425382 -38.4440938
OS 54.24901012 -38.462585
OS 54.25455748 -38.48292532
OS 54.25455748 -38.48384988
OS 54.25548204 -38.485699
OS 54.2564066 -38.48847268
OS 54.25733116 -38.49309548
OS 54.25825572 -38.49864284
OS 54.25918028 -38.50511476
OS 54.2610294 -38.5134358
OS 54.26195396 -38.5226814
OS 54.26380308 -38.53285156
OS 54.26472764 -38.54394628
OS 54.2656522 -38.55689012
OS 54.26750132 -38.56983396
OS 54.26842588 -38.58462692
OS 54.26842588 -38.59941988
OS 54.26935044 -38.61606196
OS 54.26935044 -38.6336286
OS 54.26935044 -38.63455316
OS 54.26935044 -38.6382514
OS 54.26935044 -38.64472332
OS 54.26935044 -38.6521198
OS 54.26842588 -38.66228996
OS 54.26842588 -38.67338468
OS 54.26750132 -38.68540396
OS 54.26657676 -38.6983478
OS 54.26380308 -38.72793372
OS 54.25918028 -38.7584442
OS 54.25363292 -38.78803012
OS 54.24993468 -38.80189852
OS 54.24531188 -38.81576692
OS 54.24531188 -38.81669148
OS 54.24438732 -38.8185406
OS 54.2425382 -38.82223884
OS 54.24068908 -38.82686164
OS 54.23883996 -38.83333356
OS 54.23514172 -38.83980548
OS 54.22774524 -38.855523
OS 54.21849964 -38.87216508
OS 54.20648036 -38.89065628
OS 54.19261196 -38.90729836
OS 54.17596988 -38.92301588
OS 54.17504532 -38.92301588
OS 54.17412076 -38.924865
OS 54.17134708 -38.92671412
OS 54.16764884 -38.92856324
OS 54.16302604 -38.93133692
OS 54.15840324 -38.93503516
OS 54.14453484 -38.94150708
OS 54.12789276 -38.947979
OS 54.108477 -38.95445092
OS 54.085363 -38.95814916
OS 54.06039988 -38.95999828
OS 54.05115428 -38.95999828
OS 54.04468236 -38.95907372
OS 54.03728588 -38.95814916
OS 54.02804028 -38.95630004
OS 54.01787012 -38.95445092
OS 54.0067754 -38.95167724
OS 53.99568068 -38.947979
OS 53.9836614 -38.94428076
OS 53.97164212 -38.9387334
OS 53.95962284 -38.93226148
OS 53.94760356 -38.924865
OS 53.93558428 -38.9156194
OS 53.92448956 -38.90544924
OS 53.9143194 -38.89435452
OS 53.91339484 -38.89342996
OS 53.91154572 -38.89065628
OS 53.90877204 -38.88603348
OS 53.90414924 -38.878637
OS 53.89952644 -38.87031596
OS 53.89490364 -38.85922124
OS 53.88843172 -38.8462774
OS 53.88288436 -38.83148444
OS 53.877337 -38.81484236
OS 53.87178964 -38.7954266
OS 53.86624228 -38.77416172
OS 53.86161948 -38.75012316
OS 53.85699668 -38.72423548
OS 53.854223 -38.69649868
OS 53.85237388 -38.6659882
OS 53.85144932 -38.6336286
OS 53.85144932 -38.63270404
OS 53.85144932 -38.6290058
OS 53.85144932 -38.62253388
OS 53.85144932 -38.6151374
OS 53.85237388 -38.60496724
OS 53.85237388 -38.59387252
OS 53.85329844 -38.58185324
OS 53.854223 -38.56798484
OS 53.85699668 -38.53932348
OS 53.86161948 -38.508813
OS 53.86716684 -38.47830252
OS 53.87086508 -38.46443412
OS 53.87456332 -38.45056572
OS 53.87456332 -38.44964116
OS 53.87548788 -38.44779204
OS 53.877337 -38.4440938
OS 53.87918612 -38.439471
OS 53.88103524 -38.43299908
OS 53.88473348 -38.42652716
OS 53.89212996 -38.41080964
OS 53.90137556 -38.39416756
OS 53.91339484 -38.37660092
OS 53.92726324 -38.35903428
OS 53.94390532 -38.34424132
OS 53.94482988 -38.34424132
OS 53.94575444 -38.3423922
OS 53.94852812 -38.34054308
OS 53.95222636 -38.33869396
OS 53.95684916 -38.33499572
OS 53.96239652 -38.33222204
OS 53.97626492 -38.32482556
OS 53.992907 -38.31835364
OS 54.01232276 -38.31188172
OS 54.03543676 -38.30818348
OS 54.06039988 -38.30633436
OS 54.06872092 -38.30633436
OS 54.07889108 -38.30725892
OE
OB 53.23846604 -38.94890356 I
OS 53.14878372 -38.94890356
OS 53.14878372 -38.85922124
OS 53.23846604 -38.85922124
OS 53.23846604 -38.94890356
OE
OB 53.00177868 -38.39231844 I
OS 52.74567556 -38.39231844
OS 52.71146684 -38.56521116
OS 52.7123914 -38.5642866
OS 52.71424052 -38.56336204
OS 52.7170142 -38.56151292
OS 52.721637 -38.55873924
OS 52.72718436 -38.55596556
OS 52.73365628 -38.55226732
OS 52.74844924 -38.54487084
OS 52.76694044 -38.53747436
OS 52.78728076 -38.53100244
OS 52.8094702 -38.52637964
OS 52.82056492 -38.52453052
OS 52.84090524 -38.52453052
OS 52.8464526 -38.52545508
OS 52.85384908 -38.52637964
OS 52.86217012 -38.5273042
OS 52.87141572 -38.52915332
OS 52.88158588 -38.531927
OS 52.90377532 -38.53839892
OS 52.9157946 -38.54302172
OS 52.92781388 -38.54949364
OS 52.93983316 -38.55596556
OS 52.95185244 -38.56336204
OS 52.96294716 -38.57260764
OS 52.97404188 -38.5827778
OS 52.97496644 -38.58370236
OS 52.97681556 -38.58555148
OS 52.97958924 -38.58832516
OS 52.98328748 -38.59294796
OS 52.98791028 -38.59941988
OS 52.99253308 -38.6058918
OS 52.99808044 -38.61421284
OS 53.0036278 -38.62345844
OS 53.0082506 -38.6336286
OS 53.01379796 -38.64472332
OS 53.01842076 -38.65766716
OS 53.02304356 -38.670611
OS 53.0267418 -38.6844794
OS 53.02951548 -38.70019692
OS 53.0313646 -38.71591444
OS 53.03228916 -38.73255652
OS 53.03228916 -38.73348108
OS 53.03228916 -38.73625476
OS 53.03228916 -38.74087756
OS 53.0313646 -38.74734948
OS 53.03044004 -38.75474596
OS 53.02951548 -38.763067
OS 53.02766636 -38.77323716
OS 53.02581724 -38.78340732
OS 53.02026988 -38.80744588
OS 53.01102428 -38.832409
OS 53.00547692 -38.84535284
OS 52.99808044 -38.85737212
OS 52.99068396 -38.87031596
OS 52.98143836 -38.88233524
OS 52.9805138 -38.8832598
OS 52.97866468 -38.88603348
OS 52.97496644 -38.88973172
OS 52.97034364 -38.89435452
OS 52.96387172 -38.89990188
OS 52.95647524 -38.90729836
OS 52.94722964 -38.91377028
OS 52.93705948 -38.92116676
OS 52.92596476 -38.92856324
OS 52.91302092 -38.93503516
OS 52.89915252 -38.94150708
OS 52.88435956 -38.947979
OS 52.86864204 -38.9526018
OS 52.8510754 -38.95630004
OS 52.8325842 -38.95907372
OS 52.81316844 -38.95999828
OS 52.8048474 -38.95999828
OS 52.79837548 -38.95907372
OS 52.790979 -38.95814916
OS 52.78265796 -38.9572246
OS 52.7724878 -38.95630004
OS 52.76231764 -38.95352636
OS 52.73920364 -38.947979
OS 52.71608964 -38.93965796
OS 52.70407036 -38.9341106
OS 52.69205108 -38.92763868
OS 52.68095636 -38.9202422
OS 52.66986164 -38.91192116
OS 52.66893708 -38.9109966
OS 52.66708796 -38.91007204
OS 52.66523884 -38.9063738
OS 52.6615406 -38.90267556
OS 52.6569178 -38.89805276
OS 52.652295 -38.8925054
OS 52.64674764 -38.88510892
OS 52.64212484 -38.87678788
OS 52.63657748 -38.86846684
OS 52.63103012 -38.85829668
OS 52.62085996 -38.83610724
OS 52.61253892 -38.81021956
OS 52.60976524 -38.79635116
OS 52.60791612 -38.7815582
OS 52.69020196 -38.77508628
OS 52.69020196 -38.77601084
OS 52.69020196 -38.77785996
OS 52.69112652 -38.78063364
OS 52.69205108 -38.78525644
OS 52.69482476 -38.7954266
OS 52.698523 -38.809295
OS 52.70407036 -38.8231634
OS 52.71146684 -38.83888092
OS 52.72071244 -38.85274932
OS 52.73180716 -38.86569316
OS 52.73365628 -38.86661772
OS 52.73735452 -38.87031596
OS 52.744751 -38.87493876
OS 52.75492116 -38.88048612
OS 52.76601588 -38.88603348
OS 52.77988428 -38.89065628
OS 52.7956018 -38.89435452
OS 52.81316844 -38.89527908
OS 52.8187158 -38.89527908
OS 52.82241404 -38.89435452
OS 52.83350876 -38.89342996
OS 52.8464526 -38.88973172
OS 52.86217012 -38.88510892
OS 52.87788764 -38.87771244
OS 52.89452972 -38.86661772
OS 52.9019262 -38.8601458
OS 52.90932268 -38.85274932
OS 52.91024724 -38.85182476
OS 52.9111718 -38.8509002
OS 52.91302092 -38.84812652
OS 52.9157946 -38.84535284
OS 52.92226652 -38.83518268
OS 52.929663 -38.82223884
OS 52.93613492 -38.80652132
OS 52.94260684 -38.78710556
OS 52.94722964 -38.76399156
OS 52.94907876 -38.75197228
OS 52.94907876 -38.73902844
OS 52.94907876 -38.73810388
OS 52.94907876 -38.73625476
OS 52.94907876 -38.73255652
OS 52.9481542 -38.72793372
OS 52.9481542 -38.72238636
OS 52.94722964 -38.71591444
OS 52.94445596 -38.70112148
OS 52.93983316 -38.68355484
OS 52.93336124 -38.6659882
OS 52.92411564 -38.64934612
OS 52.9111718 -38.6336286
OS 52.9111718 -38.63270404
OS 52.90932268 -38.63177948
OS 52.90469988 -38.62715668
OS 52.89637884 -38.62068476
OS 52.88528412 -38.61328828
OS 52.87049116 -38.60681636
OS 52.85384908 -38.60034444
OS 52.83443332 -38.59572164
OS 52.8233386 -38.59387252
OS 52.80577196 -38.59387252
OS 52.79837548 -38.59479708
OS 52.78912988 -38.59572164
OS 52.77803516 -38.59849532
OS 52.76694044 -38.601269
OS 52.75492116 -38.6058918
OS 52.74290188 -38.61143916
OS 52.74197732 -38.61236372
OS 52.73827908 -38.61421284
OS 52.73273172 -38.61883564
OS 52.72533524 -38.62345844
OS 52.71793876 -38.62993036
OS 52.71054228 -38.6382514
OS 52.70222124 -38.64657244
OS 52.69574932 -38.6567426
OS 52.62178452 -38.64657244
OS 52.68373004 -38.31742908
OS 53.00177868 -38.31742908
OS 53.00177868 -38.39231844
OE
OB 53.23846604 -38.57445676 I
OS 53.14878372 -38.57445676
OS 53.14878372 -38.48477444
OS 53.23846604 -38.48477444
OS 53.23846604 -38.57445676
OE
OB 54.48199924 -38.57445676 I
OS 54.39231692 -38.57445676
OS 54.39231692 -38.48477444
OS 54.48199924 -38.48477444
OS 54.48199924 -38.57445676
OE
OB 56.14990548 -38.3100326 I
OS 56.165623 -38.31095716
OS 56.18226508 -38.31188172
OS 56.1979826 -38.31373084
OS 56.211851 -38.31557996
OS 56.21370012 -38.31557996
OS 56.22017204 -38.31742908
OS 56.22849308 -38.3192782
OS 56.2395878 -38.32205188
OS 56.25160708 -38.32667468
OS 56.26455092 -38.33222204
OS 56.27841932 -38.33869396
OS 56.2904386 -38.34609044
OS 56.29228772 -38.347015
OS 56.29598596 -38.34978868
OS 56.30153332 -38.35533604
OS 56.3089298 -38.36180796
OS 56.31725084 -38.370129
OS 56.32557188 -38.38122372
OS 56.33481748 -38.393243
OS 56.34221396 -38.4071114
OS 56.34313852 -38.40896052
OS 56.34498764 -38.41358332
OS 56.34868588 -38.42190436
OS 56.35238412 -38.43299908
OS 56.3551578 -38.44594292
OS 56.35885604 -38.46073588
OS 56.36070516 -38.47737796
OS 56.36162972 -38.4949446
OS 56.36162972 -38.49586916
OS 56.36162972 -38.49864284
OS 56.36162972 -38.50234108
OS 56.36070516 -38.508813
OS 56.3597806 -38.51528492
OS 56.35885604 -38.52360596
OS 56.35700692 -38.53285156
OS 56.3551578 -38.54302172
OS 56.34868588 -38.5642866
OS 56.34498764 -38.57538132
OS 56.33944028 -38.5874006
OS 56.33296836 -38.59941988
OS 56.32649644 -38.6105146
OS 56.3181754 -38.62160932
OS 56.3089298 -38.63270404
OS 56.30800524 -38.6336286
OS 56.30615612 -38.63547772
OS 56.30338244 -38.6382514
OS 56.29875964 -38.64102508
OS 56.29321228 -38.64564788
OS 56.2858158 -38.65027068
OS 56.2765702 -38.65581804
OS 56.26640004 -38.66044084
OS 56.25438076 -38.6659882
OS 56.24051236 -38.67153556
OS 56.2257194 -38.67615836
OS 56.20815276 -38.6798566
OS 56.18966156 -38.68355484
OS 56.16932124 -38.68632852
OS 56.14620724 -38.68817764
OS 56.12216868 -38.6891022
OS 55.95852156 -38.6891022
OS 55.95852156 -38.94890356
OS 55.87346204 -38.94890356
OS 55.87346204 -38.30910804
OS 56.13603708 -38.30910804
OS 56.14990548 -38.3100326
OE
OB 57.07723916 -38.94890356 I
OS 56.99587788 -38.94890356
OS 56.99587788 -38.41358332
OS 56.80911676 -38.94890356
OS 56.73330284 -38.94890356
OS 56.54839084 -38.40433772
OS 56.54839084 -38.94890356
OS 56.46702956 -38.94890356
OS 56.46702956 -38.30910804
OS 56.59369428 -38.30910804
OS 56.74532212 -38.763067
OS 56.74532212 -38.76399156
OS 56.74624668 -38.76584068
OS 56.74717124 -38.76861436
OS 56.74902036 -38.77323716
OS 56.7527186 -38.78433188
OS 56.7573414 -38.79820028
OS 56.7619642 -38.8139178
OS 56.76751156 -38.82963532
OS 56.77213436 -38.84442828
OS 56.7758326 -38.85737212
OS 56.77675716 -38.855523
OS 56.77768172 -38.8509002
OS 56.7804554 -38.84257916
OS 56.78415364 -38.83148444
OS 56.78877644 -38.81669148
OS 56.79524836 -38.79912484
OS 56.80172028 -38.77878452
OS 56.81004132 -38.75474596
OS 56.96351828 -38.30910804
OS 57.07723916 -38.30910804
OS 57.07723916 -38.94890356
OE
OB 55.3150278 -38.30725892 I
OS 55.32704708 -38.30910804
OS 55.34184004 -38.31188172
OS 55.35848212 -38.31650452
OS 55.3751242 -38.32205188
OS 55.39176628 -38.32944836
OS 55.39269084 -38.32944836
OS 55.3936154 -38.33037292
OS 55.39916276 -38.3331466
OS 55.4074838 -38.33869396
OS 55.4167294 -38.34516588
OS 55.42782412 -38.35441148
OS 55.43891884 -38.36458164
OS 55.45001356 -38.37660092
OS 55.45925916 -38.39046932
OS 55.46018372 -38.39231844
OS 55.4629574 -38.39694124
OS 55.46665564 -38.40526228
OS 55.47127844 -38.41543244
OS 55.47590124 -38.42745172
OS 55.47959948 -38.44132012
OS 55.48237316 -38.45703764
OS 55.48329772 -38.47275516
OS 55.48329772 -38.47460428
OS 55.48329772 -38.48015164
OS 55.48237316 -38.48754812
OS 55.48052404 -38.49771828
OS 55.47775036 -38.50973756
OS 55.47312756 -38.5226814
OS 55.4675802 -38.53562524
OS 55.46018372 -38.54856908
OS 55.45925916 -38.5504182
OS 55.45648548 -38.55411644
OS 55.45093812 -38.56058836
OS 55.44354164 -38.56798484
OS 55.43429604 -38.57630588
OS 55.42320132 -38.58555148
OS 55.41025748 -38.59387252
OS 55.39453996 -38.60219356
OS 55.39546452 -38.60219356
OS 55.39731364 -38.60311812
OS 55.40008732 -38.60404268
OS 55.40378556 -38.60496724
OS 55.41395572 -38.60866548
OS 55.42689956 -38.61421284
OS 55.44169252 -38.62160932
OS 55.45648548 -38.63085492
OS 55.47035388 -38.6428742
OS 55.48329772 -38.6567426
OS 55.48422228 -38.65859172
OS 55.48792052 -38.66413908
OS 55.49346788 -38.67338468
OS 55.49901524 -38.68540396
OS 55.5045626 -38.70019692
OS 55.51010996 -38.71776356
OS 55.5138082 -38.73810388
OS 55.51473276 -38.76029332
OS 55.51473276 -38.76121788
OS 55.51473276 -38.76399156
OS 55.51473276 -38.76861436
OS 55.5138082 -38.77416172
OS 55.51288364 -38.7815582
OS 55.51103452 -38.78987924
OS 55.5091854 -38.79912484
OS 55.50733628 -38.809295
OS 55.4999398 -38.83148444
OS 55.49439244 -38.84350372
OS 55.48884508 -38.85459844
OS 55.4814486 -38.86661772
OS 55.47312756 -38.878637
OS 55.46388196 -38.89065628
OS 55.45278724 -38.901751
OS 55.45186268 -38.90267556
OS 55.45001356 -38.90452468
OS 55.44631532 -38.90729836
OS 55.44169252 -38.9109966
OS 55.43614516 -38.9156194
OS 55.42874868 -38.9202422
OS 55.42042764 -38.92578956
OS 55.41025748 -38.93041236
OS 55.40008732 -38.93595972
OS 55.38806804 -38.94150708
OS 55.37604876 -38.94612988
OS 55.36218036 -38.95075268
OS 55.3473874 -38.95445092
OS 55.33166988 -38.9572246
OS 55.31595236 -38.95907372
OS 55.29838572 -38.95999828
OS 55.29006468 -38.95999828
OS 55.28451732 -38.95907372
OS 55.27712084 -38.95814916
OS 55.2687998 -38.9572246
OS 55.2595542 -38.95537548
OS 55.24938404 -38.95352636
OS 55.2271946 -38.947979
OS 55.2040806 -38.9387334
OS 55.19206132 -38.93318604
OS 55.1809666 -38.92671412
OS 55.16987188 -38.91839308
OS 55.15877716 -38.91007204
OS 55.1578526 -38.90914748
OS 55.15600348 -38.90729836
OS 55.1532298 -38.90452468
OS 55.15045612 -38.90082644
OS 55.14583332 -38.89620364
OS 55.14121052 -38.88973172
OS 55.13566316 -38.8832598
OS 55.1301158 -38.87493876
OS 55.12456844 -38.86569316
OS 55.11902108 -38.85644756
OS 55.10885092 -38.83425812
OS 55.10052988 -38.80837044
OS 55.0977562 -38.79450204
OS 55.09590708 -38.77970908
OS 55.17449468 -38.76953892
OS 55.17449468 -38.77046348
OS 55.17541924 -38.7723126
OS 55.1763438 -38.77601084
OS 55.17726836 -38.78063364
OS 55.17819292 -38.786181
OS 55.18004204 -38.79265292
OS 55.18466484 -38.80652132
OS 55.19113676 -38.8231634
OS 55.1994578 -38.83888092
OS 55.2087034 -38.85367388
OS 55.21979812 -38.86661772
OS 55.22164724 -38.86754228
OS 55.22534548 -38.87124052
OS 55.23274196 -38.87586332
OS 55.24198756 -38.88048612
OS 55.25308228 -38.88603348
OS 55.26695068 -38.89065628
OS 55.2826682 -38.89435452
OS 55.29931028 -38.89527908
OS 55.30485764 -38.89527908
OS 55.30855588 -38.89435452
OS 55.31872604 -38.89342996
OS 55.33166988 -38.89065628
OS 55.34646284 -38.88603348
OS 55.36218036 -38.87956156
OS 55.37789788 -38.87031596
OS 55.39269084 -38.85737212
OS 55.39453996 -38.855523
OS 55.39916276 -38.84997564
OS 55.40471012 -38.8416546
OS 55.4121066 -38.83055988
OS 55.41950308 -38.81669148
OS 55.42505044 -38.80097396
OS 55.42967324 -38.78248276
OS 55.43152236 -38.76214244
OS 55.43152236 -38.76121788
OS 55.43152236 -38.75936876
OS 55.43152236 -38.75659508
OS 55.4305978 -38.75289684
OS 55.42967324 -38.74272668
OS 55.42689956 -38.7307074
OS 55.42320132 -38.71591444
OS 55.4167294 -38.70112148
OS 55.4074838 -38.68632852
OS 55.39546452 -38.67246012
OS 55.3936154 -38.670611
OS 55.3889926 -38.66691276
OS 55.38159612 -38.6613654
OS 55.37142596 -38.65489348
OS 55.35848212 -38.64842156
OS 55.3427646 -38.6428742
OS 55.32519796 -38.63917596
OS 55.3057822 -38.63732684
OS 55.29746116 -38.63732684
OS 55.29098924 -38.6382514
OS 55.2826682 -38.63917596
OS 55.2734226 -38.64102508
OS 55.26232788 -38.6428742
OS 55.2503086 -38.64564788
OS 55.2595542 -38.57630588
OS 55.264177 -38.57630588
OS 55.26787524 -38.57723044
OS 55.27989452 -38.57723044
OS 55.29006468 -38.57538132
OS 55.30208396 -38.5735322
OS 55.31595236 -38.57075852
OS 55.33166988 -38.56613572
OS 55.34646284 -38.5596638
OS 55.36218036 -38.55134276
OS 55.36310492 -38.55134276
OS 55.36402948 -38.5504182
OS 55.36865228 -38.54671996
OS 55.3751242 -38.54024804
OS 55.38252068 -38.531927
OS 55.38991716 -38.51990772
OS 55.39638908 -38.50603932
OS 55.40101188 -38.4903218
OS 55.402861 -38.4810762
OS 55.402861 -38.47090604
OS 55.402861 -38.46998148
OS 55.402861 -38.46905692
OS 55.402861 -38.46350956
OS 55.40101188 -38.45611308
OS 55.39916276 -38.44594292
OS 55.39546452 -38.4348482
OS 55.39084172 -38.42282892
OS 55.38344524 -38.41080964
OS 55.37327508 -38.39971492
OS 55.37235052 -38.39879036
OS 55.36772772 -38.39509212
OS 55.3612558 -38.39046932
OS 55.35293476 -38.38492196
OS 55.34184004 -38.38029916
OS 55.3288962 -38.37567636
OS 55.31410324 -38.37197812
OS 55.29746116 -38.37105356
OS 55.29006468 -38.37105356
OS 55.28174364 -38.37290268
OS 55.27064892 -38.3747518
OS 55.25862964 -38.37845004
OS 55.24661036 -38.38307284
OS 55.23366652 -38.39046932
OS 55.22164724 -38.39971492
OS 55.22072268 -38.40063948
OS 55.21702444 -38.40526228
OS 55.21147708 -38.4117342
OS 55.20500516 -38.4209798
OS 55.19853324 -38.43299908
OS 55.19206132 -38.44779204
OS 55.18651396 -38.46535868
OS 55.18281572 -38.485699
OS 55.10422812 -38.4718306
OS 55.10422812 -38.47090604
OS 55.10515268 -38.46813236
OS 55.10607724 -38.46443412
OS 55.1070018 -38.45888676
OS 55.10885092 -38.45241484
OS 55.1116246 -38.44501836
OS 55.11717196 -38.42745172
OS 55.12641756 -38.4071114
OS 55.13751228 -38.38677108
OS 55.15138068 -38.36735532
OS 55.16894732 -38.34978868
OS 55.16987188 -38.34886412
OS 55.171721 -38.34793956
OS 55.17449468 -38.34609044
OS 55.17819292 -38.34331676
OS 55.18281572 -38.33961852
OS 55.18928764 -38.33592028
OS 55.19575956 -38.33222204
OS 55.2040806 -38.32759924
OS 55.2225718 -38.32020276
OS 55.24383668 -38.31280628
OS 55.2687998 -38.30818348
OS 55.28174364 -38.30633436
OS 55.30485764 -38.30633436
OS 55.3150278 -38.30725892
OE
OB 54.48199924 -38.94890356 I
OS 54.39231692 -38.94890356
OS 54.39231692 -38.85922124
OS 54.48199924 -38.85922124
OS 54.48199924 -38.94890356
OE
OB 54.9914318 -38.39231844 I
OS 54.73532868 -38.39231844
OS 54.70111996 -38.56521116
OS 54.70204452 -38.5642866
OS 54.70389364 -38.56336204
OS 54.70666732 -38.56151292
OS 54.71129012 -38.55873924
OS 54.71683748 -38.55596556
OS 54.7233094 -38.55226732
OS 54.73810236 -38.54487084
OS 54.75659356 -38.53747436
OS 54.77693388 -38.53100244
OS 54.79912332 -38.52637964
OS 54.81021804 -38.52453052
OS 54.83055836 -38.52453052
OS 54.83610572 -38.52545508
OS 54.8435022 -38.52637964
OS 54.85182324 -38.5273042
OS 54.86106884 -38.52915332
OS 54.871239 -38.531927
OS 54.89342844 -38.53839892
OS 54.90544772 -38.54302172
OS 54.917467 -38.54949364
OS 54.92948628 -38.55596556
OS 54.94150556 -38.56336204
OS 54.95260028 -38.57260764
OS 54.963695 -38.5827778
OS 54.96461956 -38.58370236
OS 54.96646868 -38.58555148
OS 54.96924236 -38.58832516
OS 54.9729406 -38.59294796
OS 54.9775634 -38.59941988
OS 54.9821862 -38.6058918
OS 54.98773356 -38.61421284
OS 54.99328092 -38.62345844
OS 54.99790372 -38.6336286
OS 55.00345108 -38.64472332
OS 55.00807388 -38.65766716
OS 55.01269668 -38.670611
OS 55.01639492 -38.6844794
OS 55.0191686 -38.70019692
OS 55.02101772 -38.71591444
OS 55.02194228 -38.73255652
OS 55.02194228 -38.73348108
OS 55.02194228 -38.73625476
OS 55.02194228 -38.74087756
OS 55.02101772 -38.74734948
OS 55.02009316 -38.75474596
OS 55.0191686 -38.763067
OS 55.01731948 -38.77323716
OS 55.01547036 -38.78340732
OS 55.009923 -38.80744588
OS 55.0006774 -38.832409
OS 54.99513004 -38.84535284
OS 54.98773356 -38.85737212
OS 54.98033708 -38.87031596
OS 54.97109148 -38.88233524
OS 54.97016692 -38.8832598
OS 54.9683178 -38.88603348
OS 54.96461956 -38.88973172
OS 54.95999676 -38.89435452
OS 54.95352484 -38.89990188
OS 54.94612836 -38.90729836
OS 54.93688276 -38.91377028
OS 54.9267126 -38.92116676
OS 54.91561788 -38.92856324
OS 54.90267404 -38.93503516
OS 54.88880564 -38.94150708
OS 54.87401268 -38.947979
OS 54.85829516 -38.9526018
OS 54.84072852 -38.95630004
OS 54.82223732 -38.95907372
OS 54.80282156 -38.95999828
OS 54.79450052 -38.95999828
OS 54.7880286 -38.95907372
OS 54.78063212 -38.95814916
OS 54.77231108 -38.9572246
OS 54.76214092 -38.95630004
OS 54.75197076 -38.95352636
OS 54.72885676 -38.947979
OS 54.70574276 -38.93965796
OS 54.69372348 -38.9341106
OS 54.6817042 -38.92763868
OS 54.67060948 -38.9202422
OS 54.65951476 -38.91192116
OS 54.6585902 -38.9109966
OS 54.65674108 -38.91007204
OS 54.65489196 -38.9063738
OS 54.65119372 -38.90267556
OS 54.64657092 -38.89805276
OS 54.64194812 -38.8925054
OS 54.63640076 -38.88510892
OS 54.63177796 -38.87678788
OS 54.6262306 -38.86846684
OS 54.62068324 -38.85829668
OS 54.61051308 -38.83610724
OS 54.60219204 -38.81021956
OS 54.59941836 -38.79635116
OS 54.59756924 -38.7815582
OS 54.67985508 -38.77508628
OS 54.67985508 -38.77601084
OS 54.67985508 -38.77785996
OS 54.68077964 -38.78063364
OS 54.6817042 -38.78525644
OS 54.68447788 -38.7954266
OS 54.68817612 -38.809295
OS 54.69372348 -38.8231634
OS 54.70111996 -38.83888092
OS 54.71036556 -38.85274932
OS 54.72146028 -38.86569316
OS 54.7233094 -38.86661772
OS 54.72700764 -38.87031596
OS 54.73440412 -38.87493876
OS 54.74457428 -38.88048612
OS 54.755669 -38.88603348
OS 54.7695374 -38.89065628
OS 54.78525492 -38.89435452
OS 54.80282156 -38.89527908
OS 54.80836892 -38.89527908
OS 54.81206716 -38.89435452
OS 54.82316188 -38.89342996
OS 54.83610572 -38.88973172
OS 54.85182324 -38.88510892
OS 54.86754076 -38.87771244
OS 54.88418284 -38.86661772
OS 54.89157932 -38.8601458
OS 54.8989758 -38.85274932
OS 54.89990036 -38.85182476
OS 54.90082492 -38.8509002
OS 54.90267404 -38.84812652
OS 54.90544772 -38.84535284
OS 54.91191964 -38.83518268
OS 54.91931612 -38.82223884
OS 54.92578804 -38.80652132
OS 54.93225996 -38.78710556
OS 54.93688276 -38.76399156
OS 54.93873188 -38.75197228
OS 54.93873188 -38.73902844
OS 54.93873188 -38.73810388
OS 54.93873188 -38.73625476
OS 54.93873188 -38.73255652
OS 54.93780732 -38.72793372
OS 54.93780732 -38.72238636
OS 54.93688276 -38.71591444
OS 54.93410908 -38.70112148
OS 54.92948628 -38.68355484
OS 54.92301436 -38.6659882
OS 54.91376876 -38.64934612
OS 54.90082492 -38.6336286
OS 54.90082492 -38.63270404
OS 54.8989758 -38.63177948
OS 54.894353 -38.62715668
OS 54.88603196 -38.62068476
OS 54.87493724 -38.61328828
OS 54.86014428 -38.60681636
OS 54.8435022 -38.60034444
OS 54.82408644 -38.59572164
OS 54.81299172 -38.59387252
OS 54.79542508 -38.59387252
OS 54.7880286 -38.59479708
OS 54.778783 -38.59572164
OS 54.76768828 -38.59849532
OS 54.75659356 -38.601269
OS 54.74457428 -38.6058918
OS 54.732555 -38.61143916
OS 54.73163044 -38.61236372
OS 54.7279322 -38.61421284
OS 54.72238484 -38.61883564
OS 54.71498836 -38.62345844
OS 54.70759188 -38.62993036
OS 54.7001954 -38.6382514
OS 54.69187436 -38.64657244
OS 54.68540244 -38.6567426
OS 54.61143764 -38.64657244
OS 54.67338316 -38.31742908
OS 54.9914318 -38.31742908
OS 54.9914318 -38.39231844
OE
OB 49.95350436 -38.72331092 I
OS 50.040413 -38.72331092
OS 50.040413 -38.7954266
OS 49.95350436 -38.7954266
OS 49.95350436 -38.94890356
OS 49.87491676 -38.94890356
OS 49.87491676 -38.7954266
OS 49.5966242 -38.7954266
OS 49.5966242 -38.72331092
OS 49.88970972 -38.30910804
OS 49.95350436 -38.30910804
OS 49.95350436 -38.72331092
OE
OB 50.1467374 -38.95999828 I
OS 50.08386732 -38.95999828
OS 50.26970388 -38.29801332
OS 50.33257396 -38.29801332
OS 50.1467374 -38.95999828
OE
OB 49.35346492 -38.30725892 I
OS 49.3608614 -38.30818348
OS 49.370107 -38.30910804
OS 49.38027716 -38.31095716
OS 49.39044732 -38.31280628
OS 49.41448588 -38.3192782
OS 49.43852444 -38.3285238
OS 49.45054372 -38.33407116
OS 49.462563 -38.34054308
OS 49.47365772 -38.34886412
OS 49.48382788 -38.35810972
OS 49.48475244 -38.35903428
OS 49.48660156 -38.35995884
OS 49.48845068 -38.36365708
OS 49.49214892 -38.36735532
OS 49.49677172 -38.37197812
OS 49.50139452 -38.37845004
OS 49.50601732 -38.38492196
OS 49.51156468 -38.393243
OS 49.52081028 -38.41080964
OS 49.53005588 -38.43299908
OS 49.53375412 -38.4440938
OS 49.53560324 -38.45703764
OS 49.53745236 -38.46998148
OS 49.53837692 -38.48384988
OS 49.53837692 -38.485699
OS 49.53837692 -38.4903218
OS 49.53745236 -38.49771828
OS 49.5365278 -38.50788844
OS 49.53467868 -38.51898316
OS 49.53098044 -38.531927
OS 49.5272822 -38.5457954
OS 49.52173484 -38.5596638
OS 49.52081028 -38.56151292
OS 49.51896116 -38.56613572
OS 49.51526292 -38.5735322
OS 49.50971556 -38.58370236
OS 49.50231908 -38.59479708
OS 49.49307348 -38.60866548
OS 49.48197876 -38.62253388
OS 49.46903492 -38.6382514
OS 49.4671858 -38.64010052
OS 49.462563 -38.64564788
OS 49.4579402 -38.65027068
OS 49.4533174 -38.65489348
OS 49.44777004 -38.66044084
OS 49.44037356 -38.66783732
OS 49.43297708 -38.6752338
OS 49.42373148 -38.68355484
OS 49.41448588 -38.69280044
OS 49.40339116 -38.7029706
OS 49.39137188 -38.71314076
OS 49.37842804 -38.72516004
OS 49.36363508 -38.73717932
OS 49.34884212 -38.75012316
OS 49.34791756 -38.75104772
OS 49.34606844 -38.75289684
OS 49.3423702 -38.75567052
OS 49.3377474 -38.75936876
OS 49.33220004 -38.76491612
OS 49.32572812 -38.77046348
OS 49.31093516 -38.78248276
OS 49.29521764 -38.79635116
OS 49.28042468 -38.81021956
OS 49.26748084 -38.82223884
OS 49.26193348 -38.82686164
OS 49.25731068 -38.83148444
OS 49.25638612 -38.832409
OS 49.25361244 -38.83518268
OS 49.2499142 -38.83888092
OS 49.2452914 -38.84442828
OS 49.2406686 -38.8509002
OS 49.23512124 -38.85737212
OS 49.22402652 -38.87308964
OS 49.53930148 -38.87308964
OS 49.53930148 -38.94890356
OS 49.11492844 -38.94890356
OS 49.11492844 -38.947979
OS 49.11492844 -38.94428076
OS 49.11492844 -38.9387334
OS 49.115853 -38.93133692
OS 49.11677756 -38.92301588
OS 49.11862668 -38.91377028
OS 49.1204758 -38.90452468
OS 49.12417404 -38.89435452
OS 49.12417404 -38.89342996
OS 49.1250986 -38.8925054
OS 49.12694772 -38.88695804
OS 49.13064596 -38.878637
OS 49.13619332 -38.86754228
OS 49.1435898 -38.85459844
OS 49.1528354 -38.83980548
OS 49.16300556 -38.82501252
OS 49.1759494 -38.809295
OS 49.1759494 -38.80837044
OS 49.17779852 -38.80744588
OS 49.18242132 -38.80189852
OS 49.19074236 -38.79357748
OS 49.20276164 -38.7815582
OS 49.21663004 -38.7676898
OS 49.23419668 -38.75104772
OS 49.25546156 -38.73255652
OS 49.27857556 -38.71314076
OS 49.27950012 -38.7122162
OS 49.28319836 -38.70944252
OS 49.28874572 -38.70481972
OS 49.29521764 -38.69927236
OS 49.30353868 -38.69187588
OS 49.31370884 -38.68355484
OS 49.323879 -38.67430924
OS 49.33589828 -38.66413908
OS 49.35901228 -38.64194964
OS 49.38212628 -38.6197602
OS 49.393221 -38.60866548
OS 49.40339116 -38.59757076
OS 49.41263676 -38.5874006
OS 49.42003324 -38.57723044
OS 49.42003324 -38.57630588
OS 49.42188236 -38.57538132
OS 49.42373148 -38.57260764
OS 49.4255806 -38.5689094
OS 49.43205252 -38.55873924
OS 49.439449 -38.54671996
OS 49.44592092 -38.531927
OS 49.45239284 -38.51620948
OS 49.45609108 -38.49864284
OS 49.4579402 -38.48200076
OS 49.4579402 -38.4810762
OS 49.4579402 -38.48015164
OS 49.45701564 -38.47460428
OS 49.45609108 -38.46535868
OS 49.4533174 -38.45518852
OS 49.44961916 -38.44224468
OS 49.44314724 -38.42930084
OS 49.4348262 -38.416357
OS 49.42373148 -38.40341316
OS 49.42188236 -38.40156404
OS 49.41725956 -38.3978658
OS 49.41078764 -38.393243
OS 49.40061748 -38.38677108
OS 49.38767364 -38.38122372
OS 49.37288068 -38.37567636
OS 49.35531404 -38.37197812
OS 49.33589828 -38.37105356
OS 49.33035092 -38.37105356
OS 49.32665268 -38.37197812
OS 49.31555796 -38.37290268
OS 49.30261412 -38.37567636
OS 49.28874572 -38.3793746
OS 49.2730282 -38.38584652
OS 49.25823524 -38.39416756
OS 49.24436684 -38.40526228
OS 49.24251772 -38.4071114
OS 49.23881948 -38.4117342
OS 49.23327212 -38.41913068
OS 49.22772476 -38.4302254
OS 49.22125284 -38.44316924
OS 49.21570548 -38.45981132
OS 49.21200724 -38.47830252
OS 49.21015812 -38.4995674
OS 49.1297214 -38.49124636
OS 49.1297214 -38.4903218
OS 49.13064596 -38.48754812
OS 49.13064596 -38.48292532
OS 49.13157052 -38.4764534
OS 49.13341964 -38.46905692
OS 49.13526876 -38.46073588
OS 49.13804244 -38.45056572
OS 49.14081612 -38.44039556
OS 49.1482126 -38.41820612
OS 49.15930732 -38.39601668
OS 49.16577924 -38.38492196
OS 49.17410028 -38.37382724
OS 49.18242132 -38.36365708
OS 49.19166692 -38.35441148
OS 49.19259148 -38.35348692
OS 49.1944406 -38.35256236
OS 49.19721428 -38.34978868
OS 49.20183708 -38.347015
OS 49.20738444 -38.34331676
OS 49.21385636 -38.33961852
OS 49.22125284 -38.33499572
OS 49.23049844 -38.33037292
OS 49.2406686 -38.32575012
OS 49.25176332 -38.32112732
OS 49.2637826 -38.31742908
OS 49.27672644 -38.31373084
OS 49.29059484 -38.31095716
OS 49.3053878 -38.30818348
OS 49.32110532 -38.30725892
OS 49.3377474 -38.30633436
OS 49.346993 -38.30633436
OS 49.35346492 -38.30725892
OE
OB 48.67576244 -38.94890356 I
OS 48.59717484 -38.94890356
OS 48.59717484 -38.4487166
OS 48.59625028 -38.44964116
OS 48.59162748 -38.4533394
OS 48.58608012 -38.45888676
OS 48.57683452 -38.46535868
OS 48.56666436 -38.47367972
OS 48.55372052 -38.48292532
OS 48.53892756 -38.49309548
OS 48.52228548 -38.50326564
OS 48.52136092 -38.50326564
OS 48.52043636 -38.5041902
OS 48.514889 -38.50788844
OS 48.5056434 -38.51251124
OS 48.49454868 -38.5180586
OS 48.48160484 -38.52453052
OS 48.46773644 -38.53100244
OS 48.45386804 -38.53747436
OS 48.43999964 -38.54302172
OS 48.43999964 -38.4672078
OS 48.4409242 -38.4672078
OS 48.44277332 -38.46535868
OS 48.44647156 -38.46443412
OS 48.45109436 -38.46166044
OS 48.45664172 -38.45888676
OS 48.46311364 -38.45518852
OS 48.47883116 -38.44594292
OS 48.49732236 -38.43577276
OS 48.51581356 -38.42282892
OS 48.53522932 -38.40803596
OS 48.55464508 -38.39231844
OS 48.55556964 -38.39139388
OS 48.5564942 -38.39046932
OS 48.55926788 -38.38769564
OS 48.56296612 -38.38492196
OS 48.57128716 -38.37567636
OS 48.58238188 -38.36458164
OS 48.5934766 -38.3516378
OS 48.60549588 -38.33684484
OS 48.61566604 -38.32205188
OS 48.62491164 -38.30633436
OS 48.67576244 -38.30633436
OS 48.67576244 -38.94890356
OE
OB 48.9032042 -38.95999828 I
OS 48.84033412 -38.95999828
OS 49.02617068 -38.29801332
OS 49.08904076 -38.29801332
OS 48.9032042 -38.95999828
OE
OB 50.59699812 -38.30725892 I
OS 50.6043946 -38.30818348
OS 50.6136402 -38.30910804
OS 50.62381036 -38.31095716
OS 50.63398052 -38.31280628
OS 50.65801908 -38.3192782
OS 50.68205764 -38.3285238
OS 50.69407692 -38.33407116
OS 50.7060962 -38.34054308
OS 50.71719092 -38.34886412
OS 50.72736108 -38.35810972
OS 50.72828564 -38.35903428
OS 50.73013476 -38.35995884
OS 50.73198388 -38.36365708
OS 50.73568212 -38.36735532
OS 50.74030492 -38.37197812
OS 50.74492772 -38.37845004
OS 50.74955052 -38.38492196
OS 50.75509788 -38.393243
OS 50.76434348 -38.41080964
OS 50.77358908 -38.43299908
OS 50.77728732 -38.4440938
OS 50.77913644 -38.45703764
OS 50.78098556 -38.46998148
OS 50.78191012 -38.48384988
OS 50.78191012 -38.485699
OS 50.78191012 -38.4903218
OS 50.78098556 -38.49771828
OS 50.780061 -38.50788844
OS 50.77821188 -38.51898316
OS 50.77451364 -38.531927
OS 50.7708154 -38.5457954
OS 50.76526804 -38.5596638
OS 50.76434348 -38.56151292
OS 50.76249436 -38.56613572
OS 50.75879612 -38.5735322
OS 50.75324876 -38.58370236
OS 50.74585228 -38.59479708
OS 50.73660668 -38.60866548
OS 50.72551196 -38.62253388
OS 50.71256812 -38.6382514
OS 50.710719 -38.64010052
OS 50.7060962 -38.64564788
OS 50.7014734 -38.65027068
OS 50.6968506 -38.65489348
OS 50.69130324 -38.66044084
OS 50.68390676 -38.66783732
OS 50.67651028 -38.6752338
OS 50.66726468 -38.68355484
OS 50.65801908 -38.69280044
OS 50.64692436 -38.7029706
OS 50.63490508 -38.71314076
OS 50.62196124 -38.72516004
OS 50.60716828 -38.73717932
OS 50.59237532 -38.75012316
OS 50.59145076 -38.75104772
OS 50.58960164 -38.75289684
OS 50.5859034 -38.75567052
OS 50.5812806 -38.75936876
OS 50.57573324 -38.76491612
OS 50.56926132 -38.77046348
OS 50.55446836 -38.78248276
OS 50.53875084 -38.79635116
OS 50.52395788 -38.81021956
OS 50.51101404 -38.82223884
OS 50.50546668 -38.82686164
OS 50.50084388 -38.83148444
OS 50.49991932 -38.832409
OS 50.49714564 -38.83518268
OS 50.4934474 -38.83888092
OS 50.4888246 -38.84442828
OS 50.4842018 -38.8509002
OS 50.47865444 -38.85737212
OS 50.46755972 -38.87308964
OS 50.78283468 -38.87308964
OS 50.78283468 -38.94890356
OS 50.35846164 -38.94890356
OS 50.35846164 -38.947979
OS 50.35846164 -38.94428076
OS 50.35846164 -38.9387334
OS 50.3593862 -38.93133692
OS 50.36031076 -38.92301588
OS 50.36215988 -38.91377028
OS 50.364009 -38.90452468
OS 50.36770724 -38.89435452
OS 50.36770724 -38.89342996
OS 50.3686318 -38.8925054
OS 50.37048092 -38.88695804
OS 50.37417916 -38.878637
OS 50.37972652 -38.86754228
OS 50.387123 -38.85459844
OS 50.3963686 -38.83980548
OS 50.40653876 -38.82501252
OS 50.4194826 -38.809295
OS 50.4194826 -38.80837044
OS 50.42133172 -38.80744588
OS 50.42595452 -38.80189852
OS 50.43427556 -38.79357748
OS 50.44629484 -38.7815582
OS 50.46016324 -38.7676898
OS 50.47772988 -38.75104772
OS 50.49899476 -38.73255652
OS 50.52210876 -38.71314076
OS 50.52303332 -38.7122162
OS 50.52673156 -38.70944252
OS 50.53227892 -38.70481972
OS 50.53875084 -38.69927236
OS 50.54707188 -38.69187588
OS 50.55724204 -38.68355484
OS 50.5674122 -38.67430924
OS 50.57943148 -38.66413908
OS 50.60254548 -38.64194964
OS 50.62565948 -38.6197602
OS 50.6367542 -38.60866548
OS 50.64692436 -38.59757076
OS 50.65616996 -38.5874006
OS 50.66356644 -38.57723044
OS 50.66356644 -38.57630588
OS 50.66541556 -38.57538132
OS 50.66726468 -38.57260764
OS 50.6691138 -38.5689094
OS 50.67558572 -38.55873924
OS 50.6829822 -38.54671996
OS 50.68945412 -38.531927
OS 50.69592604 -38.51620948
OS 50.69962428 -38.49864284
OS 50.7014734 -38.48200076
OS 50.7014734 -38.4810762
OS 50.7014734 -38.48015164
OS 50.70054884 -38.47460428
OS 50.69962428 -38.46535868
OS 50.6968506 -38.45518852
OS 50.69315236 -38.44224468
OS 50.68668044 -38.42930084
OS 50.6783594 -38.416357
OS 50.66726468 -38.40341316
OS 50.66541556 -38.40156404
OS 50.66079276 -38.3978658
OS 50.65432084 -38.393243
OS 50.64415068 -38.38677108
OS 50.63120684 -38.38122372
OS 50.61641388 -38.37567636
OS 50.59884724 -38.37197812
OS 50.57943148 -38.37105356
OS 50.57388412 -38.37105356
OS 50.57018588 -38.37197812
OS 50.55909116 -38.37290268
OS 50.54614732 -38.37567636
OS 50.53227892 -38.3793746
OS 50.5165614 -38.38584652
OS 50.50176844 -38.39416756
OS 50.48790004 -38.40526228
OS 50.48605092 -38.4071114
OS 50.48235268 -38.4117342
OS 50.47680532 -38.41913068
OS 50.47125796 -38.4302254
OS 50.46478604 -38.44316924
OS 50.45923868 -38.45981132
OS 50.45554044 -38.47830252
OS 50.45369132 -38.4995674
OS 50.3732546 -38.49124636
OS 50.3732546 -38.4903218
OS 50.37417916 -38.48754812
OS 50.37417916 -38.48292532
OS 50.37510372 -38.4764534
OS 50.37695284 -38.46905692
OS 50.37880196 -38.46073588
OS 50.38157564 -38.45056572
OS 50.38434932 -38.44039556
OS 50.3917458 -38.41820612
OS 50.40284052 -38.39601668
OS 50.40931244 -38.38492196
OS 50.41763348 -38.37382724
OS 50.42595452 -38.36365708
OS 50.43520012 -38.35441148
OS 50.43612468 -38.35348692
OS 50.4379738 -38.35256236
OS 50.44074748 -38.34978868
OS 50.44537028 -38.347015
OS 50.45091764 -38.34331676
OS 50.45738956 -38.33961852
OS 50.46478604 -38.33499572
OS 50.47403164 -38.33037292
OS 50.4842018 -38.32575012
OS 50.49529652 -38.32112732
OS 50.5073158 -38.31742908
OS 50.52025964 -38.31373084
OS 50.53412804 -38.31095716
OS 50.548921 -38.30818348
OS 50.56463852 -38.30725892
OS 50.5812806 -38.30633436
OS 50.5905262 -38.30633436
OS 50.59699812 -38.30725892
OE
OB 51.0944114 -38.30725892 I
OS 51.10643068 -38.30910804
OS 51.12029908 -38.31188172
OS 51.13509204 -38.31557996
OS 51.15080956 -38.32020276
OS 51.16560252 -38.32759924
OS 51.16652708 -38.32759924
OS 51.16745164 -38.3285238
OS 51.17207444 -38.33129748
OS 51.17947092 -38.33592028
OS 51.18871652 -38.3423922
OS 51.19888668 -38.3516378
OS 51.2099814 -38.36180796
OS 51.22015156 -38.37382724
OS 51.23032172 -38.38769564
OS 51.23124628 -38.38954476
OS 51.23494452 -38.39416756
OS 51.23864276 -38.4024886
OS 51.24511468 -38.41450788
OS 51.25066204 -38.42837628
OS 51.25805852 -38.4440938
OS 51.26453044 -38.462585
OS 51.2700778 -38.48292532
OS 51.2700778 -38.48384988
OS 51.27100236 -38.485699
OS 51.27192692 -38.48847268
OS 51.27285148 -38.49309548
OS 51.27377604 -38.49864284
OS 51.2747006 -38.50511476
OS 51.27654972 -38.5134358
OS 51.27747428 -38.5226814
OS 51.2793234 -38.53285156
OS 51.28024796 -38.54394628
OS 51.28117252 -38.55689012
OS 51.28302164 -38.56983396
OS 51.2839462 -38.58462692
OS 51.2839462 -38.59941988
OS 51.28487076 -38.61606196
OS 51.28487076 -38.6336286
OS 51.28487076 -38.63455316
OS 51.28487076 -38.6382514
OS 51.28487076 -38.64472332
OS 51.28487076 -38.6521198
OS 51.2839462 -38.66228996
OS 51.2839462 -38.67338468
OS 51.28302164 -38.68540396
OS 51.28209708 -38.6983478
OS 51.2793234 -38.72793372
OS 51.2747006 -38.7584442
OS 51.26915324 -38.78803012
OS 51.265455 -38.80189852
OS 51.2608322 -38.81576692
OS 51.2608322 -38.81669148
OS 51.25990764 -38.8185406
OS 51.25805852 -38.82223884
OS 51.2562094 -38.82686164
OS 51.25436028 -38.83333356
OS 51.25066204 -38.83980548
OS 51.24326556 -38.855523
OS 51.23401996 -38.87216508
OS 51.22200068 -38.89065628
OS 51.20813228 -38.90729836
OS 51.1914902 -38.92301588
OS 51.19056564 -38.92301588
OS 51.18964108 -38.924865
OS 51.1868674 -38.92671412
OS 51.18316916 -38.92856324
OS 51.17854636 -38.93133692
OS 51.17392356 -38.93503516
OS 51.16005516 -38.94150708
OS 51.14341308 -38.947979
OS 51.12399732 -38.95445092
OS 51.10088332 -38.95814916
OS 51.0759202 -38.95999828
OS 51.0666746 -38.95999828
OS 51.06020268 -38.95907372
OS 51.0528062 -38.95814916
OS 51.0435606 -38.95630004
OS 51.03339044 -38.95445092
OS 51.02229572 -38.95167724
OS 51.011201 -38.947979
OS 50.99918172 -38.94428076
OS 50.98716244 -38.9387334
OS 50.97514316 -38.93226148
OS 50.96312388 -38.924865
OS 50.9511046 -38.9156194
OS 50.94000988 -38.90544924
OS 50.92983972 -38.89435452
OS 50.92891516 -38.89342996
OS 50.92706604 -38.89065628
OS 50.92429236 -38.88603348
OS 50.91966956 -38.878637
OS 50.91504676 -38.87031596
OS 50.91042396 -38.85922124
OS 50.90395204 -38.8462774
OS 50.89840468 -38.83148444
OS 50.89285732 -38.81484236
OS 50.88730996 -38.7954266
OS 50.8817626 -38.77416172
OS 50.8771398 -38.75012316
OS 50.872517 -38.72423548
OS 50.86974332 -38.69649868
OS 50.8678942 -38.6659882
OS 50.86696964 -38.6336286
OS 50.86696964 -38.63270404
OS 50.86696964 -38.6290058
OS 50.86696964 -38.62253388
OS 50.86696964 -38.6151374
OS 50.8678942 -38.60496724
OS 50.8678942 -38.59387252
OS 50.86881876 -38.58185324
OS 50.86974332 -38.56798484
OS 50.872517 -38.53932348
OS 50.8771398 -38.508813
OS 50.88268716 -38.47830252
OS 50.8863854 -38.46443412
OS 50.89008364 -38.45056572
OS 50.89008364 -38.44964116
OS 50.8910082 -38.44779204
OS 50.89285732 -38.4440938
OS 50.89470644 -38.439471
OS 50.89655556 -38.43299908
OS 50.9002538 -38.42652716
OS 50.90765028 -38.41080964
OS 50.91689588 -38.39416756
OS 50.92891516 -38.37660092
OS 50.94278356 -38.35903428
OS 50.95942564 -38.34424132
OS 50.9603502 -38.34424132
OS 50.96127476 -38.3423922
OS 50.96404844 -38.34054308
OS 50.96774668 -38.33869396
OS 50.97236948 -38.33499572
OS 50.97791684 -38.33222204
OS 50.99178524 -38.32482556
OS 51.00842732 -38.31835364
OS 51.02784308 -38.31188172
OS 51.05095708 -38.30818348
OS 51.0759202 -38.30633436
OS 51.08424124 -38.30633436
OS 51.0944114 -38.30725892
OE
OB 51.59182468 -38.30725892 I
OS 51.59922116 -38.30818348
OS 51.60846676 -38.30910804
OS 51.61863692 -38.31095716
OS 51.62880708 -38.31280628
OS 51.65284564 -38.3192782
OS 51.6768842 -38.3285238
OS 51.68890348 -38.33407116
OS 51.70092276 -38.34054308
OS 51.71201748 -38.34886412
OS 51.72218764 -38.35810972
OS 51.7231122 -38.35903428
OS 51.72496132 -38.35995884
OS 51.72681044 -38.36365708
OS 51.73050868 -38.36735532
OS 51.73513148 -38.37197812
OS 51.73975428 -38.37845004
OS 51.74437708 -38.38492196
OS 51.74992444 -38.393243
OS 51.75917004 -38.41080964
OS 51.76841564 -38.43299908
OS 51.77211388 -38.4440938
OS 51.773963 -38.45703764
OS 51.77581212 -38.46998148
OS 51.77673668 -38.48384988
OS 51.77673668 -38.485699
OS 51.77673668 -38.4903218
OS 51.77581212 -38.49771828
OS 51.77488756 -38.50788844
OS 51.77303844 -38.51898316
OS 51.7693402 -38.531927
OS 51.76564196 -38.5457954
OS 51.7600946 -38.5596638
OS 51.75917004 -38.56151292
OS 51.75732092 -38.56613572
OS 51.75362268 -38.5735322
OS 51.74807532 -38.58370236
OS 51.74067884 -38.59479708
OS 51.73143324 -38.60866548
OS 51.72033852 -38.62253388
OS 51.70739468 -38.6382514
OS 51.70554556 -38.64010052
OS 51.70092276 -38.64564788
OS 51.69629996 -38.65027068
OS 51.69167716 -38.65489348
OS 51.6861298 -38.66044084
OS 51.67873332 -38.66783732
OS 51.67133684 -38.6752338
OS 51.66209124 -38.68355484
OS 51.65284564 -38.69280044
OS 51.64175092 -38.7029706
OS 51.62973164 -38.71314076
OS 51.6167878 -38.72516004
OS 51.60199484 -38.73717932
OS 51.58720188 -38.75012316
OS 51.58627732 -38.75104772
OS 51.5844282 -38.75289684
OS 51.58072996 -38.75567052
OS 51.57610716 -38.75936876
OS 51.5705598 -38.76491612
OS 51.56408788 -38.77046348
OS 51.54929492 -38.78248276
OS 51.5335774 -38.79635116
OS 51.51878444 -38.81021956
OS 51.5058406 -38.82223884
OS 51.50029324 -38.82686164
OS 51.49567044 -38.83148444
OS 51.49474588 -38.832409
OS 51.4919722 -38.83518268
OS 51.48827396 -38.83888092
OS 51.48365116 -38.84442828
OS 51.47902836 -38.8509002
OS 51.473481 -38.85737212
OS 51.46238628 -38.87308964
OS 51.77766124 -38.87308964
OS 51.77766124 -38.94890356
OS 51.3532882 -38.94890356
OS 51.3532882 -38.947979
OS 51.3532882 -38.94428076
OS 51.3532882 -38.9387334
OS 51.35421276 -38.93133692
OS 51.35513732 -38.92301588
OS 51.35698644 -38.91377028
OS 51.35883556 -38.90452468
OS 51.3625338 -38.89435452
OS 51.3625338 -38.89342996
OS 51.36345836 -38.8925054
OS 51.36530748 -38.88695804
OS 51.36900572 -38.878637
OS 51.37455308 -38.86754228
OS 51.38194956 -38.85459844
OS 51.39119516 -38.83980548
OS 51.40136532 -38.82501252
OS 51.41430916 -38.809295
OS 51.41430916 -38.80837044
OS 51.41615828 -38.80744588
OS 51.42078108 -38.80189852
OS 51.42910212 -38.79357748
OS 51.4411214 -38.7815582
OS 51.4549898 -38.7676898
OS 51.47255644 -38.75104772
OS 51.49382132 -38.73255652
OS 51.51693532 -38.71314076
OS 51.51785988 -38.7122162
OS 51.52155812 -38.70944252
OS 51.52710548 -38.70481972
OS 51.5335774 -38.69927236
OS 51.54189844 -38.69187588
OS 51.5520686 -38.68355484
OS 51.56223876 -38.67430924
OS 51.57425804 -38.66413908
OS 51.59737204 -38.64194964
OS 51.62048604 -38.6197602
OS 51.63158076 -38.60866548
OS 51.64175092 -38.59757076
OS 51.65099652 -38.5874006
OS 51.658393 -38.57723044
OS 51.658393 -38.57630588
OS 51.66024212 -38.57538132
OS 51.66209124 -38.57260764
OS 51.66394036 -38.5689094
OS 51.67041228 -38.55873924
OS 51.67780876 -38.54671996
OS 51.68428068 -38.531927
OS 51.6907526 -38.51620948
OS 51.69445084 -38.49864284
OS 51.69629996 -38.48200076
OS 51.69629996 -38.4810762
OS 51.69629996 -38.48015164
OS 51.6953754 -38.47460428
OS 51.69445084 -38.46535868
OS 51.69167716 -38.45518852
OS 51.68797892 -38.44224468
OS 51.681507 -38.42930084
OS 51.67318596 -38.416357
OS 51.66209124 -38.40341316
OS 51.66024212 -38.40156404
OS 51.65561932 -38.3978658
OS 51.6491474 -38.393243
OS 51.63897724 -38.38677108
OS 51.6260334 -38.38122372
OS 51.61124044 -38.37567636
OS 51.5936738 -38.37197812
OS 51.57425804 -38.37105356
OS 51.56871068 -38.37105356
OS 51.56501244 -38.37197812
OS 51.55391772 -38.37290268
OS 51.54097388 -38.37567636
OS 51.52710548 -38.3793746
OS 51.51138796 -38.38584652
OS 51.496595 -38.39416756
OS 51.4827266 -38.40526228
OS 51.48087748 -38.4071114
OS 51.47717924 -38.4117342
OS 51.47163188 -38.41913068
OS 51.46608452 -38.4302254
OS 51.4596126 -38.44316924
OS 51.45406524 -38.45981132
OS 51.450367 -38.47830252
OS 51.44851788 -38.4995674
OS 51.36808116 -38.49124636
OS 51.36808116 -38.4903218
OS 51.36900572 -38.48754812
OS 51.36900572 -38.48292532
OS 51.36993028 -38.4764534
OS 51.3717794 -38.46905692
OS 51.37362852 -38.46073588
OS 51.3764022 -38.45056572
OS 51.37917588 -38.44039556
OS 51.38657236 -38.41820612
OS 51.39766708 -38.39601668
OS 51.404139 -38.38492196
OS 51.41246004 -38.37382724
OS 51.42078108 -38.36365708
OS 51.43002668 -38.35441148
OS 51.43095124 -38.35348692
OS 51.43280036 -38.35256236
OS 51.43557404 -38.34978868
OS 51.44019684 -38.347015
OS 51.4457442 -38.34331676
OS 51.45221612 -38.33961852
OS 51.4596126 -38.33499572
OS 51.4688582 -38.33037292
OS 51.47902836 -38.32575012
OS 51.49012308 -38.32112732
OS 51.50214236 -38.31742908
OS 51.5150862 -38.31373084
OS 51.5289546 -38.31095716
OS 51.54374756 -38.30818348
OS 51.55946508 -38.30725892
OS 51.57610716 -38.30633436
OS 51.58535276 -38.30633436
OS 51.59182468 -38.30725892
OE
OB 52.08184148 -38.30725892 I
OS 52.09386076 -38.30910804
OS 52.10865372 -38.31188172
OS 52.1252958 -38.31650452
OS 52.14193788 -38.32205188
OS 52.15857996 -38.32944836
OS 52.15950452 -38.32944836
OS 52.16042908 -38.33037292
OS 52.16597644 -38.3331466
OS 52.17429748 -38.33869396
OS 52.18354308 -38.34516588
OS 52.1946378 -38.35441148
OS 52.20573252 -38.36458164
OS 52.21682724 -38.37660092
OS 52.22607284 -38.39046932
OS 52.2269974 -38.39231844
OS 52.22977108 -38.39694124
OS 52.23346932 -38.40526228
OS 52.23809212 -38.41543244
OS 52.24271492 -38.42745172
OS 52.24641316 -38.44132012
OS 52.24918684 -38.45703764
OS 52.2501114 -38.47275516
OS 52.2501114 -38.47460428
OS 52.2501114 -38.48015164
OS 52.24918684 -38.48754812
OS 52.24733772 -38.49771828
OS 52.24456404 -38.50973756
OS 52.23994124 -38.5226814
OS 52.23439388 -38.53562524
OS 52.2269974 -38.54856908
OS 52.22607284 -38.5504182
OS 52.22329916 -38.55411644
OS 52.2177518 -38.56058836
OS 52.21035532 -38.56798484
OS 52.20110972 -38.57630588
OS 52.190015 -38.58555148
OS 52.17707116 -38.59387252
OS 52.16135364 -38.60219356
OS 52.1622782 -38.60219356
OS 52.16412732 -38.60311812
OS 52.166901 -38.60404268
OS 52.17059924 -38.60496724
OS 52.1807694 -38.60866548
OS 52.19371324 -38.61421284
OS 52.2085062 -38.62160932
OS 52.22329916 -38.63085492
OS 52.23716756 -38.6428742
OS 52.2501114 -38.6567426
OS 52.25103596 -38.65859172
OS 52.2547342 -38.66413908
OS 52.26028156 -38.67338468
OS 52.26582892 -38.68540396
OS 52.27137628 -38.70019692
OS 52.27692364 -38.71776356
OS 52.28062188 -38.73810388
OS 52.28154644 -38.76029332
OS 52.28154644 -38.76121788
OS 52.28154644 -38.76399156
OS 52.28154644 -38.76861436
OS 52.28062188 -38.77416172
OS 52.27969732 -38.7815582
OS 52.2778482 -38.78987924
OS 52.27599908 -38.79912484
OS 52.27414996 -38.809295
OS 52.26675348 -38.83148444
OS 52.26120612 -38.84350372
OS 52.25565876 -38.85459844
OS 52.24826228 -38.86661772
OS 52.23994124 -38.878637
OS 52.23069564 -38.89065628
OS 52.21960092 -38.901751
OS 52.21867636 -38.90267556
OS 52.21682724 -38.90452468
OS 52.213129 -38.90729836
OS 52.2085062 -38.9109966
OS 52.20295884 -38.9156194
OS 52.19556236 -38.9202422
OS 52.18724132 -38.92578956
OS 52.17707116 -38.93041236
OS 52.166901 -38.93595972
OS 52.15488172 -38.94150708
OS 52.14286244 -38.94612988
OS 52.12899404 -38.95075268
OS 52.11420108 -38.95445092
OS 52.09848356 -38.9572246
OS 52.08276604 -38.95907372
OS 52.0651994 -38.95999828
OS 52.05687836 -38.95999828
OS 52.051331 -38.95907372
OS 52.04393452 -38.95814916
OS 52.03561348 -38.9572246
OS 52.02636788 -38.95537548
OS 52.01619772 -38.95352636
OS 51.99400828 -38.947979
OS 51.97089428 -38.9387334
OS 51.958875 -38.93318604
OS 51.94778028 -38.92671412
OS 51.93668556 -38.91839308
OS 51.92559084 -38.91007204
OS 51.92466628 -38.90914748
OS 51.92281716 -38.90729836
OS 51.92004348 -38.90452468
OS 51.9172698 -38.90082644
OS 51.912647 -38.89620364
OS 51.9080242 -38.88973172
OS 51.90247684 -38.8832598
OS 51.89692948 -38.87493876
OS 51.89138212 -38.86569316
OS 51.88583476 -38.85644756
OS 51.8756646 -38.83425812
OS 51.86734356 -38.80837044
OS 51.86456988 -38.79450204
OS 51.86272076 -38.77970908
OS 51.94130836 -38.76953892
OS 51.94130836 -38.77046348
OS 51.94223292 -38.7723126
OS 51.94315748 -38.77601084
OS 51.94408204 -38.78063364
OS 51.9450066 -38.786181
OS 51.94685572 -38.79265292
OS 51.95147852 -38.80652132
OS 51.95795044 -38.8231634
OS 51.96627148 -38.83888092
OS 51.97551708 -38.85367388
OS 51.9866118 -38.86661772
OS 51.98846092 -38.86754228
OS 51.99215916 -38.87124052
OS 51.99955564 -38.87586332
OS 52.00880124 -38.88048612
OS 52.01989596 -38.88603348
OS 52.03376436 -38.89065628
OS 52.04948188 -38.89435452
OS 52.06612396 -38.89527908
OS 52.07167132 -38.89527908
OS 52.07536956 -38.89435452
OS 52.08553972 -38.89342996
OS 52.09848356 -38.89065628
OS 52.11327652 -38.88603348
OS 52.12899404 -38.87956156
OS 52.14471156 -38.87031596
OS 52.15950452 -38.85737212
OS 52.16135364 -38.855523
OS 52.16597644 -38.84997564
OS 52.1715238 -38.8416546
OS 52.17892028 -38.83055988
OS 52.18631676 -38.81669148
OS 52.19186412 -38.80097396
OS 52.19648692 -38.78248276
OS 52.19833604 -38.76214244
OS 52.19833604 -38.76121788
OS 52.19833604 -38.75936876
OS 52.19833604 -38.75659508
OS 52.19741148 -38.75289684
OS 52.19648692 -38.74272668
OS 52.19371324 -38.7307074
OS 52.190015 -38.71591444
OS 52.18354308 -38.70112148
OS 52.17429748 -38.68632852
OS 52.1622782 -38.67246012
OS 52.16042908 -38.670611
OS 52.15580628 -38.66691276
OS 52.1484098 -38.6613654
OS 52.13823964 -38.65489348
OS 52.1252958 -38.64842156
OS 52.10957828 -38.6428742
OS 52.09201164 -38.63917596
OS 52.07259588 -38.63732684
OS 52.06427484 -38.63732684
OS 52.05780292 -38.6382514
OS 52.04948188 -38.63917596
OS 52.04023628 -38.64102508
OS 52.02914156 -38.6428742
OS 52.01712228 -38.64564788
OS 52.02636788 -38.57630588
OS 52.03099068 -38.57630588
OS 52.03468892 -38.57723044
OS 52.0467082 -38.57723044
OS 52.05687836 -38.57538132
OS 52.06889764 -38.5735322
OS 52.08276604 -38.57075852
OS 52.09848356 -38.56613572
OS 52.11327652 -38.5596638
OS 52.12899404 -38.55134276
OS 52.1299186 -38.55134276
OS 52.13084316 -38.5504182
OS 52.13546596 -38.54671996
OS 52.14193788 -38.54024804
OS 52.14933436 -38.531927
OS 52.15673084 -38.51990772
OS 52.16320276 -38.50603932
OS 52.16782556 -38.4903218
OS 52.16967468 -38.4810762
OS 52.16967468 -38.47090604
OS 52.16967468 -38.46998148
OS 52.16967468 -38.46905692
OS 52.16967468 -38.46350956
OS 52.16782556 -38.45611308
OS 52.16597644 -38.44594292
OS 52.1622782 -38.4348482
OS 52.1576554 -38.42282892
OS 52.15025892 -38.41080964
OS 52.14008876 -38.39971492
OS 52.1391642 -38.39879036
OS 52.1345414 -38.39509212
OS 52.12806948 -38.39046932
OS 52.11974844 -38.38492196
OS 52.10865372 -38.38029916
OS 52.09570988 -38.37567636
OS 52.08091692 -38.37197812
OS 52.06427484 -38.37105356
OS 52.05687836 -38.37105356
OS 52.04855732 -38.37290268
OS 52.0374626 -38.3747518
OS 52.02544332 -38.37845004
OS 52.01342404 -38.38307284
OS 52.0004802 -38.39046932
OS 51.98846092 -38.39971492
OS 51.98753636 -38.40063948
OS 51.98383812 -38.40526228
OS 51.97829076 -38.4117342
OS 51.97181884 -38.4209798
OS 51.96534692 -38.43299908
OS 51.958875 -38.44779204
OS 51.95332764 -38.46535868
OS 51.9496294 -38.485699
OS 51.8710418 -38.4718306
OS 51.8710418 -38.47090604
OS 51.87196636 -38.46813236
OS 51.87289092 -38.46443412
OS 51.87381548 -38.45888676
OS 51.8756646 -38.45241484
OS 51.87843828 -38.44501836
OS 51.88398564 -38.42745172
OS 51.89323124 -38.4071114
OS 51.90432596 -38.38677108
OS 51.91819436 -38.36735532
OS 51.935761 -38.34978868
OS 51.93668556 -38.34886412
OS 51.93853468 -38.34793956
OS 51.94130836 -38.34609044
OS 51.9450066 -38.34331676
OS 51.9496294 -38.33961852
OS 51.95610132 -38.33592028
OS 51.96257324 -38.33222204
OS 51.97089428 -38.32759924
OS 51.98938548 -38.32020276
OS 52.01065036 -38.31280628
OS 52.03561348 -38.30818348
OS 52.04855732 -38.30633436
OS 52.07167132 -38.30633436
OS 52.08184148 -38.30725892
OE
OB 51.07499564 -38.37105356 H
OS 51.06944828 -38.37105356
OS 51.06575004 -38.37197812
OS 51.05557988 -38.37382724
OS 51.0435606 -38.37660092
OS 51.0296922 -38.38214828
OS 51.01489924 -38.39046932
OS 51.00750276 -38.39601668
OS 51.00010628 -38.40156404
OS 50.99363436 -38.40896052
OS 50.98716244 -38.41728156
OS 50.98716244 -38.41820612
OS 50.98531332 -38.42005524
OS 50.9834642 -38.42375348
OS 50.98069052 -38.42837628
OS 50.97791684 -38.43577276
OS 50.9742186 -38.4440938
OS 50.97144492 -38.45426396
OS 50.96774668 -38.46628324
OS 50.96404844 -38.48015164
OS 50.9603502 -38.49586916
OS 50.95665196 -38.5134358
OS 50.95387828 -38.53285156
OS 50.9511046 -38.555041
OS 50.94925548 -38.57907956
OS 50.94833092 -38.60496724
OS 50.94740636 -38.6336286
OS 50.94740636 -38.63547772
OS 50.94740636 -38.64010052
OS 50.94740636 -38.64842156
OS 50.94833092 -38.65951628
OS 50.94833092 -38.67153556
OS 50.94925548 -38.68632852
OS 50.95018004 -38.70204604
OS 50.95202916 -38.71868812
OS 50.95665196 -38.75474596
OS 50.95942564 -38.7723126
OS 50.96312388 -38.78895468
OS 50.96682212 -38.8046722
OS 50.97236948 -38.81946516
OS 50.97791684 -38.832409
OS 50.98438876 -38.84350372
OS 50.98438876 -38.84442828
OS 50.98623788 -38.84535284
OS 50.99086068 -38.85182476
OS 50.99918172 -38.8601458
OS 51.00935188 -38.8693914
OS 51.02322028 -38.878637
OS 51.0389378 -38.88695804
OS 51.05650444 -38.89342996
OS 51.06575004 -38.89435452
OS 51.0759202 -38.89527908
OS 51.08146756 -38.89527908
OS 51.0851658 -38.89435452
OS 51.0944114 -38.8925054
OS 51.10735524 -38.88880716
OS 51.12122364 -38.88233524
OS 51.13694116 -38.87308964
OS 51.14433764 -38.86754228
OS 51.15173412 -38.8601458
OS 51.1591306 -38.85274932
OS 51.16652708 -38.84350372
OS 51.16652708 -38.84257916
OS 51.1683762 -38.84073004
OS 51.17022532 -38.83795636
OS 51.17207444 -38.83333356
OS 51.17577268 -38.82686164
OS 51.17854636 -38.8185406
OS 51.1822446 -38.809295
OS 51.18594284 -38.79820028
OS 51.18871652 -38.78433188
OS 51.19241476 -38.76953892
OS 51.196113 -38.75197228
OS 51.19888668 -38.73348108
OS 51.2007358 -38.71129164
OS 51.20258492 -38.68817764
OS 51.20443404 -38.66228996
OS 51.20443404 -38.6336286
OS 51.20443404 -38.63270404
OS 51.20443404 -38.63177948
OS 51.20443404 -38.62715668
OS 51.20443404 -38.61883564
OS 51.20350948 -38.60774092
OS 51.20350948 -38.59572164
OS 51.20258492 -38.58092868
OS 51.20166036 -38.56521116
OS 51.19981124 -38.54764452
OS 51.19518844 -38.51251124
OS 51.19241476 -38.4949446
OS 51.18871652 -38.47830252
OS 51.18501828 -38.462585
OS 51.17947092 -38.44779204
OS 51.17392356 -38.4348482
OS 51.16745164 -38.42375348
OS 51.16745164 -38.42282892
OS 51.16560252 -38.42190436
OS 51.1637534 -38.41913068
OS 51.16097972 -38.41543244
OS 51.15265868 -38.4071114
OS 51.14248852 -38.39694124
OS 51.12862012 -38.38769564
OS 51.1129026 -38.3793746
OS 51.10458156 -38.37567636
OS 51.09533596 -38.37290268
OS 51.0851658 -38.37197812
OS 51.07499564 -38.37105356
OE
OB 54.05947532 -38.37105356 H
OS 54.05392796 -38.37105356
OS 54.05022972 -38.37197812
OS 54.04005956 -38.37382724
OS 54.02804028 -38.37660092
OS 54.01417188 -38.38214828
OS 53.99937892 -38.39046932
OS 53.99198244 -38.39601668
OS 53.98458596 -38.40156404
OS 53.97811404 -38.40896052
OS 53.97164212 -38.41728156
OS 53.97164212 -38.41820612
OS 53.969793 -38.42005524
OS 53.96794388 -38.42375348
OS 53.9651702 -38.42837628
OS 53.96239652 -38.43577276
OS 53.95869828 -38.4440938
OS 53.9559246 -38.45426396
OS 53.95222636 -38.46628324
OS 53.94852812 -38.48015164
OS 53.94482988 -38.49586916
OS 53.94113164 -38.5134358
OS 53.93835796 -38.53285156
OS 53.93558428 -38.555041
OS 53.93373516 -38.57907956
OS 53.9328106 -38.60496724
OS 53.93188604 -38.6336286
OS 53.93188604 -38.63547772
OS 53.93188604 -38.64010052
OS 53.93188604 -38.64842156
OS 53.9328106 -38.65951628
OS 53.9328106 -38.67153556
OS 53.93373516 -38.68632852
OS 53.93465972 -38.70204604
OS 53.93650884 -38.71868812
OS 53.94113164 -38.75474596
OS 53.94390532 -38.7723126
OS 53.94760356 -38.78895468
OS 53.9513018 -38.8046722
OS 53.95684916 -38.81946516
OS 53.96239652 -38.832409
OS 53.96886844 -38.84350372
OS 53.96886844 -38.84442828
OS 53.97071756 -38.84535284
OS 53.97534036 -38.85182476
OS 53.9836614 -38.8601458
OS 53.99383156 -38.8693914
OS 54.00769996 -38.878637
OS 54.02341748 -38.88695804
OS 54.04098412 -38.89342996
OS 54.05022972 -38.89435452
OS 54.06039988 -38.89527908
OS 54.06594724 -38.89527908
OS 54.06964548 -38.89435452
OS 54.07889108 -38.8925054
OS 54.09183492 -38.88880716
OS 54.10570332 -38.88233524
OS 54.12142084 -38.87308964
OS 54.12881732 -38.86754228
OS 54.1362138 -38.8601458
OS 54.14361028 -38.85274932
OS 54.15100676 -38.84350372
OS 54.15100676 -38.84257916
OS 54.15285588 -38.84073004
OS 54.154705 -38.83795636
OS 54.15655412 -38.83333356
OS 54.16025236 -38.82686164
OS 54.16302604 -38.8185406
OS 54.16672428 -38.809295
OS 54.17042252 -38.79820028
OS 54.1731962 -38.78433188
OS 54.17689444 -38.76953892
OS 54.18059268 -38.75197228
OS 54.18336636 -38.73348108
OS 54.18521548 -38.71129164
OS 54.1870646 -38.68817764
OS 54.18891372 -38.66228996
OS 54.18891372 -38.6336286
OS 54.18891372 -38.63270404
OS 54.18891372 -38.63177948
OS 54.18891372 -38.62715668
OS 54.18891372 -38.61883564
OS 54.18798916 -38.60774092
OS 54.18798916 -38.59572164
OS 54.1870646 -38.58092868
OS 54.18614004 -38.56521116
OS 54.18429092 -38.54764452
OS 54.17966812 -38.51251124
OS 54.17689444 -38.4949446
OS 54.1731962 -38.47830252
OS 54.16949796 -38.462585
OS 54.1639506 -38.44779204
OS 54.15840324 -38.4348482
OS 54.15193132 -38.42375348
OS 54.15193132 -38.42282892
OS 54.1500822 -38.42190436
OS 54.14823308 -38.41913068
OS 54.1454594 -38.41543244
OS 54.13713836 -38.4071114
OS 54.1269682 -38.39694124
OS 54.1130998 -38.38769564
OS 54.09738228 -38.3793746
OS 54.08906124 -38.37567636
OS 54.07981564 -38.37290268
OS 54.06964548 -38.37197812
OS 54.05947532 -38.37105356
OE
OB 49.87491676 -38.43669732 H
OS 49.67336268 -38.72331092
OS 49.87491676 -38.72331092
OS 49.87491676 -38.43669732
OE
OB 56.14158444 -38.38492196 H
OS 55.95852156 -38.38492196
OS 55.95852156 -38.61328828
OS 56.13048972 -38.61328828
OS 56.13696164 -38.61236372
OS 56.14343356 -38.61236372
OS 56.15083004 -38.61143916
OS 56.16839668 -38.60959004
OS 56.18781244 -38.6058918
OS 56.2072282 -38.60034444
OS 56.22479484 -38.59294796
OS 56.23311588 -38.58832516
OS 56.2395878 -38.5827778
OS 56.24143692 -38.58092868
OS 56.24513516 -38.57723044
OS 56.25068252 -38.56983396
OS 56.25715444 -38.56058836
OS 56.26362636 -38.54856908
OS 56.26917372 -38.53377612
OS 56.27287196 -38.51713404
OS 56.27472108 -38.49771828
OS 56.27472108 -38.49679372
OS 56.27472108 -38.49586916
OS 56.27472108 -38.49124636
OS 56.27379652 -38.48292532
OS 56.2719474 -38.47367972
OS 56.27009828 -38.46350956
OS 56.26640004 -38.45149028
OS 56.26085268 -38.44039556
OS 56.25438076 -38.42930084
OS 56.2534562 -38.42837628
OS 56.25068252 -38.42467804
OS 56.24605972 -38.42005524
OS 56.24051236 -38.41358332
OS 56.23219132 -38.4071114
OS 56.22294572 -38.40156404
OS 56.21277556 -38.39601668
OS 56.20075628 -38.39139388
OS 56.19983172 -38.39139388
OS 56.19613348 -38.39046932
OS 56.19058612 -38.38954476
OS 56.18318964 -38.38769564
OS 56.17209492 -38.38677108
OS 56.15822652 -38.38584652
OS 56.14158444 -38.38492196
OE
SE

### steps/pcb/layers/comp_+_bot/features


### steps/pcb/layers/comp_+_top/features


### steps/pcb/layers/dielectric_1/features
UNITS=MM
#Layer_Color=255
#
#Feature symbol names
#

#
#Feature attribute names
#

#
#Layer features
#

### steps/pcb/layers/dielectric_2/features
UNITS=MM
#Layer_Color=255
#
#Feature symbol names
#

#
#Feature attribute names
#

#
#Layer features
#

### steps/pcb/layers/dielectric_3/features
UNITS=MM
#Layer_Color=255
#
#Feature symbol names
#

#
#Feature attribute names
#

#
#Layer features
#

### steps/pcb/layers/drill_non-plated_bottom-top/features
UNITS=MM
#Layer_Color=9474304
#
#Feature symbol names
#
$0 r2999.99908

#
#Feature attribute names
#
@0 .geometry
@1 .drill

#
#Feature attribute text strings
#
&0 Pad_Simple_X5299.9996Y5299.9996H2999.9991C4015.9991

#
#Layer features
#
P 20.24000016 42.13999954 0 P 0 0 ;0=0,1=1
P 20.43999976 -1.26000002 0 P 0 0 ;0=0,1=1

### steps/pcb/layers/drill_plated_bottom-top/features
UNITS=MM
#Layer_Color=9474304
#
#Feature symbol names
#
$0 r299.9994
$1 r762
$2 r961.9996
$3 r1090.00036
$4 r1200.00014
$5 r3700.00022

#
#Feature attribute names
#
@0 .geometry
@1 .drill

#
#Feature attribute text strings
#
&0 VIA_RoundD599.9988H299.9994C1315.9994
&1 Pad_Simple_X0.0000Y0.0000H3700.0002C4716.0002
&2 Pad_Simple_X1524.0000Y1524.0000H762.0000C1778.0000
&3 Pad_Simple_X1562.0009Y1562.0009H961.9996C1977.9996
&4 Pad_Simple_X2090.0009Y2090.0009H1090.0004C2106.0004
&5 Pad_Simple_X1799.9989Y1799.9989H1200.0001C2216.0001

#
#Layer features
#
P 0 0 3 P 0 0 ;0=4,1=0
P 0 40.64 3 P 0 0 ;0=4,1=0
P 2.0779994 43.3299997 3 P 0 0 ;0=4,1=0
P 4.39999882 2.00000108 5 P 0 0 ;0=1,1=0
P 4.39999882 38.599999 5 P 0 0 ;0=1,1=0
P 4.8300005 7.63999996 4 P 0 0 ;0=5,1=0
P 4.8300005 7.63999996 1 P 0 0 ;0=2,1=0
P 4.8300005 12.71999996 1 P 0 0 ;0=2,1=0
P 4.8300005 12.71999996 4 P 0 0 ;0=5,1=0
P 4.8300005 17.79999996 1 P 0 0 ;0=2,1=0
P 4.8300005 17.79999996 4 P 0 0 ;0=5,1=0
P 4.8300005 33.03999996 4 P 0 0 ;0=5,1=0
P 4.8300005 33.03999996 1 P 0 0 ;0=2,1=0
P 5.1259994 43.3299997 3 P 0 0 ;0=4,1=0
P 8.1739994 43.3299997 3 P 0 0 ;0=4,1=0
P 11.2219994 43.3299997 3 P 0 0 ;0=4,1=0
P 14.2699994 43.3299997 3 P 0 0 ;0=4,1=0
P 35.50000012 -1.00000054 5 P 0 0 ;0=1,1=0
P 36.20000126 40.10000108 5 P 0 0 ;0=1,1=0
P 37.8500005 7.63999996 2 P 0 0 ;0=3,1=0
P 37.8500005 7.63999996 4 P 0 0 ;0=5,1=0
P 37.8500005 12.71999996 2 P 0 0 ;0=3,1=0
P 37.8500005 12.71999996 4 P 0 0 ;0=5,1=0
P 37.8500005 17.79999996 4 P 0 0 ;0=5,1=0
P 37.8500005 17.79999996 2 P 0 0 ;0=3,1=0
P 37.8500005 22.87999996 2 P 0 0 ;0=3,1=0
P 37.8500005 22.87999996 4 P 0 0 ;0=5,1=0
P 37.8500005 33.03999996 2 P 0 0 ;0=3,1=0
P 37.8500005 33.03999996 4 P 0 0 ;0=5,1=0
P 40.64 0 3 P 0 0 ;0=4,1=0
P 40.64 40.64 3 P 0 0 ;0=4,1=0
P 40.67999992 20.33999996 3 P 0 0 ;0=4,1=0
P -2.99999908 16.00000102 0 P 0 0 ;0=0,1=2
P -2.99999908 17.99999956 0 P 0 0 ;0=0,1=2
P -2.99999908 20.00000064 0 P 0 0 ;0=0,1=2
P -2.99999908 21.99999918 0 P 0 0 ;0=0,1=2
P -2.99999908 24.00000026 0 P 0 0 ;0=0,1=2
P -2.99999908 25.9999988 0 P 0 0 ;0=0,1=2
P -2.99999908 27.99999988 0 P 0 0 ;0=0,1=2
P -2.99999908 30.00000096 0 P 0 0 ;0=0,1=2
P -2.99999908 31.9999995 0 P 0 0 ;0=0,1=2
P -2.99999908 34.00000058 0 P 0 0 ;0=0,1=2
P -2.99999908 35.99999912 0 P 0 0 ;0=0,1=2
P -2.99999908 38.0000002 0 P 0 0 ;0=0,1=2
P -2.99999908 39.99999874 0 P 0 0 ;0=0,1=2
P 0.50000154 -3.99999962 0 P 0 0 ;0=0,1=2
P 2.50000008 -3.99999962 0 P 0 0 ;0=0,1=2
P 4.50000116 -3.99999962 0 P 0 0 ;0=0,1=2
P 6.4999997 -3.99999962 0 P 0 0 ;0=0,1=2
P 8.50000078 -3.99999962 0 P 0 0 ;0=0,1=2
P 10.49999932 -3.99999962 0 P 0 0 ;0=0,1=2
P 12.5000004 -3.99999962 0 P 0 0 ;0=0,1=2
P 12.74500118 40.26499948 0 P 0 0 ;0=0,1=2
P 12.74500118 41.21500012 0 P 0 0 ;0=0,1=2
P 12.74500118 44.63999962 0 P 0 0 ;0=0,1=2
P 12.75500116 42.16500076 0 P 0 0 ;0=0,1=2
P 12.98999942 18.0150008 0 P 0 0 ;0=0,1=2
P 14.50000148 -3.99999962 0 P 0 0 ;0=0,1=2
P 15.88470534 21.56499878 0 P 0 0 ;0=0,1=2
P 16.30970576 23.03999964 0 P 0 0 ;0=0,1=2
P 16.50000002 -3.99999962 0 P 0 0 ;0=0,1=2
P 17.57500168 13.89000016 0 P 0 0 ;0=0,1=2
P 17.915001 15.69625258 0 P 0 0 ;0=0,1=2
P 18.8149992 15.10000028 0 P 0 0 ;0=0,1=2
P 18.8149992 15.98270108 0 P 0 0 ;0=0,1=2
P 18.8149992 16.85250122 0 P 0 0 ;0=0,1=2
P 19.01500134 7.39000046 0 P 0 0 ;0=0,1=2
P 19.01500134 8.5900006 0 P 0 0 ;0=0,1=2
P 19.01500134 9.7899982 0 P 0 0 ;0=0,1=2
P 19.01500134 11.09000068 0 P 0 0 ;0=0,1=2
P 19.01500134 12.39000062 0 P 0 0 ;0=0,1=2
P 21.11499968 6.76500044 0 P 0 0 ;0=0,1=2
P 21.11499968 7.78999966 0 P 0 0 ;0=0,1=2
P 21.11499968 8.9899998 0 P 0 0 ;0=0,1=2
P 21.11499968 10.28999974 0 P 0 0 ;0=0,1=2
P 21.11499968 11.38590052 0 P 0 0 ;0=0,1=2
P 22.05919388 12.29000082 0 P 0 0 ;0=0,1=2
P 22.45970616 20.01499934 0 P 0 0 ;0=0,1=2
P 23.29999912 38.90000094 0 P 0 0 ;0=0,1=2
P 23.33999904 44.0138312 0 P 0 0 ;0=0,1=2
P 23.4097068 20.04000056 0 P 0 0 ;0=0,1=2
P 24.35970744 20.04000056 0 P 0 0 ;0=0,1=2
P 24.49999926 -3.50000062 0 P 0 0 ;0=0,1=2
P 25.7999992 38.90000094 0 P 0 0 ;0=0,1=2
P 26.50000034 -3.50000062 0 P 0 0 ;0=0,1=2
P 28.50000142 -3.50000062 0 P 0 0 ;0=0,1=2
P 30.49999996 -3.50000062 0 P 0 0 ;0=0,1=2
P 32.50000104 -3.50000062 0 P 0 0 ;0=0,1=2
P 32.80000044 38.90000094 0 P 0 0 ;0=0,1=2
P 35.30000052 44.0000009 0 P 0 0 ;0=0,1=2
P 38.4999992 -3.50000062 0 P 0 0 ;0=0,1=2
P 39.60000208 38.91499964 0 P 0 0 ;0=0,1=2
P 40.50000028 -3.50000062 0 P 0 0 ;0=0,1=2
P 40.67999992 42.76499956 0 P 0 0 ;0=0,1=2
P 42.2249981 38.91499964 0 P 0 0 ;0=0,1=2
P 44.4999999 0.499999 0 P 0 0 ;0=0,1=2
P 44.4999999 2.50000008 0 P 0 0 ;0=0,1=2
P 44.4999999 4.49999862 0 P 0 0 ;0=0,1=2
P 44.4999999 6.4999997 0 P 0 0 ;0=0,1=2
P 44.4999999 8.49999824 0 P 0 0 ;0=0,1=2
P 44.4999999 10.49999932 0 P 0 0 ;0=0,1=2
P 44.4999999 12.49999786 0 P 0 0 ;0=0,1=2
P 44.4999999 14.49999894 0 P 0 0 ;0=0,1=2
P 44.4999999 16.50000002 0 P 0 0 ;0=0,1=2
P 44.4999999 18.49999856 0 P 0 0 ;0=0,1=2
P 44.4999999 20.49999964 0 P 0 0 ;0=0,1=2
P 44.4999999 22.49999818 0 P 0 0 ;0=0,1=2
P 44.4999999 24.49999926 0 P 0 0 ;0=0,1=2
P 44.4999999 26.4999978 0 P 0 0 ;0=0,1=2
P 44.4999999 28.49999888 0 P 0 0 ;0=0,1=2
P 44.4999999 30.49999996 0 P 0 0 ;0=0,1=2
P 44.4999999 32.4999985 0 P 0 0 ;0=0,1=2
P 44.4999999 34.49999958 0 P 0 0 ;0=0,1=2
P 44.4999999 36.49999812 0 P 0 0 ;0=0,1=2
P 44.4999999 38.4999992 0 P 0 0 ;0=0,1=2
P 44.4999999 40.49999774 0 P 0 0 ;0=0,1=2

### steps/pcb/layers/l01-top_layer/features
UNITS=MM
#Layer_Physical_Order=1
#Layer_Color=255
#
#Feature symbol names
#
$0 r1000.00054
$1 r99.9998
$2 r2090.0009
$3 r5299.99956
$4 r1562.00094
$5 r1524
$6 r1799.99894
$7 r599.9988

#
#Feature attribute names
#
@0 .geometry
@1 .pad_usage
@2 .smd
@3 .nomenclature
@4 .string
@5 .string_angle

#
#Feature attribute text strings
#
&0 SMD_RoundX1000.0005Y1000.0005
&1 Pad_Simple_X2090.0009Y2090.0009H1090.0004C2106.0004
&2 Pad_Simple_X5299.9996Y5299.9996H2999.9991C4015.9991
&3 Pad_Simple_X1562.0009Y1562.0009H961.9996C1977.9996
&4 Pad_Simple_X1524.0000Y1524.0000H762.0000C1778.0000
&5 Pad_Simple_X1799.9989Y1799.9989H1200.0001C2216.0001
&6 VIA_RoundD599.9988H299.9994C1315.9994

#
#Layer features
#
L -9.5600012 -24.45999934 40.4400004 -24.45999934 1 P 0
L -9.5600012 -35.9599992 -9.5600012 -24.45999934 1 P 0
L -9.5600012 -35.9599992 28.439999 -35.9599992 1 P 0
L -9.5600012 -39.45999982 -9.5600012 -35.9599992 1 P 0
L -9.5600012 -39.45999982 28.439999 -39.45999982 1 P 0
L -9.5600012 -42.96000044 -9.5600012 -39.45999982 1 P 0
L -9.5600012 -42.96000044 28.439999 -42.96000044 1 P 0
L -10.0600002 -23.96000034 62.93999858 -23.96000034 1 P 0
L -10.0600002 -43.45999944 -10.0600002 -23.96000034 1 P 0
L -10.0600002 -43.45999944 62.93999858 -43.45999944 1 P 0
L 28.439999 -35.96000174 45.44000056 -35.9599992 1 P 0
L 28.439999 -39.45999982 28.439999 -35.9599992 1 P 0
L 28.439999 -39.46000236 45.44000056 -39.45999982 1 P 0
L 28.439999 -42.96000044 28.439999 -39.45999982 1 P 0
L 28.439999 -42.96000298 45.44000056 -42.96000044 1 P 0
L 40.4400004 -24.45999934 62.43999958 -24.45999934 1 P 0
L 40.4400004 -35.9599992 40.4400004 -24.45999934 1 P 0
L 40.67999992 20.33999996 44.63999962 20.33999996 0 P 0
L 45.44000056 -35.9599992 62.43999958 -35.9599992 1 P 0
L 45.44000056 -39.45999982 62.43999958 -39.45999982 1 P 0
L 45.44000056 -42.96000044 45.44000056 -35.9599992 1 P 0
L 45.44000056 -42.96000044 62.43999958 -42.96000044 1 P 0
L 62.43999958 -35.9599992 62.43999958 -24.45999934 1 P 0
L 62.43999958 -42.96000044 62.43999958 -35.9599992 1 P 0
L 62.93999858 -43.45999944 62.93999858 -23.96000034 1 P 0
P -2.20000068 -2.69999968 0 P 0 0 ;0=0,1=0,2
P -2.37499906 43.52500058 0 P 0 0 ;0=0,1=0,2
P 0 0 2 P 0 0 ;0=1,1=0
P 0 40.64 2 P 0 0 ;0=1,1=0
P 2.0779994 43.3299997 2 P 0 0 ;0=1,1=0
P 4.8300005 7.63999996 6 P 0 0 ;0=5,1=0
P 4.8300005 7.63999996 5 P 0 0 ;0=4,1=0
P 4.8300005 12.71999996 6 P 0 0 ;0=5,1=0
P 4.8300005 12.71999996 5 P 0 0 ;0=4,1=0
P 4.8300005 17.79999996 6 P 0 0 ;0=5,1=0
P 4.8300005 17.79999996 5 P 0 0 ;0=4,1=0
P 4.8300005 33.03999996 6 P 0 0 ;0=5,1=0
P 4.8300005 33.03999996 5 P 0 0 ;0=4,1=0
P 5.1259994 43.3299997 2 P 0 0 ;0=1,1=0
P 8.1739994 43.3299997 2 P 0 0 ;0=1,1=0
P 11.2219994 43.3299997 2 P 0 0 ;0=1,1=0
P 14.2699994 43.3299997 2 P 0 0 ;0=1,1=0
P 20.24000016 42.13999954 3 P 0 0 ;0=2,1=0
P 20.43999976 -1.26000002 3 P 0 0 ;0=2,1=0
P 37.8500005 7.63999996 6 P 0 0 ;0=5,1=0
P 37.8500005 7.63999996 4 P 0 0 ;0=3,1=0
P 37.8500005 12.71999996 6 P 0 0 ;0=5,1=0
P 37.8500005 12.71999996 4 P 0 0 ;0=3,1=0
P 37.8500005 17.79999996 6 P 0 0 ;0=5,1=0
P 37.8500005 17.79999996 4 P 0 0 ;0=3,1=0
P 37.8500005 22.87999996 4 P 0 0 ;0=3,1=0
P 37.8500005 22.87999996 6 P 0 0 ;0=5,1=0
P 37.8500005 33.03999996 4 P 0 0 ;0=3,1=0
P 37.8500005 33.03999996 6 P 0 0 ;0=5,1=0
P 40.64 0 2 P 0 0 ;0=1,1=0
P 40.64 40.64 2 P 0 0 ;0=1,1=0
P 40.67999992 20.33999996 2 P 0 0 ;0=1,1=0
P 43.12499884 43.52500058 0 P 0 0 ;0=0,1=0,2
S P 0
OB 23.88064312 44.95700432 I
OS 23.8844455 44.95573686
OS 23.919942 44.9544694
OS 23.92374438 44.95320194
OS 23.92881676 44.95193448
OS 23.93515152 44.94939702
OS 23.9402239 44.94812956
OS 23.95797088 44.94559464
OS 23.97128048 44.94242726
OS 23.9820577 44.93672242
OS 23.988395 44.9341875
OS 23.99663222 44.93101758
OS 24.0010696 44.9278502
OS 24.00740944 44.92404528
OS 24.01374674 44.92151036
OS 24.0219865 44.91834044
OS 24.02388896 44.91644052
OS 24.02642388 44.91517306
OS 24.04036848 44.90883322
OS 24.04924324 44.90376338
OS 24.055578 44.899961
OS 24.06191784 44.89742354
OS 24.06698768 44.89615608
OS 24.07395998 44.89045124
OS 24.07839736 44.8860164
OS 24.08093228 44.88474894
OS 24.08663712 44.87904664
OS 24.08790458 44.87650918
OS 24.08980704 44.87460926
OS 24.09234196 44.8733418
OS 24.09931426 44.8663695
OS 24.10058172 44.86383204
OS 24.10248418 44.86193212
OS 24.1050191 44.86066466
OS 24.11198886 44.85369236
OS 24.11325632 44.8511549
OS 24.11515878 44.84925498
OS 24.1176937 44.84798752
OS 24.12339854 44.84228268
OS 24.124666 44.83974776
OS 24.12783592 44.83657784
OS 24.13037084 44.83531038
OS 24.13480822 44.830873
OS 24.13607568 44.82833808
OS 24.14368044 44.82073332
OS 24.14621536 44.81439602
OS 24.14938528 44.80615626
OS 24.1525552 44.80171888
OS 24.1588925 44.79537904
OS 24.16269742 44.78904174
OS 24.16903472 44.7827019
OS 24.17346956 44.77065976
OS 24.17537202 44.76622238
OS 24.18170932 44.7560827
OS 24.18297678 44.74721048
OS 24.18424424 44.7421381
OS 24.1855117 44.73453334
OS 24.19438646 44.71551636
OS 24.19628892 44.70347676
OS 24.20135876 44.69079962
OS 24.20262622 44.68572978
OS 24.20389368 44.67812248
OS 24.20516114 44.65023328
OS 24.2064286 44.61600678
OS 24.20769606 44.53994902
OS 24.20833106 41.48175092
OS 24.20833106 41.48048346
OS 24.20769606 38.81145654
OS 24.20833106 38.80701916
OS 24.2070636 38.80321678
OS 24.20769606 38.78229988
OS 24.2070636 38.76265298
OS 24.20833106 38.75884806
OS 24.2070636 38.75377822
OS 24.20579614 38.74490346
OS 24.2070636 38.73983362
OS 24.20769606 38.73286132
OS 24.2064286 38.72652402
OS 24.20516114 38.72145164
OS 24.20389368 38.68849514
OS 24.20135876 38.6821553
OS 24.192484 38.67328308
OS 24.1861467 38.67074562
OS 24.15065274 38.66947816
OS 24.14685036 38.6682107
OS 24.14178052 38.66694324
OS 24.12973584 38.6688457
OS 24.12656592 38.66947816
OS 24.12276354 38.6682107
OS 24.11389132 38.66694324
OS 24.10121672 38.6682107
OS 24.08853958 38.66694324
OS 24.0625503 38.66757824
OS 24.05304308 38.66694324
OS 24.04924324 38.6682107
OS 24.04227094 38.6688457
OS 24.03466364 38.66757824
OS 24.02769134 38.66694324
OS 24.02388896 38.6682107
OS 24.01374674 38.67074562
OS 23.9820577 38.67201562
OS 23.9750854 38.67771792
OS 23.97001302 38.6827903
OS 23.9674781 38.6891276
OS 23.96621064 38.72462156
OS 23.96494318 38.72842394
OS 23.96367572 38.7372987
OS 23.96494318 38.74110108
OS 23.96621064 38.74870838
OS 23.96494318 38.75251076
OS 23.96367572 38.76138552
OS 23.96494318 38.76645282
OS 23.96430818 38.78863718
OS 23.96494318 38.80321678
OS 23.96367572 38.80701916
OS 23.96430818 38.82413368
OS 23.96304072 44.54755378
OS 23.96240826 44.55199116
OS 23.96367572 44.55579354
OS 23.96240826 44.57734544
OS 23.9611408 44.58114782
OS 23.9598708 44.62171162
OS 23.95733588 44.62805146
OS 23.9535335 44.63692368
OS 23.95226604 44.64199606
OS 23.9471962 44.65086828
OS 23.94212382 44.65593812
OS 23.94085636 44.65847304
OS 23.93515152 44.66544534
OS 23.9326166 44.6667128
OS 23.9269143 44.67241764
OS 23.92564684 44.67495256
OS 23.92247692 44.67812248
OS 23.919942 44.67938994
OS 23.9129697 44.68509478
OS 23.90979978 44.6882647
OS 23.90346248 44.69079962
OS 23.89649018 44.69270208
OS 23.88064312 44.70094184
OS 23.87557328 44.7022093
OS 23.8654336 44.70347676
OS 23.86163122 44.70474168
OS 23.85275646 44.70854406
OS 23.84768662 44.70981152
OS 23.83120456 44.71108152
OS 23.80141798 44.71298144
OS 23.74944196 44.7142489
OS 23.25759636 44.71551636
OS 23.2493566 44.71615136
OS 23.24555422 44.7148839
OS 23.22273486 44.71615136
OS 23.21893248 44.7148839
OS 23.20372296 44.71615136
OS 23.19991804 44.71741882
OS 23.16949392 44.71868628
OS 23.16315662 44.72248866
OS 23.15618432 44.7281935
OS 23.15491686 44.73073096
OS 23.1523794 44.73706826
OS 23.15174694 44.75798516
OS 23.1523794 44.76495492
OS 23.15111194 44.7687573
OS 23.14921456 44.77699706
OS 23.14857956 44.78650682
OS 23.14984448 44.7903092
OS 23.14921456 44.81376102
OS 23.14984448 44.8245357
OS 23.14857956 44.82833808
OS 23.14921456 44.8593972
OS 23.14857956 44.87017188
OS 23.14984448 44.87397426
OS 23.14921456 44.89615608
OS 23.15047948 44.90122846
OS 23.15174694 44.90756576
OS 23.1523794 44.91453806
OS 23.15111194 44.91707298
OS 23.1523794 44.9208779
OS 23.15364686 44.9411598
OS 23.15808424 44.9468621
OS 23.16061916 44.94812956
OS 23.16315662 44.95193448
OS 23.16949392 44.9544694
OS 23.20435542 44.95636932
OS 23.2094278 44.95763678
OS 23.2214674 44.95827178
OS 23.22526978 44.95700432
OS 23.24808914 44.95827178
OS 23.25189152 44.95700432
OS 23.26837104 44.95827178
OS 23.88064312 44.95700432
OE
SE
S P 0
OB 24.62982374 40.45559092 I
OS 24.65961286 40.453691
OS 24.67229 40.45242354
OS 24.6786273 40.45115608
OS 24.68496714 40.44861862
OS 24.6932069 40.44545124
OS 24.70207912 40.44418632
OS 24.7071515 40.44291632
OS 24.71538872 40.43974894
OS 24.72299348 40.43467656
OS 24.73693808 40.42960672
OS 24.74137546 40.4264368
OS 24.7477153 40.4200995
OS 24.75025022 40.41883204
OS 24.7686322 40.40045006
OS 24.76989712 40.39791514
OS 24.7743345 40.39474522
OS 24.7813068 40.38777292
OS 24.78257426 40.385238
OS 24.78701164 40.38207062
OS 24.80539362 40.36368864
OS 24.80666108 40.36115372
OS 24.81299838 40.35481388
OS 24.81426584 40.35227896
OS 24.81680076 40.34594166
OS 24.81997068 40.3377019
OS 24.82567552 40.32819214
OS 24.82821044 40.318055
OS 24.83011036 40.30727778
OS 24.83264528 40.30094048
OS 24.8358152 40.29270072
OS 24.83708266 40.28382596
OS 24.83835012 40.26734644
OS 24.83961758 40.25467184
OS 24.84088504 40.22298026
OS 24.83961758 40.21917534
OS 24.83835012 40.18368392
OS 24.83708266 40.179879
OS 24.8358152 40.16720186
OS 24.83074282 40.15579472
OS 24.82821044 40.1456525
OS 24.82694298 40.13678028
OS 24.82187314 40.12790552
OS 24.81680076 40.11649838
OS 24.81363338 40.10825862
OS 24.80539362 40.10001632
OS 24.80412362 40.0974814
OS 24.79968878 40.09177656
OS 24.79715132 40.0905091
OS 24.77877188 40.07212966
OS 24.77750188 40.06959474
OS 24.77560196 40.06769482
OS 24.77306704 40.06642482
OS 24.76736474 40.06071998
OS 24.76609728 40.05818506
OS 24.76292736 40.05501768
OS 24.76039244 40.05374768
OS 24.75342014 40.04804538
OS 24.75025022 40.04487546
OS 24.74391038 40.04234054
OS 24.73567062 40.03917062
OS 24.73123324 40.0360007
OS 24.71475372 40.02839594
OS 24.6932069 40.01825626
OS 24.68179722 40.0169888
OS 24.67799484 40.01572134
OS 24.66912008 40.01191642
OS 24.66024532 40.0093815
OS 24.6513731 40.00811404
OS 24.62665382 40.00621158
OS 24.60573692 40.00557912
OS 24.60193454 40.00684658
OS 24.57341288 40.00874904
OS 24.56707558 40.0100165
OS 24.55693336 40.01381888
OS 24.54615868 40.0169888
OS 24.5410863 40.01825626
OS 24.53157908 40.02015618
OS 24.51573456 40.02839594
OS 24.5074948 40.03156332
OS 24.50305742 40.03346578
OS 24.49989004 40.0366357
OS 24.49925504 40.03853562
OS 24.49672012 40.03980308
OS 24.4941852 40.04234054
OS 24.49165028 40.043608
OS 24.48594544 40.04931284
OS 24.48467798 40.05184776
OS 24.48277552 40.05374768
OS 24.4802406 40.05501768
OS 24.47453576 40.06071998
OS 24.4732683 40.06325744
OS 24.47009838 40.06642482
OS 24.467566 40.06769482
OS 24.46312862 40.07212966
OS 24.46186116 40.07466712
OS 24.45869124 40.0778345
OS 24.45615632 40.07910196
OS 24.45045148 40.08480426
OS 24.44918402 40.08734172
OS 24.4460141 40.0905091
OS 24.44347918 40.09177656
OS 24.4390418 40.09621394
OS 24.43777434 40.09874886
OS 24.43016958 40.10635616
OS 24.42889958 40.10889108
OS 24.42636466 40.11523092
OS 24.42319728 40.12347068
OS 24.42129482 40.1253706
OS 24.42002736 40.12790552
OS 24.41749244 40.13044298
OS 24.41305506 40.14248512
OS 24.41052014 40.14882242
OS 24.40481784 40.15832964
OS 24.40228038 40.16720186
OS 24.40038046 40.17924654
OS 24.39340816 40.19636106
OS 24.38960578 40.2343874
OS 24.39087324 40.23819232
OS 24.39277316 40.26164414
OS 24.39404062 40.26671144
OS 24.39784554 40.27685366
OS 24.40101292 40.28509342
OS 24.40291538 40.2971381
OS 24.40418284 40.30220794
OS 24.41368752 40.32058992
OS 24.41685744 40.32882714
OS 24.42129482 40.33579944
OS 24.42763212 40.34974404
OS 24.43397196 40.36115372
OS 24.4390418 40.3725634
OS 24.44411418 40.38143562
OS 24.44918402 40.38650546
OS 24.45045148 40.38904038
OS 24.4536214 40.39347776
OS 24.45615632 40.39474522
OS 24.45869124 40.39728014
OS 24.46122616 40.3985476
OS 24.46629854 40.4061549
OS 24.46883346 40.40742236
OS 24.47580322 40.4131272
OS 24.4802406 40.41756458
OS 24.49608512 40.42326942
OS 24.49925504 40.4264368
OS 24.50178996 40.42770426
OS 24.50242496 40.42833926
OS 24.50305742 40.42897172
OS 24.5151021 40.4334091
OS 24.5214394 40.43594402
OS 24.5290467 40.4410164
OS 24.53601646 40.44291632
OS 24.54489122 40.44418632
OS 24.55693336 40.44861862
OS 24.56770804 40.45178854
OS 24.57278042 40.453056
OS 24.60003208 40.45495846
OS 24.61524414 40.45622592
OS 24.62602136 40.45686092
OS 24.62982374 40.45559092
OE
SE
S P 0
OB 24.63235866 41.19716678 I
OS 24.6583454 41.19526432
OS 24.6646827 41.19399686
OS 24.67482492 41.19019448
OS 24.6855996 41.18702456
OS 24.69066944 41.1857571
OS 24.69827674 41.18448964
OS 24.7071515 41.17941726
OS 24.71855864 41.17434742
OS 24.72489594 41.1718125
OS 24.72743086 41.17054504
OS 24.73630562 41.16420774
OS 24.74137546 41.16294028
OS 24.74961522 41.15977036
OS 24.75658752 41.15279806
OS 24.75912498 41.1515306
OS 24.7616599 41.14899568
OS 24.76419482 41.14772822
OS 24.7686322 41.14329084
OS 24.76989712 41.14075592
OS 24.77306704 41.137586
OS 24.77560196 41.13631854
OS 24.78003934 41.13188116
OS 24.7813068 41.12934624
OS 24.78574418 41.12490886
OS 24.7882791 41.1236414
OS 24.79144648 41.12047402
OS 24.79271648 41.11793656
OS 24.7952514 41.11540164
OS 24.79651886 41.11286672
OS 24.8015887 41.10779688
OS 24.80412362 41.10145958
OS 24.80539362 41.09638974
OS 24.81109592 41.08941744
OS 24.8155333 41.08498006
OS 24.82060568 41.0761053
OS 24.82567552 41.07103546
OS 24.82821044 41.0621607
OS 24.82947536 41.05075102
OS 24.83454774 41.03934388
OS 24.8358152 41.03427404
OS 24.83708266 41.02539928
OS 24.83835012 41.01272214
OS 24.83961758 40.98863786
OS 24.84088504 40.96835596
OS 24.83961758 40.95567882
OS 24.83771512 40.9258897
OS 24.83644766 40.91448256
OS 24.8351802 40.90941018
OS 24.83264528 40.90307288
OS 24.82947536 40.89483312
OS 24.82821044 40.88976074
OS 24.82821044 40.88849328
OS 24.82694298 40.87835106
OS 24.82123814 40.87137876
OS 24.81173092 40.8580717
OS 24.80792854 40.85426932
OS 24.80666108 40.85173186
OS 24.8015887 40.83905726
OS 24.79588386 40.83208242
OS 24.79271648 40.82891504
OS 24.79144648 40.82638012
OS 24.78574418 40.82067528
OS 24.78320672 40.81940782
OS 24.78003934 40.8162379
OS 24.77877188 40.81370298
OS 24.77306704 40.80799814
OS 24.77052958 40.80673068
OS 24.76736474 40.8035633
OS 24.76609728 40.80102838
OS 24.7616599 40.796591
OS 24.75912498 40.79532354
OS 24.75151768 40.78771624
OS 24.74518038 40.78518132
OS 24.73693808 40.7820114
OS 24.72933332 40.7756741
OS 24.7261634 40.77250418
OS 24.71728864 40.76743434
OS 24.7122188 40.76236196
OS 24.69700928 40.75982704
OS 24.68496714 40.75538966
OS 24.6792623 40.75348974
OS 24.67418992 40.75222228
OS 24.6653177 40.75095228
OS 24.64123342 40.74968482
OS 24.63235866 40.74841736
OS 24.58545756 40.74968482
OS 24.58165264 40.75095228
OS 24.56517312 40.75222228
OS 24.55629836 40.75602466
OS 24.54996106 40.75855958
OS 24.54489122 40.75982704
OS 24.534114 40.7617295
OS 24.52777924 40.76426442
OS 24.51827202 40.76996926
OS 24.50622734 40.77440664
OS 24.50178996 40.77757402
OS 24.49672012 40.7826464
OS 24.4941852 40.78391386
OS 24.4872129 40.7896187
OS 24.48277552 40.79405608
OS 24.466931 40.79976092
OS 24.46439608 40.80229584
OS 24.46312862 40.80482822
OS 24.45552132 40.80989806
OS 24.45045148 40.81497044
OS 24.44918402 40.81750536
OS 24.44157672 40.82511012
OS 24.4390418 40.83144996
OS 24.43714188 40.83842226
OS 24.43523942 40.84032472
OS 24.43397196 40.84285964
OS 24.42763212 40.84919694
OS 24.42636466 40.85173186
OS 24.42065982 40.85870416
OS 24.41622498 40.86314154
OS 24.41052014 40.87898606
OS 24.40481784 40.88849328
OS 24.40355038 40.89736804
OS 24.40228038 40.90243788
OS 24.40038046 40.91828494
OS 24.399113 40.92335478
OS 24.39594308 40.93032454
OS 24.39340816 40.9391993
OS 24.3921407 40.94807406
OS 24.39087324 40.9607512
OS 24.3921407 40.98990532
OS 24.39340816 40.9937077
OS 24.39467562 41.001315
OS 24.39974546 41.01272214
OS 24.40101292 41.01779452
OS 24.40228038 41.03047166
OS 24.40418284 41.0425138
OS 24.40735276 41.05075102
OS 24.41242006 41.0621607
OS 24.41368752 41.06723308
OS 24.41495498 41.0761053
OS 24.41622498 41.08117768
OS 24.42192728 41.08814998
OS 24.42382974 41.0900499
OS 24.4250972 41.09258482
OS 24.43080204 41.09955712
OS 24.43460442 41.10336204
OS 24.43650688 41.1039945
OS 24.43777434 41.10652688
OS 24.4460141 41.11476918
OS 24.44854902 41.11603664
OS 24.45488886 41.1236414
OS 24.45869124 41.12744632
OS 24.4605937 41.12807878
OS 24.46186116 41.1306137
OS 24.47009838 41.13885346
OS 24.4726333 41.14012092
OS 24.47580322 41.1445583
OS 24.48150806 41.15026314
OS 24.48404298 41.1515306
OS 24.49165028 41.1591379
OS 24.49798758 41.16167282
OS 24.50622734 41.1648402
OS 24.51066472 41.16801012
OS 24.51573456 41.17307996
OS 24.51827202 41.17434742
OS 24.52524432 41.18005226
OS 24.534749 41.1857571
OS 24.54742614 41.18702456
OS 24.55122852 41.18829202
OS 24.56010328 41.1920944
OS 24.5689755 41.19463186
OS 24.57785026 41.19589932
OS 24.60129954 41.19779924
OS 24.62855628 41.19843424
OS 24.63235866 41.19716678
OE
SE
S P 0
OB 24.6386985 41.9387401 I
OS 24.65200556 41.93683764
OS 24.6570754 41.93557018
OS 24.6640477 41.93240026
OS 24.67292246 41.92986534
OS 24.68750206 41.92796542
OS 24.69510682 41.92669796
OS 24.7001792 41.92542796
OS 24.71348626 41.91845566
OS 24.72553094 41.91402082
OS 24.73250324 41.90958344
OS 24.73503816 41.90704852
OS 24.75088268 41.90134368
OS 24.75912498 41.89310392
OS 24.7616599 41.89183392
OS 24.76482728 41.889934
OS 24.76609728 41.88739908
OS 24.79271648 41.86077988
OS 24.79398394 41.85824242
OS 24.8015887 41.85063766
OS 24.80602608 41.83859552
OS 24.81236592 41.8284533
OS 24.8155333 41.82148354
OS 24.81870322 41.81324378
OS 24.82504052 41.80310156
OS 24.82947536 41.79232688
OS 24.83264528 41.78408458
OS 24.8358152 41.77711228
OS 24.83708266 41.76824006
OS 24.83961758 41.73401356
OS 24.84088504 41.70739182
OS 24.83961758 41.70359198
OS 24.83771512 41.66619556
OS 24.8351802 41.6509835
OS 24.83074282 41.64020882
OS 24.82821044 41.6300666
OS 24.82694298 41.62119438
OS 24.82187314 41.61231962
OS 24.81680076 41.60090994
OS 24.81363338 41.59267018
OS 24.80539362 41.58443042
OS 24.80412362 41.58189804
OS 24.79841878 41.57492574
OS 24.7952514 41.57175582
OS 24.79144648 41.56288106
OS 24.79017902 41.55781122
OS 24.78447418 41.55083892
OS 24.78193926 41.54957146
OS 24.77877188 41.54640154
OS 24.77750188 41.54386662
OS 24.77560196 41.54196416
OS 24.76926212 41.53942924
OS 24.7610249 41.53625932
OS 24.75658752 41.53309194
OS 24.75025022 41.5267521
OS 24.7477153 41.52548464
OS 24.740743 41.51978234
OS 24.73757308 41.51661242
OS 24.72172602 41.51091012
OS 24.7198261 41.50900766
OS 24.70841896 41.50393782
OS 24.70334658 41.50266782
OS 24.6925719 41.5007679
OS 24.6862346 41.49823298
OS 24.67799484 41.49506306
OS 24.6653177 41.4937956
OS 24.66024532 41.49252814
OS 24.62538636 41.49062568
OS 24.60700438 41.48999322
OS 24.603202 41.49126068
OS 24.5689755 41.49252814
OS 24.56517312 41.4937956
OS 24.55249598 41.49506306
OS 24.53855138 41.50140036
OS 24.53031162 41.50457028
OS 24.52334186 41.50900766
OS 24.50939726 41.51534496
OS 24.49798758 41.5216848
OS 24.4865779 41.5267521
OS 24.47770568 41.53182448
OS 24.4726333 41.53689432
OS 24.47009838 41.53816178
OS 24.46312862 41.54386662
OS 24.46186116 41.54640154
OS 24.45615632 41.55210638
OS 24.4536214 41.55337384
OS 24.45171894 41.5552763
OS 24.45045148 41.55781122
OS 24.44474664 41.56351606
OS 24.44221172 41.56478352
OS 24.4390418 41.56795344
OS 24.43777434 41.57048836
OS 24.4320695 41.57746066
OS 24.42889958 41.58063058
OS 24.42636466 41.58696534
OS 24.4250972 41.59203772
OS 24.42002736 41.60090994
OS 24.41495498 41.61231962
OS 24.41242006 41.62753168
OS 24.40355038 41.64654612
OS 24.40228038 41.65541834
OS 24.39974546 41.66556056
OS 24.39467562 41.67697024
OS 24.39340816 41.68204008
OS 24.3921407 41.69091484
OS 24.38960578 41.7188015
OS 24.39087324 41.72260388
OS 24.39277316 41.74605824
OS 24.39404062 41.75239554
OS 24.398478 41.76317022
OS 24.40101292 41.76950752
OS 24.40228038 41.77838228
OS 24.40418284 41.78662204
OS 24.41368752 41.80500148
OS 24.41685744 41.81324378
OS 24.42129482 41.82021608
OS 24.42636466 41.83162322
OS 24.43143704 41.84049544
OS 24.43523942 41.84429782
OS 24.43650688 41.84683528
OS 24.4390418 41.8493702
OS 24.44030926 41.85190512
OS 24.44221172 41.85380758
OS 24.44474664 41.85507504
OS 24.45171894 41.86204734
OS 24.4529864 41.86458226
OS 24.45488886 41.86648472
OS 24.45742378 41.86775218
OS 24.46439608 41.87472448
OS 24.46566354 41.8772594
OS 24.467566 41.87915932
OS 24.47009838 41.88042932
OS 24.47580322 41.88613162
OS 24.47707068 41.88866654
OS 24.4802406 41.89183392
OS 24.48277552 41.89310392
OS 24.48974782 41.89880876
OS 24.49291774 41.90197614
OS 24.49925504 41.90451106
OS 24.50432742 41.90578106
OS 24.51827202 41.91465328
OS 24.53031162 41.91909066
OS 24.53601646 41.92226058
OS 24.53728392 41.92226058
OS 24.5486936 41.92733042
OS 24.56137074 41.92859788
OS 24.57278042 41.92986534
OS 24.58165264 41.93367026
OS 24.58799248 41.93620518
OS 24.59305978 41.93747264
OS 24.60763938 41.93937256
OS 24.63489358 41.94000756
OS 24.6386985 41.9387401
OE
SE
S P 0
OB 24.66785262 42.6689012 I
OS 24.671655 42.66763374
OS 24.68940198 42.66636628
OS 24.70334658 42.66003152
OS 24.70968388 42.65749406
OS 24.72109356 42.65115676
OS 24.73250324 42.64608692
OS 24.74391038 42.63974708
OS 24.75532006 42.63467724
OS 24.76672974 42.6283374
OS 24.76926212 42.62453502
OS 24.77179958 42.62326756
OS 24.77877188 42.61756272
OS 24.78447418 42.60932296
OS 24.78701164 42.6080555
OS 24.78891156 42.60615304
OS 24.79144648 42.59981828
OS 24.79334894 42.59284598
OS 24.79651886 42.5884086
OS 24.80285616 42.58206876
OS 24.80412362 42.57953384
OS 24.80982846 42.57256154
OS 24.81299838 42.56939162
OS 24.81426584 42.5668567
OS 24.81680076 42.5605194
OS 24.81997068 42.55227964
OS 24.82567552 42.54277242
OS 24.82821044 42.53263274
OS 24.83011036 42.52185552
OS 24.8358152 42.50727846
OS 24.83835012 42.48953148
OS 24.84025258 42.45340252
OS 24.84088504 42.44009292
OS 24.83961758 42.43629054
OS 24.83835012 42.40079658
OS 24.83708266 42.3969942
OS 24.8358152 42.3830496
OS 24.82947536 42.369105
OS 24.82631052 42.36086524
OS 24.82187314 42.35389294
OS 24.8155333 42.33994834
OS 24.809196 42.3285412
OS 24.80412362 42.31713152
OS 24.79905378 42.30825676
OS 24.79398394 42.30318946
OS 24.79271648 42.300652
OS 24.78701164 42.2936797
OS 24.78447418 42.29241224
OS 24.78003934 42.28797486
OS 24.77877188 42.28543994
OS 24.7743345 42.28100256
OS 24.7679972 42.27720018
OS 24.7616599 42.27086288
OS 24.75658752 42.26959542
OS 24.74834776 42.2664255
OS 24.740108 42.25818574
OS 24.73123324 42.25311336
OS 24.7261634 42.24804352
OS 24.7198261 42.2455086
OS 24.71538872 42.2448736
OS 24.71475372 42.24424368
OS 24.70334658 42.24297622
OS 24.68686706 42.23536892
OS 24.67672484 42.232834
OS 24.65897786 42.23156654
OS 24.65264056 42.22903162
OS 24.6444008 42.2258617
OS 24.6374285 42.22395924
OS 24.63235866 42.22269178
OS 24.6234839 42.22142432
OS 24.61841406 42.22015686
OS 24.60193454 42.22142432
OS 24.59813216 42.22269178
OS 24.58988986 42.22459424
OS 24.5835551 42.22712916
OS 24.5689755 42.23156654
OS 24.55629836 42.232834
OS 24.54615868 42.23410146
OS 24.52460932 42.24424368
OS 24.51636956 42.24741106
OS 24.5144671 42.24931098
OS 24.51193218 42.25057844
OS 24.50432742 42.25565082
OS 24.49735512 42.25755074
OS 24.49291774 42.2594532
OS 24.48594544 42.26515804
OS 24.48277552 42.26832796
OS 24.4802406 42.26959542
OS 24.47453576 42.27530026
OS 24.4732683 42.27783518
OS 24.47009838 42.28100256
OS 24.467566 42.28227256
OS 24.46312862 42.2867074
OS 24.46186116 42.28924486
OS 24.45869124 42.29241224
OS 24.45615632 42.2936797
OS 24.45045148 42.29938454
OS 24.44918402 42.30191946
OS 24.4460141 42.30508684
OS 24.44347918 42.3063543
OS 24.4390418 42.31079168
OS 24.43777434 42.3133266
OS 24.43016958 42.3209339
OS 24.42889958 42.32346882
OS 24.42636466 42.32980866
OS 24.4250972 42.3348785
OS 24.41622498 42.34755564
OS 24.41432252 42.35452794
OS 24.4117876 42.36086524
OS 24.4060853 42.37163992
OS 24.40355038 42.38051214
OS 24.399113 42.40776888
OS 24.39721054 42.41220626
OS 24.39467562 42.41854356
OS 24.39340816 42.42361594
OS 24.3921407 42.43248562
OS 24.39087324 42.44516276
OS 24.3921407 42.47431942
OS 24.39340816 42.47812434
OS 24.39467562 42.48699402
OS 24.40101292 42.50093862
OS 24.40228038 42.51742068
OS 24.4054503 42.53073028
OS 24.41242006 42.54404242
OS 24.41558998 42.55227964
OS 24.4181249 42.55861694
OS 24.42129482 42.56178686
OS 24.42256228 42.56432178
OS 24.42636466 42.57319654
OS 24.42953458 42.5814363
OS 24.43777434 42.58967606
OS 24.4390418 42.59221098
OS 24.45742378 42.61059042
OS 24.4599587 42.61185788
OS 24.46186116 42.61376034
OS 24.46312862 42.61629526
OS 24.48277552 42.6359447
OS 24.48531044 42.63721216
OS 24.49165028 42.64354946
OS 24.49798758 42.64608692
OS 24.50622734 42.6492543
OS 24.51953948 42.6562266
OS 24.52967916 42.65876406
OS 24.53918638 42.66066398
OS 24.54996106 42.66509882
OS 24.5550309 42.66636628
OS 24.56770804 42.66763374
OS 24.58418756 42.6689012
OS 24.61207676 42.6701712
OS 24.66785262 42.6689012
OE
SE
S P 0
OB 31.31665568 44.95700432 I
OS 31.3204606 44.95573686
OS 31.3546871 44.9544694
OS 31.35848948 44.95320194
OS 31.36482932 44.95193448
OS 31.37116408 44.94939702
OS 31.37623646 44.94812956
OS 31.39398344 44.94559464
OS 31.40729304 44.94242726
OS 31.4231401 44.93545496
OS 31.43201232 44.9341875
OS 31.43708216 44.93292004
OS 31.44532192 44.92975012
OS 31.44722438 44.9278502
OS 31.4497593 44.92658274
OS 31.45863406 44.92277782
OS 31.46687382 44.91961044
OS 31.47384612 44.91517306
OS 31.48778818 44.90883322
OS 31.49412548 44.90503084
OS 31.49919786 44.899961
OS 31.50173278 44.89869354
OS 31.51124 44.89172124
OS 31.511875 44.88981878
OS 31.51440992 44.88855132
OS 31.52708706 44.88348148
OS 31.52962198 44.88221402
OS 31.53722928 44.87460926
OS 31.5397642 44.8733418
OS 31.54420158 44.87017188
OS 31.54546904 44.86763696
OS 31.54800142 44.86510204
OS 31.54863642 44.86319958
OS 31.55117134 44.86193212
OS 31.60757966 44.80552126
OS 31.60884966 44.80298634
OS 31.61645442 44.79537904
OS 31.61898934 44.78904174
OS 31.6202568 44.7839719
OS 31.62913156 44.77002476
OS 31.63039902 44.76495492
OS 31.63927378 44.74847794
OS 31.64307616 44.73960318
OS 31.64561108 44.73326588
OS 31.65068346 44.72439112
OS 31.65448584 44.71551636
OS 31.6563883 44.70347676
OS 31.66019068 44.69333454
OS 31.6633606 44.68636224
OS 31.66462806 44.6812924
OS 31.66589552 44.67241764
OS 31.66716298 44.6673478
OS 31.6690629 44.64516344
OS 31.67033036 44.6400936
OS 31.6760352 44.62171162
OS 31.67793512 44.6058671
OS 31.67920258 44.58305028
OS 31.67983758 44.57988036
OS 31.67857012 44.57607798
OS 31.67730266 44.54692132
OS 31.6760352 44.54311894
OS 31.6747652 44.53424418
OS 31.67223028 44.52790434
OS 31.66969536 44.51903466
OS 31.6684279 44.51396228
OS 31.66652798 44.49177792
OS 31.66526052 44.48417316
OS 31.66399306 44.47783332
OS 31.66145814 44.47149602
OS 31.65828822 44.46452372
OS 31.6557533 44.4556515
OS 31.65385084 44.44487682
OS 31.65131592 44.43853698
OS 31.649416 44.43663706
OS 31.64307616 44.42269246
OS 31.63990624 44.41445016
OS 31.63546886 44.40874786
OS 31.6342014 44.4062104
OS 31.63166648 44.39987564
OS 31.62849656 44.39163588
OS 31.62152426 44.38466358
OS 31.6202568 44.38212866
OS 31.61138458 44.37071898
OS 31.60884966 44.36818406
OS 31.60441482 44.35613938
OS 31.6012449 44.351702
OS 31.59617506 44.34663216
OS 31.59490506 44.34409724
OS 31.59237014 44.34156232
OS 31.59173768 44.3396624
OS 31.58920276 44.33839494
OS 31.5258196 44.27501178
OS 31.52328468 44.27374432
OS 31.51694484 44.26740448
OS 31.51060754 44.26486956
OS 31.50236778 44.26170218
OS 31.49666294 44.25599734
OS 31.49412548 44.25472988
OS 31.49159056 44.25219242
OS 31.4852558 44.24839004
OS 31.47891596 44.24205274
OS 31.46307144 44.2363479
OS 31.46116898 44.23444544
OS 31.45863406 44.23317798
OS 31.4497593 44.2293756
OS 31.44088708 44.22810814
OS 31.4358147 44.22684068
OS 31.42757748 44.2236733
OS 31.41933772 44.21923592
OS 31.41046296 44.216701
OS 31.40159074 44.21543354
OS 31.38954606 44.21099616
OS 31.38384122 44.2090937
OS 31.374969 44.20782624
OS 31.3267979 44.20529132
OS 31.22665586 44.20402386
OS 30.5471957 44.2027564
OS 30.54339332 44.20148894
OS 30.50155952 44.20021894
OS 30.49775714 44.19895148
OS 30.48761492 44.19768402
OS 30.4787427 44.19388164
OS 30.46860048 44.19134672
OS 30.46099572 44.19007926
OS 30.4445162 44.18247196
OS 30.43564398 44.17993704
OS 30.42676922 44.17866958
OS 30.41852946 44.17549966
OS 30.40902224 44.16979482
OS 30.3969801 44.16535744
OS 30.3900078 44.16092514
OS 30.3760632 44.1545853
OS 30.36465352 44.148248
OS 30.35324384 44.14317562
OS 30.34437416 44.13810578
OS 30.34183924 44.13557086
OS 30.33930178 44.1343034
OS 30.3354994 44.13049848
OS 30.33296448 44.12923102
OS 30.3285271 44.12479364
OS 30.32725964 44.12225872
OS 30.32408972 44.1190888
OS 30.3215548 44.11782134
OS 30.31584996 44.1121165
OS 30.3145825 44.10958158
OS 30.31268004 44.10768166
OS 30.31014512 44.1064142
OS 30.30444028 44.1007119
OS 30.30317282 44.09817444
OS 30.3000029 44.09500706
OS 30.29746798 44.0937396
OS 30.29176314 44.08803476
OS 30.29049568 44.0854973
OS 30.2873283 44.08232992
OS 30.28479338 44.08106246
OS 30.280356 44.07662508
OS 30.27908854 44.07409016
OS 30.27528616 44.07028524
OS 30.2740187 44.06775032
OS 30.27021632 44.06394794
OS 30.26577894 44.05190326
OS 30.26134156 44.04493096
OS 30.25500426 44.0309889
OS 30.2524668 44.0246516
OS 30.2461295 44.01577684
OS 30.24169212 44.0037347
OS 30.23535482 43.99359248
OS 30.2321849 43.98662018
OS 30.22901498 43.97838296
OS 30.2264826 43.97204312
OS 30.22458014 43.9701432
OS 30.22331268 43.96760828
OS 30.22077776 43.96126844
OS 30.2195103 43.95239622
OS 30.21824284 43.94732384
OS 30.21507292 43.93908408
OS 30.211903 43.9283094
OS 30.21063554 43.9156348
OS 30.20936808 43.89915528
OS 30.20746816 43.87570092
OS 30.20683316 43.86239386
OS 30.20810062 43.85858894
OS 30.21000308 43.82879982
OS 30.21127054 43.81485522
OS 30.212538 43.80724792
OS 30.21634038 43.79710824
OS 30.21824284 43.79013594
OS 30.2195103 43.7850661
OS 30.22141276 43.77555888
OS 30.22394768 43.76921904
OS 30.23091744 43.75337452
OS 30.23345236 43.738165
OS 30.2385222 43.72929024
OS 30.24232712 43.72041548
OS 30.24486204 43.71407818
OS 30.24866442 43.70773834
OS 30.25500426 43.70140104
OS 30.25880664 43.6950612
OS 30.26514394 43.6887239
OS 30.2676814 43.6823866
OS 30.27084878 43.67414684
OS 30.2740187 43.66970946
OS 30.27908854 43.66463962
OS 30.280356 43.6621047
OS 30.29873544 43.64372272
OS 30.3012729 43.64245526
OS 30.30317282 43.6405528
OS 30.30444028 43.63801788
OS 30.31141258 43.63104558
OS 30.31395004 43.62977812
OS 30.31584996 43.62787566
OS 30.31711742 43.62534074
OS 30.32408972 43.61837098
OS 30.32662464 43.61710352
OS 30.3285271 43.61520106
OS 30.32979456 43.61266614
OS 30.3354994 43.6069613
OS 30.33803432 43.60569384
OS 30.34437416 43.59935654
OS 30.34690908 43.59808908
OS 30.35324384 43.59555162
OS 30.35831622 43.59428416
OS 30.36528852 43.58857932
OS 30.3697259 43.58414448
OS 30.37226082 43.58287448
OS 30.37923312 43.57717218
OS 30.38240304 43.57400226
OS 30.38874034 43.57146734
OS 30.40078248 43.56702996
OS 30.40268494 43.5651275
OS 30.40521986 43.56386258
OS 30.41409208 43.5600602
OS 30.42296684 43.55879274
OS 30.42993914 43.55689028
OS 30.43627644 43.55435536
OS 30.4521235 43.54738306
OS 30.46416564 43.5454806
OS 30.48254508 43.53977576
OS 30.49522222 43.5385083
OS 30.53008118 43.53660838
OS 30.58078974 43.53533838
OS 34.74500544 43.53407092
OS 34.794444 43.53280346
OS 34.81726336 43.531536
OS 34.84198264 43.52963608
OS 34.8483174 43.52709862
OS 34.85719216 43.5245637
OS 34.86606692 43.52329624
OS 34.88571636 43.52139378
OS 34.89332112 43.52012632
OS 34.8983935 43.51885886
OS 34.9047308 43.51632394
OS 34.91170056 43.51315402
OS 34.92184278 43.5106191
OS 34.93135 43.50871664
OS 34.93768984 43.50618172
OS 34.93958976 43.5042818
OS 34.95353436 43.4979445
OS 34.96177412 43.49477458
OS 34.96367658 43.49287466
OS 34.9662115 43.4916072
OS 34.98015356 43.48526736
OS 34.99156324 43.47893006
OS 34.99409816 43.47639514
OS 35.00107046 43.47449268
OS 35.0074103 43.47195776
OS 35.01184768 43.46878784
OS 35.01691752 43.463718
OS 35.01945244 43.46245054
OS 35.02198736 43.45991308
OS 35.02452482 43.45864562
OS 35.02768966 43.45420824
OS 35.0333945 43.44850594
OS 35.03592942 43.44723594
OS 35.04226926 43.44090118
OS 35.04480418 43.43963372
OS 35.05114402 43.4370988
OS 35.05621386 43.4358288
OS 35.06318616 43.4301265
OS 35.06762354 43.42568912
OS 35.07015846 43.42442166
OS 35.0758633 43.41871682
OS 35.07713076 43.4161819
OS 35.08030068 43.41174452
OS 35.0828356 43.41047706
OS 35.08600552 43.40477222
OS 35.09043782 43.39272754
OS 35.09741266 43.38575524
OS 35.09868012 43.38322286
OS 35.10691988 43.3749831
OS 35.1094548 43.37371564
OS 35.11452464 43.36610834
OS 35.12149694 43.35913604
OS 35.12720178 43.34329152
OS 35.1303717 43.3401216
OS 35.13163916 43.33758668
OS 35.136709 43.326177
OS 35.13924646 43.3198397
OS 35.14558376 43.31096748
OS 35.14684868 43.3058951
OS 35.1493836 43.2995578
OS 35.15825836 43.28054082
OS 35.16079328 43.26279638
OS 35.16269574 43.2520217
OS 35.16713312 43.2374421
OS 35.16840058 43.22856988
OS 35.1703005 43.20511552
OS 35.1715705 43.17215902
OS 35.17220296 43.13349514
OS 35.1709355 43.12969276
OS 35.16966804 43.0865915
OS 35.16840058 43.08279166
OS 35.16713312 43.06250722
OS 35.1645982 43.05616992
OS 35.16206074 43.04729516
OS 35.15952582 43.02954818
OS 35.15762336 43.0200435
OS 35.15508844 43.01370366
OS 35.15318852 43.0118012
OS 35.14811614 42.99912406
OS 35.14494876 42.9908843
OS 35.14304884 42.98898438
OS 35.14178138 42.98644946
OS 35.13924646 42.983912
OS 35.13290662 42.96743248
OS 35.12530186 42.95983026
OS 35.12403186 42.9572928
OS 35.11832956 42.9503205
OS 35.1164271 42.94842058
OS 35.11515964 42.94588312
OS 35.11135726 42.9370109
OS 35.10628488 42.92813614
OS 35.09994758 42.92179884
OS 35.09868012 42.91926392
OS 35.07903322 42.89961702
OS 35.07713076 42.89898202
OS 35.0758633 42.8964471
OS 35.06762354 42.88820734
OS 35.06572108 42.88757234
OS 35.06445362 42.88503742
OS 35.04353672 42.86412052
OS 35.0410018 42.86285306
OS 35.03783188 42.85841568
OS 35.03212704 42.85271084
OS 35.02959212 42.85144338
OS 35.02198736 42.84383862
OS 35.01565006 42.8413037
OS 35.0074103 42.83813378
OS 34.999803 42.83306394
OS 34.9928307 42.82989402
OS 34.98459094 42.82672664
OS 34.97761864 42.82228926
OS 34.9662115 42.81721688
OS 34.9522669 42.80961212
OS 34.9383223 42.80327228
OS 34.91930786 42.79440006
OS 34.90156088 42.79186514
OS 34.8907862 42.78996268
OS 34.8762066 42.7855253
OS 34.87113676 42.78425784
OS 34.83754526 42.78235792
OS 34.78557178 42.78109046
OS 32.1349243 42.779823
OS 32.1342893 42.77919054
OS 32.13048692 42.780458
OS 32.11020248 42.77919054
OS 32.04682186 42.77792054
OS 32.04301694 42.77665308
OS 32.01386282 42.77538562
OS 32.01006044 42.77411816
OS 32.0037206 42.77158324
OS 31.99484838 42.76904832
OS 31.98217124 42.76778086
OS 31.97709886 42.7665134
OS 31.96696172 42.76524594
OS 31.95047966 42.75763864
OS 31.94540982 42.75637118
OS 31.93463514 42.75446872
OS 31.92639538 42.75130134
OS 31.91245078 42.7449615
OS 31.90738094 42.74369404
OS 31.89723872 42.74242658
OS 31.88583158 42.73608674
OS 31.87695682 42.73228436
OS 31.86871706 42.72911444
OS 31.86110976 42.72277968
OS 31.85920984 42.72087722
OS 31.85667492 42.71960976
OS 31.85413746 42.71707484
OS 31.85223754 42.71643984
OS 31.85097008 42.71390492
OS 31.84273032 42.70566516
OS 31.8401954 42.7043977
OS 31.8338581 42.6980604
OS 31.82751826 42.69552294
OS 31.8192785 42.69235556
OS 31.81484112 42.68918564
OS 31.80850382 42.6828458
OS 31.8059689 42.68157834
OS 31.7989966 42.67460604
OS 31.79772914 42.67207112
OS 31.79329176 42.6689012
OS 31.78885438 42.66446636
OS 31.78758692 42.66193144
OS 31.78378708 42.65812906
OS 31.78315208 42.6562266
OS 31.78124962 42.65559414
OS 31.77998216 42.65305922
OS 31.77744724 42.64671938
OS 31.77427732 42.63847962
OS 31.76603756 42.63023986
OS 31.7647701 42.62770494
OS 31.75906526 42.62073264
OS 31.75589534 42.61756272
OS 31.75336042 42.61122542
OS 31.75019304 42.60298566
OS 31.74512066 42.5953809
OS 31.73941582 42.58206876
OS 31.73434598 42.57319654
OS 31.72674122 42.55671702
OS 31.72040392 42.54277242
OS 31.71913646 42.53770258
OS 31.717234 42.52185552
OS 31.71469908 42.49650378
OS 31.71343162 42.48889648
OS 31.71216416 42.48255918
OS 31.7108967 42.47748934
OS 31.70899424 42.47051704
OS 31.70772678 42.4654472
OS 31.70519186 42.45023514
OS 31.7039244 42.437558
OS 31.70519186 42.42868324
OS 31.70709178 42.41664364
OS 31.70835924 42.4103038
OS 31.70962924 42.40523396
OS 31.71279662 42.39445674
OS 31.71406408 42.3893869
OS 31.71533154 42.38051214
OS 31.71660154 42.367835
OS 31.71850146 42.3557954
OS 31.71976892 42.35072556
OS 31.72357384 42.34058334
OS 31.72674122 42.33234358
OS 31.72800614 42.3272712
OS 31.7299086 42.31649652
OS 31.73244352 42.31015922
OS 31.73434598 42.30825676
OS 31.73814836 42.29938454
OS 31.74131828 42.29114478
OS 31.74322074 42.2867074
OS 31.74955804 42.2803701
OS 31.7508255 42.27783518
OS 31.75336042 42.27530026
OS 31.75716534 42.26896042
OS 31.75906526 42.26705796
OS 31.76096772 42.2664255
OS 31.76223518 42.26389058
OS 31.7647701 42.25755074
OS 31.76794002 42.24931098
OS 31.77491232 42.24234122
OS 31.77617978 42.2398063
OS 31.7913893 42.22459424
OS 31.7920243 42.22269178
OS 31.79455922 42.22142432
OS 31.81547612 42.20050742
OS 31.81610858 42.19860496
OS 31.81864604 42.1973375
OS 31.8338581 42.18212798
OS 31.83639302 42.18086052
OS 31.84273032 42.17452322
OS 31.85667492 42.16945084
OS 31.86427968 42.16184608
OS 31.8668146 42.16057608
OS 31.87822428 42.15170386
OS 31.88963396 42.14663148
OS 31.90104364 42.14029418
OS 31.90357856 42.13775926
OS 31.90864586 42.1364918
OS 31.9149857 42.13395688
OS 31.93653506 42.1238172
OS 31.94794474 42.12254974
OS 31.95428458 42.12001228
OS 31.96696172 42.1162099
OS 31.97202902 42.11494244
OS 32.01259536 42.11367498
OS 32.01639774 42.11240752
OS 32.058864 42.11177252
OS 32.06203392 42.11240752
OS 32.0658363 42.11114006
OS 33.016571 42.1098726
OS 33.02037338 42.10860514
OS 33.05840226 42.10733768
OS 33.06220464 42.10606768
OS 33.06917694 42.10416776
OS 33.0774167 42.10099784
OS 33.09516622 42.09846292
OS 33.1053059 42.09719546
OS 33.1116432 42.09466054
OS 33.1255878 42.0883207
OS 33.13446256 42.08705324
OS 33.14270232 42.08515078
OS 33.14903962 42.08261586
OS 33.15094208 42.08071594
OS 33.153477 42.07944594
OS 33.16488668 42.0743761
OS 33.1731239 42.07120618
OS 33.17502636 42.06930626
OS 33.17756128 42.0680388
OS 33.18389858 42.06423642
OS 33.19214088 42.06106904
OS 33.19847818 42.05853158
OS 33.2016481 42.0553642
OS 33.20418302 42.05409674
OS 33.21305778 42.05029182
OS 33.21939508 42.0477569
OS 33.22636738 42.04205206
OS 33.22953476 42.03888214
OS 33.23206968 42.03761468
OS 33.23777452 42.03190984
OS 33.23904198 42.02937492
OS 33.2422119 42.026205
OS 33.24474682 42.02493754
OS 33.25171912 42.0192327
OS 33.25488904 42.01606532
OS 33.26883364 42.01099294
OS 33.28467816 41.99515096
OS 33.28658062 41.98817866
OS 33.289113 41.98183882
OS 33.2960853 41.97486652
OS 33.29735276 41.9723316
OS 33.3030576 41.9653593
OS 33.30559252 41.96409184
OS 33.31256482 41.95711954
OS 33.31319982 41.95521708
OS 33.31573474 41.95394962
OS 33.32270704 41.94697732
OS 33.3239745 41.9444424
OS 33.3315818 41.93683764
OS 33.33411672 41.93050034
OS 33.33728664 41.92226058
OS 33.34045656 41.9178232
OS 33.34679386 41.91148336
OS 33.3505937 41.90514606
OS 33.35629854 41.89817376
OS 33.358201 41.89246892
OS 33.35946846 41.8835967
OS 33.36073592 41.87599194
OS 33.36707576 41.86711718
OS 33.37024314 41.85887742
OS 33.37404806 41.8487352
OS 33.37658298 41.8423979
OS 33.3784829 41.83669306
OS 33.37975036 41.83162322
OS 33.38165282 41.79676172
OS 33.38355528 41.72133642
OS 33.38228782 41.71753404
OS 33.38165282 41.68394254
OS 33.38228782 41.6719004
OS 33.38102036 41.66809548
OS 33.3791179 41.63323652
OS 33.37785044 41.62689922
OS 33.37531552 41.62055938
OS 33.3721456 41.6097847
OS 33.37087814 41.60471486
OS 33.36961068 41.5958401
OS 33.3645383 41.58696534
OS 33.35946846 41.5755582
OS 33.35186116 41.5616136
OS 33.34679386 41.55020646
OS 33.33918656 41.53625932
OS 33.33538418 41.5273871
OS 33.32904688 41.51597996
OS 33.32270704 41.50964012
OS 33.32143958 41.5071052
OS 33.31446728 41.5001329
OS 33.31193236 41.49886544
OS 33.30876244 41.49442806
OS 33.30432506 41.48999322
OS 33.30179014 41.48872322
OS 33.29862022 41.48555584
OS 33.29735276 41.48302092
OS 33.29164792 41.47731608
OS 33.289113 41.47604862
OS 33.28721308 41.47414616
OS 33.28594562 41.47161124
OS 33.27897332 41.46463894
OS 33.2764384 41.46337148
OS 33.27453848 41.46147156
OS 33.27327102 41.45893664
OS 33.25488904 41.44055466
OS 33.25235158 41.4392872
OS 33.25045166 41.43738474
OS 33.2491842 41.43484982
OS 33.24347936 41.42914498
OS 33.24094444 41.42787752
OS 33.23333714 41.42027022
OS 33.22700238 41.4177353
OS 33.21876008 41.41456538
OS 33.21432524 41.411398
OS 33.21305778 41.40886308
OS 33.21052032 41.40759308
OS 33.19911318 41.3987234
OS 33.19530826 41.39491848
OS 33.17946374 41.38921364
OS 33.17756128 41.38731372
OS 33.16615414 41.38224134
OS 33.1610843 41.38097388
OS 33.14903962 41.37907396
OS 33.13065764 41.36956674
OS 33.1179805 41.36449436
OS 33.1065759 41.35942452
OS 33.09072884 41.35752206
OS 33.07678424 41.3562546
OS 33.06537456 41.35498714
OS 33.04889504 41.35245222
OS 33.0438252 41.35118476
OS 33.03812036 41.3492823
OS 33.02544576 41.34801484
OS 32.97727466 41.34547992
OS 32.93100348 41.34484492
OS 32.92910102 41.34547992
OS 32.92530118 41.344215
OS 31.374334 41.34358
OS 31.37116408 41.344215
OS 31.36736424 41.34294754
OS 31.31158584 41.34167754
OS 31.30778346 41.34041008
OS 31.28243172 41.33914262
OS 31.27102204 41.33407278
OS 31.2646822 41.33153786
OS 31.25327506 41.32519802
OS 31.24186792 41.32012818
OS 31.22792332 41.31252088
OS 31.21651364 41.30745104
OS 31.20256904 41.29984374
OS 31.19369428 41.29604136
OS 31.18228714 41.28970406
OS 31.1772173 41.28463168
OS 31.17468238 41.28336676
OS 31.170245 41.28019684
OS 31.16897754 41.27766192
OS 31.16200524 41.27068962
OS 31.15947032 41.26942216
OS 31.15186302 41.2618174
OS 31.14552318 41.25927994
OS 31.13728342 41.25611256
OS 31.12651128 41.24533534
OS 31.12460882 41.24470288
OS 31.12334136 41.24216796
OS 31.11953898 41.2332932
OS 31.11446914 41.22442098
OS 31.1081293 41.21808368
OS 31.10432692 41.21174384
OS 31.09798708 41.20540654
OS 31.09291724 41.19146194
OS 31.08847986 41.1857571
OS 31.08657994 41.1851221
OS 31.08531248 41.18258718
OS 31.07643772 41.1711775
OS 31.0739028 41.16864258
OS 31.07136534 41.16230782
OS 31.06819796 41.15406552
OS 31.0612282 41.14075592
OS 31.05996074 41.13568608
OS 31.05869074 41.12681132
OS 31.0542559 41.11476918
OS 31.04855106 41.10145958
OS 31.0466486 41.08434506
OS 31.04538114 41.0767403
OS 31.04411368 41.07166792
OS 31.0403113 41.06152824
OS 31.03904384 41.05645586
OS 31.03777384 41.0488511
OS 31.03523892 41.01842698
OS 31.03460646 41.01399214
OS 31.03587392 41.01018722
OS 31.03777384 40.98293556
OS 31.03904384 40.97532826
OS 31.0403113 40.97025842
OS 31.04284622 40.96391858
OS 31.04474614 40.95694628
OS 31.04601614 40.95187644
OS 31.0472836 40.9391993
OS 31.04855106 40.93412946
OS 31.04981852 40.9252547
OS 31.05742328 40.90877772
OS 31.06186066 40.88912828
OS 31.07009788 40.87328122
OS 31.0732678 40.86504146
OS 31.07643772 40.86060662
OS 31.07897264 40.8580717
OS 31.0802401 40.85553678
OS 31.08277502 40.85300186
OS 31.08404248 40.8504644
OS 31.08657994 40.84792948
OS 31.0878474 40.84539456
OS 31.0941847 40.83905726
OS 31.09608716 40.83208242
OS 31.09862208 40.82574512
OS 31.10559438 40.81877282
OS 31.10686184 40.8162379
OS 31.10939676 40.81370298
OS 31.11066422 40.81116552
OS 31.1151016 40.80799814
OS 31.1220739 40.80102838
OS 31.1227089 40.79912592
OS 31.12524382 40.79785846
OS 31.14615818 40.77694156
OS 31.14742564 40.77440664
OS 31.15186302 40.77123672
OS 31.15883532 40.76426442
OS 31.15947032 40.76236196
OS 31.16200524 40.7610945
OS 31.170245 40.75285474
OS 31.17087746 40.75095228
OS 31.17341492 40.74968482
OS 31.1772173 40.74588244
OS 31.17975222 40.74461498
OS 31.18608952 40.73827768
OS 31.20193404 40.73257538
OS 31.2038365 40.73067292
OS 31.20637142 40.72940546
OS 31.20890634 40.72687054
OS 31.21397872 40.72560308
OS 31.22285094 40.72179816
OS 31.23552808 40.7141934
OS 31.24186792 40.71165848
OS 31.25010514 40.70848856
OS 31.26341474 40.70151626
OS 31.26848712 40.7002488
OS 31.2792618 40.69834634
OS 31.28940402 40.69454396
OS 31.30398108 40.69010658
OS 31.3128533 40.68883912
OS 31.3407425 40.68757166
OS 31.34454488 40.6863042
OS 31.36292686 40.68440428
OS 31.37053162 40.68313682
OS 31.38067384 40.6806019
OS 31.39461844 40.67933444
OS 31.45102676 40.67616452
OS 31.57018578 40.67489706
OS 32.48796398 40.6736296
OS 32.49176636 40.67236214
OS 32.52599032 40.67109214
OS 32.53233016 40.66855722
OS 32.54120238 40.66475484
OS 32.55007714 40.66348738
OS 32.55514952 40.66221992
OS 32.56212182 40.66031746
OS 32.57669634 40.65334516
OS 32.5855711 40.65081024
OS 32.59571332 40.64954278
OS 32.60458554 40.64447294
OS 32.61853014 40.6381331
OS 32.62486998 40.63559818
OS 32.63373966 40.62925834
OS 32.64578434 40.6248235
OS 32.65212164 40.62102112
OS 32.6533891 40.6184862
OS 32.65909394 40.61404882
OS 32.66162886 40.61278136
OS 32.66606624 40.60834398
OS 32.6673337 40.60580906
OS 32.67050362 40.60263914
OS 32.67303854 40.60137168
OS 32.68001084 40.59566684
OS 32.68444822 40.591232
OS 32.6939529 40.58932954
OS 32.69839028 40.58742708
OS 32.70029274 40.58552716
OS 32.7015602 40.58045478
OS 32.70346266 40.57221502
OS 32.70663004 40.56777764
OS 32.71360234 40.56587772
OS 32.71994218 40.5646128
OS 32.72437956 40.56144288
OS 32.72691448 40.55256812
OS 32.72818194 40.54749828
OS 32.7357867 40.53989098
OS 32.7370567 40.53735606
OS 32.742759 40.53038376
OS 32.7497313 40.52467892
OS 32.7554336 40.51643916
OS 32.75797106 40.5151717
OS 32.75987098 40.51326924
OS 32.7624059 40.50693194
OS 32.7636759 40.5018621
OS 32.76874574 40.49298988
OS 32.77128066 40.49045496
OS 32.77381558 40.48411512
OS 32.7769855 40.47587536
OS 32.78332534 40.46573314
OS 32.78649272 40.45876084
OS 32.7909301 40.4467187
OS 32.79283256 40.44481624
OS 32.7979024 40.4334091
OS 32.79916986 40.42453688
OS 32.80043732 40.4194645
OS 32.80677716 40.40298498
OS 32.80804208 40.39791514
OS 32.80994454 40.38080316
OS 32.811212 40.37066094
OS 32.81247946 40.35291396
OS 32.81374692 40.3377019
OS 32.81501438 40.33136206
OS 32.81881676 40.32122238
OS 32.82135168 40.31488508
OS 32.82325414 40.30791278
OS 32.82198668 40.29396818
OS 32.81691684 40.2825585
OS 32.81311192 40.26734644
OS 32.811212 40.23755732
OS 32.80867454 40.21727542
OS 32.80740708 40.20586574
OS 32.80043732 40.18875376
OS 32.79916986 40.179879
OS 32.7979024 40.17480916
OS 32.79473248 40.1665694
OS 32.78776018 40.15072234
OS 32.78586026 40.13868274
OS 32.78332534 40.1323429
OS 32.7776205 40.12283568
OS 32.77254812 40.10889108
OS 32.76684328 40.10191878
OS 32.7636759 40.09874886
OS 32.7624059 40.09621394
OS 32.7567036 40.08924164
OS 32.75353368 40.08607172
OS 32.75099876 40.07973696
OS 32.74782884 40.0714972
OS 32.73959162 40.06325744
OS 32.7357867 40.0569176
OS 32.73388678 40.05501768
OS 32.73135186 40.05374768
OS 32.72564702 40.04804538
OS 32.72437956 40.04550792
OS 32.7224771 40.043608
OS 32.71994218 40.04234054
OS 32.71170242 40.03410078
OS 32.71106742 40.03219832
OS 32.7085325 40.03093086
OS 32.69902528 40.02142618
OS 32.69839028 40.01952372
OS 32.69585536 40.01825626
OS 32.68888306 40.01128396
OS 32.6876156 40.00874904
OS 32.68571568 40.00684658
OS 32.68318076 40.00557912
OS 32.67747592 39.99987428
OS 32.67620846 39.99733936
OS 32.67303854 39.99416944
OS 32.67050362 39.99290198
OS 32.66479878 39.98719714
OS 32.66353132 39.98466222
OS 32.6603614 39.9814923
OS 32.65782648 39.98022484
OS 32.65085418 39.97452
OS 32.64768426 39.97135008
OS 32.63564212 39.96691524
OS 32.63120474 39.96501278
OS 32.62866982 39.9624804
OS 32.62613744 39.96121294
OS 32.61726268 39.95740802
OS 32.61092538 39.9548731
OS 32.60205062 39.94980326
OS 32.59317586 39.94599834
OS 32.58430364 39.94473088
OS 32.57733134 39.94283096
OS 32.5709915 39.94029604
OS 32.5652892 39.93839358
OS 32.56021936 39.93712612
OS 32.54373984 39.93585866
OS 32.5044435 39.9345912
OS 32.47274938 39.93332374
OS 28.7338262 39.93268874
OS 28.7281239 39.93332374
OS 28.72432152 39.93205374
OS 28.70340462 39.93268874
OS 28.68122026 39.93205374
OS 28.67868534 39.93332374
OS 28.67488042 39.93205374
OS 28.6254444 39.92825136
OS 28.6178371 39.9269839
OS 28.61023234 39.92191406
OS 28.60769742 39.9206466
OS 28.60072512 39.91494176
OS 28.59312036 39.89846224
OS 28.5912179 39.86867312
OS 28.58995044 39.8509236
OS 28.58931544 39.8312767
OS 28.59058544 39.82874178
OS 28.58931544 39.8249394
OS 28.58868298 39.7634587
OS 28.58931544 39.51183106
OS 28.58804798 39.50802614
OS 28.58678052 39.40154426
OS 28.58551306 39.39774188
OS 28.5842456 39.3660503
OS 28.5779083 39.35210824
OS 28.57473838 39.34386848
OS 28.57220346 39.3387961
OS 28.56966854 39.33752864
OS 28.56269624 39.33055634
OS 28.56142624 39.32802142
OS 28.55445394 39.3248515
OS 28.54241434 39.32041412
OS 28.53544204 39.31724674
OS 28.52656728 39.31597928
OS 28.49170578 39.31407682
OS 28.4397323 39.31280936
OS 27.58217242 39.31217436
OS 27.57837004 39.31344182
OS 27.50991704 39.31470928
OS 27.50611212 39.31597928
OS 27.48456276 39.31724674
OS 27.47061816 39.32358404
OS 27.4623784 39.32675396
OS 27.4554061 39.33372626
OS 27.45287118 39.33499372
OS 27.44589888 39.34069856
OS 27.44082904 39.34830332
OS 27.43956158 39.35084078
OS 27.4357592 39.359713
OS 27.4351242 39.3793599
OS 27.4357592 39.38886712
OS 27.4344892 39.39267204
OS 27.43322174 39.39774188
OS 27.43385674 39.41739132
OS 27.43195428 39.43070092
OS 27.43322174 39.4345033
OS 27.43258928 39.45668766
OS 27.43322174 39.47253472
OS 27.43195428 39.4763371
OS 27.43322174 39.495349
OS 27.43195428 39.49915392
OS 27.43068682 39.64112976
OS 27.42941936 39.64493468
OS 27.4281519 39.68169356
OS 27.42308206 39.69310324
OS 27.4205446 39.69944308
OS 27.41927714 39.70451292
OS 27.41293984 39.71338768
OS 27.40343516 39.7228949
OS 27.39836278 39.72416236
OS 27.39519286 39.72479482
OS 27.39012302 39.72352736
OS 27.38251826 39.71719006
OS 27.37491096 39.70958276
OS 27.37237604 39.70324546
OS 27.36793866 39.69120078
OS 27.36476874 39.68296102
OS 27.36350128 39.67789118
OS 27.36223382 39.63859484
OS 27.36096636 39.63479246
OS 27.3596989 39.53464788
OS 27.3590639 39.43513576
OS 27.3596989 39.42436362
OS 27.35843144 39.42056124
OS 27.3590639 39.39964434
OS 27.35779644 39.3933045
OS 27.35652898 39.3730226
OS 27.35526152 39.35654562
OS 27.34575684 39.34069856
OS 27.34131946 39.33626118
OS 27.33878454 39.33499372
OS 27.33117724 39.32738642
OS 27.32483994 39.3248515
OS 27.31279526 39.32041412
OS 27.30582296 39.31724674
OS 27.30075312 39.31597928
OS 27.26082178 39.31407682
OS 27.2101183 39.31280936
OS 26.86468338 39.31217436
OS 26.860881 39.31344182
OS 26.79116054 39.31470928
OS 26.78735816 39.31597928
OS 26.76707372 39.31724674
OS 26.75566404 39.32231658
OS 26.74742682 39.3254865
OS 26.74045452 39.32992388
OS 26.73538468 39.33499372
OS 26.73284976 39.33626118
OS 26.72587746 39.34323348
OS 26.72461 39.3457684
OS 26.71953762 39.3533757
OS 26.71827016 39.35844554
OS 26.7163677 39.39203704
OS 26.71510024 39.39837688
OS 26.71446778 39.4078841
OS 26.71573524 39.41168648
OS 26.71446778 39.4345033
OS 26.71573524 39.43830568
OS 26.71446778 39.45859012
OS 26.71383278 39.77106346
OS 26.71446778 39.78564052
OS 26.71320032 39.7894429
OS 26.71446778 39.8109948
OS 26.71320032 39.81479718
OS 26.71193286 39.82367194
OS 26.7100304 39.85979836
OS 26.70876294 39.86740566
OS 26.70559302 39.87437796
OS 26.69988818 39.89022248
OS 26.69798826 39.89212494
OS 26.69671826 39.89465986
OS 26.69038096 39.9009997
OS 26.6891135 39.90353462
OS 26.6834112 39.90923692
OS 26.67707136 39.9130393
OS 26.67326898 39.91684168
OS 26.66693168 39.9193766
OS 26.6485497 39.92254652
OS 26.64411232 39.92571644
OS 26.63270264 39.93078628
OS 26.6212955 39.92951882
OS 26.61242328 39.92318152
OS 26.60608344 39.9206466
OS 26.59784368 39.91747668
OS 26.59213884 39.91177184
OS 26.58960392 39.91050438
OS 26.587069 39.90796946
OS 26.58453408 39.906702
OS 26.5800967 39.90226716
OS 26.57882924 39.8997297
OS 26.57565932 39.89656232
OS 26.5731244 39.89529486
OS 26.56868956 39.89085748
OS 26.56361718 39.88198272
OS 26.56108226 39.87564542
OS 26.5598148 39.87057304
OS 26.56108226 39.8655032
OS 26.5598148 39.85282606
OS 26.55727988 39.82113702
OS 26.55601242 39.8173321
OS 26.55727988 39.80845988
OS 26.55664488 39.78754298
OS 26.55727988 39.77296592
OS 26.55601242 39.76916354
OS 26.55664488 39.75331648
OS 26.55537742 39.67091888
OS 26.55474496 39.6664815
OS 26.55601242 39.66268166
OS 26.55474496 39.64620214
OS 26.5528425 39.59612858
OS 26.55157504 39.5859889
OS 26.54904012 39.57964906
OS 26.54460274 39.56887438
OS 26.54333528 39.563802
OS 26.53763044 39.5568297
OS 26.53446052 39.55366232
OS 26.53319306 39.5511274
OS 26.52748822 39.5441551
OS 26.51608108 39.53528288
OS 26.49326426 39.52514066
OS 26.48312204 39.52260574
OS 26.44192324 39.52070328
OS 26.4374884 39.52007082
OS 26.43368348 39.52133828
OS 26.41720396 39.52007082
OS 26.28663526 39.51880336
OS 26.25494622 39.52007082
OS 26.21374488 39.52070328
OS 26.20804258 39.52007082
OS 26.2042402 39.52133828
OS 26.1630414 39.5232382
OS 26.15796902 39.5245082
OS 26.14466196 39.5302105
OS 26.1364222 39.53338042
OS 26.13451974 39.53528288
OS 26.13198482 39.53655034
OS 26.12564498 39.54288764
OS 26.12311006 39.5441551
OS 26.11740522 39.5498574
OS 26.11613776 39.55239486
OS 26.10980046 39.55873216
OS 26.108533 39.56126708
OS 26.10472808 39.57014184
OS 26.1015607 39.5783816
OS 26.09839078 39.5853539
OS 26.09712332 39.59803104
OS 26.0945884 39.68296102
OS 26.09332094 39.80212004
OS 26.09205094 39.91494176
OS 26.08761864 39.9193766
OS 26.07937634 39.92127906
OS 26.06923666 39.92508144
OS 26.06226436 39.92825136
OS 26.02867286 39.93015382
OS 26.00838842 39.93142128
OS 25.93106066 39.93268874
OS 25.39294642 39.93332374
OS 25.38914404 39.93205374
OS 25.29533676 39.93078628
OS 25.29153438 39.92951882
OS 25.26047526 39.9276189
OS 25.25413796 39.92508144
OS 25.2471682 39.92191406
OS 25.23892844 39.9200116
OS 25.23449106 39.91810914
OS 25.23132114 39.91494176
OS 25.23005368 39.906067
OS 25.22942122 39.54795748
OS 25.23005368 39.53211296
OS 25.22878622 39.52831058
OS 25.23005368 39.5092936
OS 25.22878622 39.50549122
OS 25.22942122 39.48457686
OS 25.22815376 39.47950702
OS 25.22688376 39.47189972
OS 25.2262513 39.46619488
OS 25.22751876 39.46365996
OS 25.2262513 39.45985758
OS 25.22498384 39.43957314
OS 25.219279 39.43260084
OS 25.21420662 39.427531
OS 25.2053344 39.42499608
OS 25.17301036 39.42309616
OS 25.16667052 39.4218287
OS 25.16096822 39.4211937
OS 25.1571633 39.42246116
OS 25.14892354 39.42309616
OS 25.13878132 39.4218287
OS 25.1368814 39.4211937
OS 25.13307648 39.42246116
OS 25.1096272 39.4218287
OS 25.09251268 39.42246116
OS 25.0887103 39.4211937
OS 25.07223078 39.42246116
OS 25.06843094 39.4211937
OS 24.5151021 39.4218287
OS 24.50432742 39.4211937
OS 24.5005225 39.42246116
OS 24.4796056 39.4218287
OS 24.4599587 39.42246116
OS 24.45742378 39.4211937
OS 24.4536214 39.42246116
OS 24.44538164 39.42309616
OS 24.43523942 39.4218287
OS 24.42953458 39.4211937
OS 24.4257322 39.42246116
OS 24.41685744 39.42372862
OS 24.38706832 39.42562854
OS 24.38073102 39.42816346
OS 24.37185626 39.43703822
OS 24.36932134 39.44337806
OS 24.36805388 39.47887202
OS 24.36678642 39.4826744
OS 24.36551896 39.48774424
OS 24.36678642 39.50422376
OS 24.36551896 39.5169009
OS 24.36678642 39.52577566
OS 24.36551896 39.54225518
OS 24.36678642 39.55239486
OS 24.36551896 39.55619724
OS 24.36551896 39.73239958
OS 24.36551896 39.73366704
OS 24.36615142 39.81923456
OS 24.36551896 39.83381416
OS 24.36678642 39.83761654
OS 24.36551896 39.8578959
OS 24.36678642 39.86170082
OS 24.36615142 39.88261772
OS 24.36741888 39.88768756
OS 24.36868634 39.8940274
OS 24.36995634 39.92571644
OS 24.37629364 39.93585866
OS 24.38073102 39.94283096
OS 24.38263094 39.94473088
OS 24.3915057 39.94980326
OS 24.40038046 39.95360564
OS 24.42256228 39.95424064
OS 24.42699966 39.95360564
OS 24.43080204 39.9548731
OS 24.44030926 39.95677556
OS 24.44981648 39.95740802
OS 24.4536214 39.95614056
OS 24.47643822 39.95740802
OS 24.4802406 39.95614056
OS 24.5005225 39.95740802
OS 24.5074948 39.95677556
OS 24.89285852 39.95804302
OS 24.8972959 39.95994294
OS 24.89919836 39.9618454
OS 24.90046582 39.96691524
OS 24.90173328 39.97578746
OS 24.90046582 40.50946686
OS 24.89602844 40.5151717
OS 24.88715622 40.51643916
OS 24.51763702 40.51707416
OS 24.50305742 40.51643916
OS 24.49925504 40.51770662
OS 24.47833814 40.51707416
OS 24.46249362 40.51770662
OS 24.45869124 40.51643916
OS 24.44981648 40.51770662
OS 24.42889958 40.51707416
OS 24.42256228 40.51834162
OS 24.40101292 40.51960908
OS 24.38580086 40.52087654
OS 24.37882856 40.52531392
OS 24.3705888 40.53355368
OS 24.36932134 40.5424259
OS 24.36678642 40.57918732
OS 24.36551896 40.5829897
OS 24.36678642 40.60834398
OS 24.36551896 40.6121489
OS 24.36678642 40.63242826
OS 24.36805388 40.63623064
OS 24.36995634 40.66855722
OS 24.37312372 40.6729946
OS 24.37502618 40.67616452
OS 24.3775611 40.67743198
OS 24.38136348 40.68123436
OS 24.38770332 40.68376928
OS 24.42129482 40.6856692
OS 24.42636466 40.68693666
OS 24.43714188 40.68757166
OS 24.44094426 40.6863042
OS 24.46312862 40.68693666
OS 24.47516822 40.6863042
OS 24.47897314 40.68757166
OS 24.49101528 40.68693666
OS 24.49291774 40.68757166
OS 24.4941852 40.6863042
OS 24.49798758 40.68757166
OS 24.89476098 40.68883912
OS 24.89919836 40.69200904
OS 24.90173328 40.70214872
OS 24.90046582 41.2396305
OS 24.89602844 41.24533534
OS 24.88715622 41.2466028
OS 24.5011575 41.2472378
OS 24.48911282 41.2466028
OS 24.48531044 41.24787026
OS 24.46566354 41.2472378
OS 24.45805878 41.24850526
OS 24.45742378 41.24914026
OS 24.4536214 41.24787026
OS 24.44094426 41.2466028
OS 24.43714188 41.24787026
OS 24.42699966 41.25040772
OS 24.39530808 41.25167518
OS 24.39277316 41.2542101
OS 24.39023824 41.25547756
OS 24.37946356 41.26244986
OS 24.3781961 41.26498478
OS 24.37185626 41.27385954
OS 24.36932134 41.28019684
OS 24.36741888 41.31378834
OS 24.36615142 41.32139564
OS 24.36551896 41.3372427
OS 24.36678642 41.34104508
OS 24.36551896 41.36639682
OS 24.36678642 41.3701992
OS 24.36805388 41.38667872
OS 24.3705888 41.41329792
OS 24.38136348 41.42407514
OS 24.3915057 41.42661006
OS 24.398478 41.42597506
OS 24.42002736 41.42724252
OS 24.4250972 41.42850998
OS 24.4396768 41.42914498
OS 24.44347918 41.42787752
OS 24.4599587 41.42914498
OS 24.89349352 41.43041244
OS 24.89919836 41.43484982
OS 24.90046582 41.43991966
OS 24.90173328 41.44879442
OS 24.90046582 41.98247382
OS 24.89792836 41.98500874
OS 24.8972959 41.9869112
OS 24.88842368 41.98944612
OS 24.4796056 41.99007858
OS 24.46376362 41.98944612
OS 24.4599587 41.99071358
OS 24.43840934 41.98944612
OS 24.4320695 41.99198104
OS 24.39657808 41.9932485
OS 24.38770332 41.9995858
OS 24.38136348 42.00339072
OS 24.3781961 42.0065581
OS 24.37692864 42.00909302
OS 24.3705888 42.0192327
OS 24.36932134 42.02430508
OS 24.36741888 42.05029182
OS 24.36615142 42.06296896
OS 24.36551896 42.09022316
OS 24.36678642 42.09402554
OS 24.36805388 42.12698458
OS 24.36932134 42.13078696
OS 24.3705888 42.1434641
OS 24.37692864 42.1574087
OS 24.37882856 42.16564846
OS 24.38073102 42.16754838
OS 24.38136348 42.16945084
OS 24.38770332 42.17198576
OS 24.89602844 42.17325322
OS 24.89919836 42.17642314
OS 24.90046582 42.18149552
OS 24.90173328 42.1903652
OS 24.90046582 42.72404714
OS 24.89602844 42.72974944
OS 24.89095606 42.7310169
OS 24.4872129 42.7316519
OS 24.47897314 42.7310169
OS 24.47516822 42.73228436
OS 24.45425386 42.7316519
OS 24.44791656 42.73291936
OS 24.44347918 42.73355182
OS 24.4396768 42.73228436
OS 24.43080204 42.7310169
OS 24.41558998 42.73481928
OS 24.38263094 42.73608674
OS 24.3705888 42.74813142
OS 24.36932134 42.75700364
OS 24.36805388 42.78869522
OS 24.36678642 42.7924976
OS 24.36551896 42.79756744
OS 24.36678642 42.8140495
OS 24.36551896 42.82672664
OS 24.36678642 42.83559886
OS 24.36551896 42.85207838
OS 24.36678642 42.86348552
OS 24.36551896 42.86729044
OS 24.36678642 44.8803141
OS 24.36805388 44.88411394
OS 24.36995634 44.92531528
OS 24.3712238 44.93038512
OS 24.37565864 44.9411598
OS 24.3781961 44.95003202
OS 24.38199848 44.95636932
OS 24.38897078 44.95827178
OS 31.31665568 44.95700432
OE
OB 27.75076746 44.47149602 H
OS 27.74696508 44.47022856
OS 27.71273858 44.4689611
OS 27.70893366 44.4676911
OS 27.67977954 44.46642364
OS 27.67597716 44.46515618
OS 27.67090732 44.46388872
OS 27.65442526 44.4626238
OS 27.64935542 44.46135634
OS 27.62210122 44.45945388
OS 27.61766638 44.45882142
OS 27.61386146 44.46008888
OS 27.60879162 44.45882142
OS 27.57520012 44.45691896
OS 27.55745314 44.4556515
OS 27.54984584 44.45438404
OS 27.54350854 44.45311658
OS 27.53843616 44.45184912
OS 27.52132418 44.44994666
OS 27.51625434 44.4486792
OS 27.48900014 44.44550928
OS 27.47125062 44.44424182
OS 27.46491586 44.44297436
OS 27.45984348 44.4417069
OS 27.45287118 44.43980444
OS 27.44780134 44.43853698
OS 27.4211796 44.4347346
OS 27.40470262 44.43346714
OS 27.4008977 44.43219968
OS 27.38885556 44.43029722
OS 27.38378572 44.42902976
OS 27.3730085 44.42585984
OS 27.3596989 44.42395992
OS 27.34258692 44.42205746
OS 27.32103502 44.41952254
OS 27.31406272 44.41762008
OS 27.29948566 44.41191524
OS 27.29441582 44.41064778
OS 27.28110622 44.40747786
OS 27.27413392 44.40431048
OS 27.26779408 44.40177556
OS 27.25955432 44.39987564
OS 27.25321702 44.39860818
OS 27.23800496 44.39607326
OS 27.23293258 44.39480326
OS 27.22279544 44.39100088
OS 27.21455568 44.38783096
OS 27.20187854 44.3865635
OS 27.19300378 44.38529604
OS 27.18793394 44.38402858
OS 27.17969164 44.38085866
OS 27.17335434 44.37832374
OS 27.16511712 44.37515636
OS 27.16004474 44.37388636
OS 27.15053752 44.37198644
OS 27.14420022 44.36945152
OS 27.13722792 44.3662816
OS 27.13088808 44.36374668
OS 27.12581824 44.36247922
OS 27.1125061 44.3593093
OS 27.10617134 44.35677438
OS 27.0928592 44.35106954
OS 27.08778936 44.34980208
OS 27.07828214 44.34789962
OS 27.065605 44.34283232
OS 27.0586327 44.3396624
OS 27.04975794 44.33712748
OS 27.0389858 44.33522502
OS 27.02567366 44.32825272
OS 27.01680144 44.32445034
OS 26.99524954 44.31430812
OS 26.98637732 44.31304066
OS 26.97940502 44.3111382
OS 26.95341828 44.29909606
OS 26.94454352 44.29402622
OS 26.93059892 44.28768638
OS 26.91919432 44.28134908
OS 26.90524718 44.27501178
OS 26.88369782 44.26486956
OS 26.87165568 44.26296964
OS 26.86531838 44.26043218
OS 26.8545437 44.25472988
OS 26.84820386 44.25219242
OS 26.8063726 44.23064306
OS 26.79369546 44.22557068
OS 26.78672316 44.21986838
OS 26.78355324 44.216701
OS 26.78101832 44.21543354
OS 26.76580626 44.20529132
OS 26.76073642 44.20402386
OS 26.74869428 44.2021214
OS 26.74172198 44.19768402
OS 26.7379196 44.19388164
OS 26.72904484 44.1888118
OS 26.723975 44.18373942
OS 26.72144008 44.18247196
OS 26.7100304 44.17740212
OS 26.69862072 44.17106228
OS 26.68721358 44.16599244
OS 26.68087628 44.1621926
OS 26.6758039 44.15712022
OS 26.67326898 44.15585276
OS 26.67073406 44.15331784
OS 26.66819914 44.15205038
OS 26.66439676 44.148248
OS 26.6618593 44.14698054
OS 26.65932438 44.14444308
OS 26.65425454 44.14317562
OS 26.64284486 44.13683832
OS 26.63777502 44.13176594
OS 26.63523756 44.13049848
OS 26.63143518 44.1266961
OS 26.62890026 44.12542864
OS 26.62510042 44.12162626
OS 26.62256296 44.1203588
OS 26.61622566 44.11782134
OS 26.61115582 44.11655388
OS 26.60354852 44.10894912
OS 26.6010136 44.10768166
OS 26.58960392 44.09880944
OS 26.587069 44.09627452
OS 26.58072916 44.0937396
OS 26.57565932 44.0924696
OS 26.56868956 44.0867673
OS 26.56551964 44.08359738
OS 26.56298472 44.08232992
OS 26.5465052 44.06584786
OS 26.54397028 44.0645804
OS 26.54016536 44.06077802
OS 26.53382806 44.0582431
OS 26.5255883 44.05507318
OS 26.52241838 44.05190326
OS 26.51988346 44.0506358
OS 26.51481108 44.04556596
OS 26.51227616 44.0442985
OS 26.50847632 44.04049866
OS 26.5059414 44.03922866
OS 26.50213648 44.03542628
OS 26.48819188 44.03035644
OS 26.48058712 44.02274914
OS 26.4780522 44.02148168
OS 26.4710799 44.01577684
OS 26.46981244 44.01324192
OS 26.4641076 44.00753708
OS 26.46157014 44.00626962
OS 26.45840276 44.00183224
OS 26.45143046 43.99485994
OS 26.44889554 43.99359248
OS 26.4438257 43.98852264
OS 26.44129078 43.98725518
OS 26.43495094 43.98471772
OS 26.42671118 43.98155288
OS 26.41847142 43.97331312
OS 26.4159365 43.97204312
OS 26.41276658 43.9701432
OS 26.41149912 43.96760828
OS 26.37347024 43.92957686
OS 26.37220278 43.92704194
OS 26.3690354 43.92387202
OS 26.36649794 43.9226071
OS 26.35952564 43.91690226
OS 26.35635826 43.91373234
OS 26.34241366 43.9086625
OS 26.33734128 43.90359012
OS 26.33480636 43.90232266
OS 26.33227144 43.89978774
OS 26.32973652 43.89852028
OS 26.32530168 43.8940829
OS 26.32403422 43.89154798
OS 26.31959684 43.8871106
OS 26.31706192 43.88584314
OS 26.31262454 43.88140576
OS 26.31135708 43.87887084
OS 26.30818716 43.87570092
OS 26.30565224 43.87443346
OS 26.2999474 43.86872862
OS 26.29867994 43.8661937
OS 26.29551002 43.86302632
OS 26.2929751 43.86175886
OS 26.28853772 43.85732148
OS 26.28727026 43.85478656
OS 26.28410034 43.85161664
OS 26.28156542 43.85034918
OS 26.27586058 43.84464434
OS 26.27459312 43.84210942
OS 26.2714232 43.83894204
OS 26.26888828 43.83767204
OS 26.26445344 43.8332372
OS 26.26318598 43.83069974
OS 26.26001606 43.82753236
OS 26.25748114 43.8262649
OS 26.2517763 43.82056006
OS 26.25050884 43.81802514
OS 26.24733892 43.81485522
OS 26.244804 43.81358776
OS 26.23909916 43.80788292
OS 26.2378317 43.805348
OS 26.23529678 43.80281308
OS 26.23402932 43.80027816
OS 26.23022694 43.79647578
OS 26.22578956 43.7844311
OS 26.22261964 43.77999626
OS 26.2175498 43.77492388
OS 26.21628234 43.77238896
OS 26.21311242 43.76795158
OS 26.2105775 43.76668412
OS 26.20107028 43.7571769
OS 26.20043782 43.75527444
OS 26.1979029 43.75400698
OS 26.17571854 43.73182516
OS 26.17445108 43.72929024
OS 26.17191362 43.7229504
OS 26.17508354 43.71851556
OS 26.1839583 43.71724556
OS 26.19409798 43.71851556
OS 26.20107028 43.7242204
OS 26.20297274 43.72612032
OS 26.21184496 43.7311927
OS 26.21501488 43.73436008
OS 26.21628234 43.736895
OS 26.22198718 43.74259984
OS 26.2245221 43.7438673
OS 26.22769202 43.74703468
OS 26.22895948 43.7495696
OS 26.23466432 43.7565419
OS 26.2378317 43.75971182
OS 26.23973416 43.76668412
OS 26.24226908 43.77302396
OS 26.24924138 43.77999626
OS 26.25050884 43.78253118
OS 26.25621368 43.78950348
OS 26.2587486 43.79077094
OS 26.2657209 43.79774324
OS 26.26698836 43.80027816
OS 26.2714232 43.80344808
OS 26.2783955 43.81041784
OS 26.2790305 43.8123203
OS 26.28156542 43.81358776
OS 26.28980518 43.82182752
OS 26.29107264 43.82436244
OS 26.2929751 43.8262649
OS 26.29551002 43.82753236
OS 26.30121486 43.8332372
OS 26.30248232 43.83577212
OS 26.30438478 43.83767204
OS 26.3069197 43.83894204
OS 26.313892 43.84591434
OS 26.31515946 43.84844926
OS 26.31706192 43.85034918
OS 26.31959684 43.85161664
OS 26.32656914 43.85858894
OS 26.3272016 43.8604914
OS 26.32973652 43.86175886
OS 26.33924374 43.87126608
OS 26.3398762 43.873166
OS 26.34241366 43.87443346
OS 26.35065342 43.88267322
OS 26.35192088 43.88521068
OS 26.3538208 43.8871106
OS 26.35635826 43.88837806
OS 26.35889318 43.89091298
OS 26.3614281 43.89218298
OS 26.36649794 43.89725282
OS 26.37283778 43.89978774
OS 26.38107754 43.90295766
OS 26.38678238 43.9086625
OS 26.38931476 43.90992996
OS 26.39184968 43.91246488
OS 26.3943846 43.91373234
OS 26.39755452 43.91690226
OS 26.39882198 43.91943718
OS 26.40325936 43.92387202
OS 26.40579428 43.92513948
OS 26.41023166 43.92957686
OS 26.41149912 43.93211178
OS 26.4159365 43.93654916
OS 26.41847142 43.93781662
OS 26.42164134 43.94098654
OS 26.4229088 43.94352146
OS 26.42861364 43.9492263
OS 26.43114856 43.95049376
OS 26.43431848 43.95366368
OS 26.43558594 43.9561986
OS 26.44129078 43.96190344
OS 26.44319324 43.9625359
OS 26.4438257 43.96443836
OS 26.44572816 43.96507082
OS 26.44699562 43.96760828
OS 26.45396538 43.97458058
OS 26.4565003 43.97584804
OS 26.46157014 43.98091788
OS 26.4641076 43.98218534
OS 26.47678474 43.98725518
OS 26.48375704 43.99296002
OS 26.48692442 43.9961274
OS 26.48945934 43.99739486
OS 26.518616 44.02655406
OS 26.52115092 44.02782152
OS 26.52368584 44.03035644
OS 26.52622076 44.0316239
OS 26.5325606 44.03415882
OS 26.54143282 44.03922866
OS 26.54397028 44.04176612
OS 26.5465052 44.04303358
OS 26.55030758 44.04683342
OS 26.5528425 44.04810088
OS 26.55664488 44.05190326
OS 26.55918234 44.05317326
OS 26.56171726 44.05570818
OS 26.56805456 44.0582431
OS 26.5731244 44.05951056
OS 26.5800967 44.0652154
OS 26.58326662 44.06838532
OS 26.58580154 44.06965278
OS 26.58833646 44.0721877
OS 26.59087138 44.07345516
OS 26.59594122 44.078525
OS 26.59847868 44.079795
OS 26.61115582 44.08486484
OS 26.61369074 44.08739976
OS 26.61622566 44.08866722
OS 26.6212955 44.0937396
OS 26.62383042 44.09500706
OS 26.63080272 44.10197936
OS 26.63207018 44.10451174
OS 26.63523756 44.10768166
OS 26.63777502 44.10894912
OS 26.6415774 44.1127515
OS 26.64411232 44.11401896
OS 26.64664724 44.11655388
OS 26.65298708 44.1190888
OS 26.66122684 44.12225872
OS 26.6688316 44.1273311
OS 26.6758039 44.13049848
OS 26.68404366 44.1336684
OS 26.69164842 44.1400057
OS 26.69481834 44.14317562
OS 26.69735326 44.14444308
OS 26.70432556 44.15014792
OS 26.70622802 44.15205038
OS 26.71510024 44.15585276
OS 26.7315823 44.16472498
OS 26.74045452 44.16852736
OS 26.74679436 44.17106228
OS 26.75566404 44.17740212
OS 26.76200388 44.17993704
OS 26.76707372 44.1812045
OS 26.77594848 44.18627434
OS 26.78989308 44.19261418
OS 26.79623038 44.19641656
OS 26.80130276 44.20148894
OS 26.80383768 44.2027564
OS 26.8063726 44.20529132
OS 26.80890498 44.20655878
OS 26.81397736 44.21162862
OS 26.81651228 44.21289608
OS 26.82792196 44.21796846
OS 26.83679418 44.2230383
OS 26.85327624 44.23064306
OS 26.87228814 44.23951528
OS 26.87735798 44.24078528
OS 26.88686774 44.2426852
OS 26.89320504 44.24522012
OS 26.9014448 44.2496575
OS 26.91412194 44.25472988
OS 26.91665686 44.25599734
OS 26.92679908 44.26233464
OS 26.93313638 44.26486956
OS 26.99524954 44.29529368
OS 27.00158938 44.29909606
OS 27.00665922 44.30036352
OS 27.01553398 44.30163098
OS 27.02060382 44.30289844
OS 27.03708334 44.31050574
OS 27.0459581 44.31304066
OS 27.05926516 44.31621058
OS 27.0732123 44.32254788
OS 27.08398698 44.3257178
OS 27.0934942 44.32761772
OS 27.0998315 44.33015518
OS 27.1131411 44.33586002
OS 27.12328332 44.33839494
OS 27.13152308 44.34029486
OS 27.14546768 44.34663216
OS 27.15624236 44.34980208
OS 27.16955196 44.35296946
OS 27.17652426 44.35613938
OS 27.18539648 44.35994176
OS 27.1955387 44.36247922
OS 27.20377846 44.36437914
OS 27.2101183 44.36691406
OS 27.21835806 44.37008398
OS 27.22850028 44.3726189
OS 27.2430748 44.37452136
OS 27.26716162 44.37832374
OS 27.27730384 44.38212866
OS 27.28427614 44.38402858
OS 27.29441582 44.3865635
OS 27.31026034 44.38846596
OS 27.31533272 44.38973342
OS 27.32167002 44.39226834
OS 27.32990978 44.39543826
OS 27.340052 44.39797318
OS 27.35779644 44.4005081
OS 27.36286882 44.40177556
OS 27.37491096 44.4062104
OS 27.38124826 44.40747786
OS 27.39265794 44.40874786
OS 27.39899778 44.41001532
OS 27.40913746 44.41128278
OS 27.4218146 44.41255024
OS 27.43702666 44.41508516
OS 27.44336396 44.41635262
OS 27.45413864 44.41952254
OS 27.47885792 44.42142246
OS 27.49913982 44.42395992
OS 27.51688934 44.42522738
OS 27.53399878 44.4271273
OS 27.544141 44.42966476
OS 27.55681814 44.43093222
OS 27.57329766 44.43219968
OS 27.63668082 44.4347346
OS 27.70069644 44.4353696
OS 27.83443252 44.4347346
OS 27.8382349 44.43600206
OS 27.90795536 44.4347346
OS 27.95929638 44.43283214
OS 27.9821132 44.43156468
OS 27.99986272 44.43029722
OS 28.00620002 44.42902976
OS 28.0163397 44.42649484
OS 28.0505662 44.42269246
OS 28.0708481 44.420155
OS 28.0847927 44.41888754
OS 28.09049754 44.41698762
OS 28.09936976 44.41445016
OS 28.10951198 44.41191524
OS 28.12852642 44.41064778
OS 28.1323288 44.40938032
OS 28.1399361 44.40811286
OS 28.14373848 44.4068454
OS 28.15768308 44.40304556
OS 28.1665553 44.4005081
OS 28.18303736 44.39924064
OS 28.19190704 44.39797318
OS 28.20014934 44.39607326
OS 28.20521918 44.39480326
OS 28.2153614 44.39100088
OS 28.2223337 44.38910096
OS 28.22740354 44.38783096
OS 28.2432506 44.38593104
OS 28.25338774 44.38339612
OS 28.25972758 44.38085866
OS 28.27050226 44.37769128
OS 28.27557464 44.37642382
OS 28.29141916 44.37452136
OS 28.29902646 44.3732539
OS 28.30916614 44.37198644
OS 28.31423598 44.37071898
OS 28.3243782 44.36691406
OS 28.33261796 44.36374668
OS 28.3376878 44.36247922
OS 28.34719502 44.36057676
OS 28.35353486 44.35804184
OS 28.36684446 44.352337
OS 28.3719143 44.35106954
OS 28.38142152 44.34916708
OS 28.39156374 44.3453647
OS 28.40487334 44.3396624
OS 28.40994572 44.33839494
OS 28.41945294 44.33649248
OS 28.42579024 44.33395756
OS 28.44290222 44.32698526
OS 28.45177698 44.3257178
OS 28.46381912 44.32128042
OS 28.47713126 44.31557558
OS 28.4822011 44.31430812
OS 28.4955107 44.3111382
OS 28.52149744 44.29909606
OS 28.54051188 44.2902213
OS 28.55255402 44.28832138
OS 28.55889132 44.28578392
OS 28.56966854 44.28008162
OS 28.57854076 44.27627924
OS 28.60009266 44.26613702
OS 28.6051625 44.26486956
OS 28.61530218 44.2636021
OS 28.63685408 44.25345988
OS 28.65079868 44.24585512
OS 28.66474328 44.23951528
OS 28.6672782 44.23824782
OS 28.67424796 44.23254298
OS 28.67868534 44.2293756
OS 28.68565764 44.2236733
OS 28.68882502 44.22050338
OS 28.69136248 44.21923592
OS 28.7002347 44.21543354
OS 28.70847446 44.21226362
OS 28.71608176 44.20719124
OS 28.72305406 44.20529132
OS 28.7281239 44.20402386
OS 28.73699612 44.2027564
OS 28.75854802 44.19261418
OS 28.76742024 44.18754434
OS 28.77439254 44.1818395
OS 28.776295 44.17993704
OS 28.77882992 44.17866958
OS 28.78580222 44.17296474
OS 28.7889696 44.16979482
OS 28.8029142 44.16472498
OS 28.81051896 44.15965514
OS 28.81939372 44.15585276
OS 28.8308034 44.14951546
OS 28.83587324 44.14444308
OS 28.8384107 44.14317562
OS 28.845383 44.13747078
OS 28.84854784 44.1343034
OS 28.85488768 44.13176594
OS 28.86312744 44.12859856
OS 28.8650299 44.1266961
OS 28.88150942 44.1190888
OS 28.89038164 44.11401896
OS 28.8929191 44.11148404
OS 28.89545402 44.11021658
OS 28.911931 44.0937396
OS 28.91446592 44.0924696
OS 28.92207322 44.08486484
OS 28.93411536 44.08042746
OS 28.93855274 44.07725754
OS 28.94552504 44.0715527
OS 28.95313234 44.06648286
OS 28.95883464 44.06077802
OS 28.96517448 44.0582431
OS 28.97024178 44.05697564
OS 28.98165146 44.04810088
OS 28.98862376 44.04239858
OS 28.99052622 44.04049866
OS 28.99306114 44.03922866
OS 28.99686352 44.03542628
OS 29.00383582 44.03352636
OS 29.01397804 44.02718652
OS 29.01714796 44.0240166
OS 29.01968288 44.02274914
OS 29.04630208 43.9961274
OS 29.048837 43.99485994
OS 29.0564443 43.98725518
OS 29.06531652 43.98471772
OS 29.07165636 43.98091788
OS 29.07862866 43.97521304
OS 29.08306604 43.97204312
OS 29.08876834 43.96634082
OS 29.0900358 43.96380336
OS 29.09320572 43.96063598
OS 29.09574064 43.95936852
OS 29.09890802 43.9561986
OS 29.10017802 43.95366368
OS 29.10588286 43.94795884
OS 29.10841778 43.94669138
OS 29.11539008 43.94098654
OS 29.11855746 43.93781662
OS 29.12679976 43.93591416
OS 29.13377206 43.93147678
OS 29.13757444 43.9276744
OS 29.14010936 43.92640694
OS 29.14264428 43.92387202
OS 29.1451792 43.9226071
OS 29.14708166 43.92070464
OS 29.14834658 43.91816972
OS 29.17053094 43.89598536
OS 29.1724334 43.89535036
OS 29.17370086 43.89281544
OS 29.23011172 43.83640458
OS 29.23201164 43.83577212
OS 29.2332791 43.8332372
OS 29.27828028 43.78823602
OS 29.28018274 43.78760102
OS 29.2814502 43.7850661
OS 29.30109964 43.76541666
OS 29.30363456 43.7641492
OS 29.30680448 43.76097928
OS 29.30807194 43.75844436
OS 29.31377678 43.75273952
OS 29.3163117 43.75147206
OS 29.31948162 43.74830214
OS 29.32074908 43.74576722
OS 29.32645392 43.73879746
OS 29.32835384 43.736895
OS 29.33088876 43.7305577
OS 29.33405868 43.72231794
OS 29.33976098 43.7166131
OS 29.34103098 43.71407818
OS 29.3435659 43.71154326
OS 29.34483336 43.7090058
OS 29.34927074 43.70457096
OS 29.35180566 43.70330096
OS 29.35624304 43.69886612
OS 29.3575105 43.69632866
OS 29.36194788 43.69189382
OS 29.3644828 43.69062636
OS 29.36892018 43.68618898
OS 29.37018764 43.68365406
OS 29.37399002 43.67985168
OS 29.37525748 43.67731676
OS 29.3777924 43.67478184
OS 29.38222978 43.66273716
OS 29.3853997 43.65830232
OS 29.390467 43.65322994
OS 29.39173446 43.65069502
OS 29.4183562 43.62407328
OS 29.41962366 43.6215409
OS 29.42469604 43.61646852
OS 29.4259635 43.6139336
OS 29.42849842 43.6075963
OS 29.43356826 43.59872154
OS 29.4392731 43.59174924
OS 29.44117556 43.58984932
OS 29.44244302 43.58731186
OS 29.4462454 43.58350948
OS 29.44751286 43.58097456
OS 29.45131524 43.57717218
OS 29.45321516 43.57019988
OS 29.45575262 43.56386258
OS 29.46272492 43.55689028
OS 29.46399238 43.55435536
OS 29.4728646 43.54294568
OS 29.47540206 43.54041076
OS 29.47666952 43.53533838
OS 29.48300682 43.52393124
OS 29.48807666 43.51885886
OS 29.48934666 43.51632394
OS 29.49885388 43.50681672
OS 29.5007538 43.50618172
OS 29.50202126 43.50364934
OS 29.50582618 43.49984696
OS 29.50709364 43.49731204
OS 29.51089348 43.49350712
OS 29.5134284 43.48716982
OS 29.51659832 43.47893006
OS 29.52166816 43.47132276
OS 29.52610554 43.46054808
OS 29.53117792 43.45167332
OS 29.53624776 43.44660348
OS 29.53751522 43.44406856
OS 29.54005014 43.44153364
OS 29.5413176 43.43899872
OS 29.54638998 43.43392888
OS 29.54765744 43.43139396
OS 29.55145982 43.4225192
OS 29.55906712 43.4085746
OS 29.5628695 43.39969984
OS 29.56793934 43.39082762
OS 29.57300918 43.38575524
OS 29.57427664 43.38322286
OS 29.57998148 43.37625056
OS 29.5831514 43.37181318
OS 29.58568632 43.36927826
OS 29.5888537 43.3610385
OS 29.59139116 43.35469866
OS 29.597096 43.34519144
OS 29.60026338 43.33695168
OS 29.60216584 43.3325143
OS 29.60723568 43.32490954
OS 29.6110406 43.31603732
OS 29.61357552 43.30970002
OS 29.61991282 43.2995578
OS 29.62371774 43.29068304
OS 29.64526456 43.24885178
OS 29.64906694 43.23997702
OS 29.65223686 43.23173726
OS 29.65413932 43.22983734
OS 29.6579417 43.22096258
OS 29.65920916 43.21208782
OS 29.66047662 43.20701798
OS 29.66364654 43.19878076
OS 29.66935138 43.18927354
OS 29.67061884 43.18420116
OS 29.69470312 43.13476514
OS 29.69597058 43.12969276
OS 29.69723804 43.11955054
OS 29.7061128 43.1005361
OS 29.70864772 43.09039388
OS 29.70991518 43.08279166
OS 29.71498502 43.07138198
OS 29.71878994 43.06250722
OS 29.72132486 43.052365
OS 29.72259232 43.04476024
OS 29.72892962 43.03081564
OS 29.73146708 43.0244758
OS 29.73273454 43.0194085
OS 29.73463446 43.00863382
OS 29.7409743 42.99468922
OS 29.74414422 42.98644946
OS 29.74541168 42.98137708
OS 29.74667914 42.97250486
OS 29.7530139 42.95856026
OS 29.75554882 42.95222296
OS 29.75871874 42.93764336
OS 29.76252112 42.92750368
OS 29.76569104 42.91926392
OS 29.7669585 42.91419154
OS 29.76886096 42.89961702
OS 29.77139588 42.87933258
OS 29.7739308 42.86919036
OS 29.77710072 42.8609506
OS 29.7809031 42.84827346
OS 29.78280556 42.83243148
OS 29.78407302 42.82609164
OS 29.7878754 42.81594942
OS 29.79168032 42.80200482
OS 29.79294778 42.79440006
OS 29.7954827 42.77158324
OS 29.79801762 42.76144102
OS 29.80118754 42.75066634
OS 29.80372246 42.74052412
OS 29.80498992 42.7316519
OS 29.80625738 42.72657952
OS 29.80752484 42.70883508
OS 29.80878976 42.7050327
OS 29.81386214 42.68728318
OS 29.81703206 42.6562266
OS 29.81829952 42.64608692
OS 29.81956698 42.62580248
OS 29.8214669 42.60868796
OS 29.82463682 42.59411344
OS 29.82653928 42.57699892
OS 29.8284392 42.54467234
OS 29.82970666 42.49650378
OS 29.83097666 42.42298094
OS 29.83414404 42.41854356
OS 29.8360465 42.41664364
OS 29.84111634 42.41537364
OS 29.86013332 42.41664364
OS 29.86456816 42.42107848
OS 29.86583816 42.42614832
OS 29.86456816 42.44262784
OS 29.85949832 42.45403752
OS 29.85823086 42.46291228
OS 29.8563284 42.48762902
OS 29.85506094 42.50157362
OS 29.85252602 42.55481456
OS 29.85125856 42.57636392
OS 29.8499911 42.59411344
OS 29.84872364 42.60425312
OS 29.84745618 42.61059042
OS 29.84618872 42.61566026
OS 29.84492126 42.6220001
OS 29.8423838 42.63721216
OS 29.83984888 42.66256644
OS 29.83731396 42.67777596
OS 29.8360465 42.6828458
OS 29.83414404 42.68855064
OS 29.83287658 42.69362302
OS 29.83160912 42.70630016
OS 29.83034166 42.71137
OS 29.82780674 42.73672174
OS 29.82653928 42.74179158
OS 29.82527182 42.7519338
OS 29.82273436 42.75827364
OS 29.81893198 42.7734857
OS 29.81766452 42.7861603
OS 29.81639706 42.79123014
OS 29.8151296 42.80390728
OS 29.81386214 42.80770966
OS 29.81259468 42.81278204
OS 29.80878976 42.82545918
OS 29.80752484 42.83052902
OS 29.80498992 42.84827346
OS 29.80308746 42.86412052
OS 29.80182 42.86919036
OS 29.79801762 42.87933258
OS 29.7948477 42.88757234
OS 29.79231278 42.89771456
OS 29.79104532 42.90531932
OS 29.78470802 42.91926392
OS 29.78217056 42.92813614
OS 29.78027064 42.9439832
OS 29.77900318 42.9503205
OS 29.7739308 42.96426256
OS 29.77076342 42.97250486
OS 29.76822596 42.98264454
OS 29.76632604 42.98961684
OS 29.76315612 42.9978566
OS 29.75935374 43.00673136
OS 29.75681882 43.01560612
OS 29.7536489 43.02891318
OS 29.74667914 43.04476024
OS 29.74414422 43.05490246
OS 29.74224176 43.06187476
OS 29.73843938 43.07201444
OS 29.734002 43.08279166
OS 29.73146708 43.09293134
OS 29.73019708 43.1005361
OS 29.72385978 43.11067832
OS 29.72259232 43.11574816
OS 29.70864772 43.14490228
OS 29.70738026 43.15757942
OS 29.69470312 43.18420116
OS 29.68836328 43.19561084
OS 29.68202852 43.2095529
OS 29.67568868 43.22096258
OS 29.66935138 43.23490718
OS 29.66047662 43.25392162
OS 29.6585767 43.26596376
OS 29.65603924 43.27230106
OS 29.63955972 43.30526264
OS 29.62752012 43.32997938
OS 29.61611044 43.35153128
OS 29.6110406 43.35660112
OS 29.60977314 43.35913604
OS 29.6040683 43.36610834
OS 29.59963092 43.3743481
OS 29.59836346 43.38322286
OS 29.597096 43.39082762
OS 29.59329108 43.39716492
OS 29.5894887 43.4009673
OS 29.58822124 43.40350476
OS 29.57934648 43.4149119
OS 29.57427664 43.4225192
OS 29.57237418 43.4294915
OS 29.56603942 43.43963372
OS 29.5628695 43.44660348
OS 29.55969958 43.45484324
OS 29.55336228 43.46245054
OS 29.55145982 43.46435046
OS 29.55019236 43.46688538
OS 29.54448752 43.47385768
OS 29.5413176 43.4770276
OS 29.54005014 43.47956252
OS 29.53751522 43.48590236
OS 29.53117792 43.49731204
OS 29.52483808 43.50364934
OS 29.52357062 43.50618172
OS 29.51976824 43.50998664
OS 29.51850078 43.51252156
OS 29.51596586 43.51505648
OS 29.5134284 43.52139378
OS 29.51026102 43.52963608
OS 29.50329126 43.53660838
OS 29.50202126 43.5391433
OS 29.49631896 43.5461156
OS 29.49314904 43.54928298
OS 29.48934666 43.55689028
OS 29.48934666 43.55815774
OS 29.48300682 43.56956488
OS 29.47793698 43.57463472
OS 29.47666952 43.57717218
OS 29.46018746 43.5936517
OS 29.45892 43.59618662
OS 29.45511762 43.599989
OS 29.4525827 43.60632884
OS 29.44941278 43.6145686
OS 29.44371048 43.62027344
OS 29.44244302 43.62280836
OS 29.43864064 43.6266082
OS 29.43737318 43.62914312
OS 29.4329358 43.63231304
OS 29.42723096 43.63801788
OS 29.4259635 43.6405528
OS 29.42216112 43.64435772
OS 29.42089112 43.64689264
OS 29.4183562 43.64942756
OS 29.41582128 43.65576486
OS 29.41265136 43.66400716
OS 29.40567906 43.67097946
OS 29.4044116 43.67351438
OS 29.38919954 43.6887239
OS 29.38793462 43.69125882
OS 29.38286478 43.69632866
OS 29.38159478 43.69886612
OS 29.37905986 43.70520342
OS 29.3777924 43.71027326
OS 29.37208756 43.71724556
OS 29.36892018 43.72041548
OS 29.36765018 43.7229504
OS 29.35941042 43.7311927
OS 29.3568755 43.73246016
OS 29.35370558 43.736895
OS 29.33786106 43.75273952
OS 29.33532614 43.75400698
OS 29.33215622 43.7571769
OS 29.33088876 43.75971182
OS 29.32518646 43.76541666
OS 29.32265154 43.76668412
OS 29.31948162 43.76985404
OS 29.31821416 43.77238896
OS 29.31441178 43.77619134
OS 29.31314178 43.7787288
OS 29.30807194 43.78379864
OS 29.30553702 43.7926734
OS 29.30173464 43.7990107
OS 29.29666226 43.80408054
OS 29.2953948 43.80661546
OS 29.28968996 43.81358776
OS 29.28271766 43.8192926
OS 29.2814502 43.82182752
OS 29.27701282 43.8262649
OS 29.2744779 43.82753236
OS 29.27004052 43.83196974
OS 29.26877306 43.83450466
OS 29.26433822 43.83894204
OS 29.2618033 43.8402095
OS 29.25863338 43.84337688
OS 29.25736592 43.84591434
OS 29.25292854 43.85034918
OS 29.25039362 43.85161664
OS 29.24595624 43.85605402
OS 29.24468878 43.85858894
OS 29.2402514 43.86302632
OS 29.23771648 43.86429124
OS 29.2332791 43.86872862
OS 29.23201164 43.87126608
OS 29.2275768 43.87570092
OS 29.22503934 43.87696838
OS 29.22187196 43.8801383
OS 29.2206045 43.88267322
OS 29.21616712 43.8871106
OS 29.2136322 43.88837806
OS 29.2066599 43.8940829
OS 29.20349252 43.89725282
OS 29.18954792 43.90232266
OS 29.18447554 43.90739504
OS 29.18194062 43.9086625
OS 29.1794057 43.91119742
OS 29.17687078 43.91246488
OS 29.1724334 43.91690226
OS 29.17116594 43.91943718
OS 29.16799602 43.9226071
OS 29.1654611 43.92387202
OS 29.16102372 43.9283094
OS 29.15975626 43.93084432
OS 29.15531888 43.9352817
OS 29.15278396 43.93654916
OS 29.14708166 43.942254
OS 29.1458142 43.94478892
OS 29.12996714 43.96063598
OS 29.12743222 43.96190344
OS 29.12552976 43.96380336
OS 29.1242623 43.96634082
OS 29.11729 43.97331312
OS 29.11475508 43.97458058
OS 29.10841778 43.98091788
OS 29.10588286 43.98218534
OS 29.09954302 43.98471772
OS 29.09447318 43.98598772
OS 29.08750342 43.99169002
OS 29.0843335 43.99485994
OS 29.08179858 43.9961274
OS 29.06658652 44.01133946
OS 29.06404906 44.01260946
OS 29.05771176 44.01894676
OS 29.05264192 44.02021422
OS 29.04439962 44.02338414
OS 29.03869732 44.02908898
OS 29.03615986 44.03035644
OS 29.03362494 44.03289136
OS 29.03109002 44.03415882
OS 29.02412026 44.04113112
OS 29.0228528 44.04366604
OS 29.01841542 44.04683342
OS 29.01461304 44.0506358
OS 29.01207558 44.05190326
OS 29.00954066 44.05444072
OS 29.00700574 44.05570818
OS 29.00066844 44.0582431
OS 28.99179368 44.06331294
OS 28.98925876 44.06584786
OS 28.98672384 44.06711786
OS 28.97151178 44.08232992
OS 28.96897432 44.08359738
OS 28.9613721 44.09120214
OS 28.95503226 44.0937396
OS 28.94996242 44.09500706
OS 28.92714306 44.1127515
OS 28.92334068 44.11655388
OS 28.91827084 44.11782134
OS 28.91002854 44.12099126
OS 28.9068637 44.12416118
OS 28.90432624 44.12542864
OS 28.8992564 44.13049848
OS 28.89672148 44.13176594
OS 28.89038164 44.13810578
OS 28.88784672 44.13937324
OS 28.8789745 44.14317562
OS 28.87009974 44.148248
OS 28.8650299 44.15331784
OS 28.86249244 44.1545853
OS 28.85995752 44.15712022
OS 28.8574226 44.15838768
OS 28.8510853 44.16472498
OS 28.844748 44.1672599
OS 28.83650824 44.17042982
OS 28.82700102 44.17613466
OS 28.82066118 44.17866958
OS 28.8092515 44.18500688
OS 28.80544912 44.1888118
OS 28.8029142 44.19007926
OS 28.7959419 44.1957841
OS 28.79150452 44.20021894
OS 28.78516976 44.2027564
OS 28.77692746 44.20592378
OS 28.7693227 44.21099616
OS 28.7623504 44.21416354
OS 28.75347564 44.21796846
OS 28.75094072 44.21923592
OS 28.74333342 44.22430322
OS 28.7344612 44.22810814
OS 28.72622398 44.23127552
OS 28.72432152 44.23317798
OS 28.7217866 44.23444544
OS 28.707842 44.24078528
OS 28.69643232 44.24712258
OS 28.68248772 44.25345988
OS 28.66093836 44.2636021
OS 28.65586852 44.26486956
OS 28.6457263 44.26613702
OS 28.63685408 44.2712094
OS 28.62797932 44.27501178
OS 28.61973956 44.2781817
OS 28.61213226 44.28325154
OS 28.58995044 44.29402622
OS 28.55572394 44.31050574
OS 28.54685172 44.31304066
OS 28.53797696 44.31430812
OS 28.51135522 44.32698526
OS 28.49234078 44.33586002
OS 28.48346856 44.33712748
OS 28.47142642 44.34156232
OS 28.46508658 44.34409724
OS 28.45811428 44.34726462
OS 28.45304444 44.34853462
OS 28.4397323 44.351702
OS 28.433395 44.35423692
OS 28.42642524 44.35740684
OS 28.4200854 44.35994176
OS 28.41501556 44.36121176
OS 28.40550834 44.36311168
OS 28.39536612 44.36691406
OS 28.38839382 44.37008398
OS 28.38205652 44.3726189
OS 28.37318176 44.37388636
OS 28.36113962 44.37832374
OS 28.35289986 44.38149366
OS 28.34656256 44.38402858
OS 28.3376878 44.38529604
OS 28.33261796 44.3865635
OS 28.31867336 44.38783096
OS 28.30726622 44.39290334
OS 28.30092638 44.39543826
OS 28.2907867 44.39797318
OS 28.2831794 44.39924064
OS 28.27176972 44.40431048
OS 28.26543242 44.4068454
OS 28.25655766 44.40938032
OS 28.24071314 44.41128278
OS 28.23437584 44.41255024
OS 28.22423362 44.41635262
OS 28.21726132 44.41825508
OS 28.21219148 44.41952254
OS 28.19634442 44.42142246
OS 28.18240236 44.42269246
OS 28.159583 44.42649484
OS 28.15451316 44.4277623
OS 28.14754086 44.42966476
OS 28.14247102 44.43093222
OS 28.12472404 44.43346714
OS 28.10761206 44.4353696
OS 28.10000476 44.43663706
OS 28.08986254 44.43790452
OS 28.08352524 44.43917198
OS 28.07845286 44.44043944
OS 28.07148056 44.4423419
OS 28.05627104 44.44487682
OS 28.02394446 44.4480442
OS 28.00683502 44.44994666
OS 27.99796026 44.45121412
OS 27.99098796 44.45311658
OS 27.98464812 44.45438404
OS 27.96753614 44.4562865
OS 27.94345186 44.45755396
OS 27.92697234 44.45882142
OS 27.91746258 44.45945388
OS 27.91176028 44.45882142
OS 27.90795536 44.46008888
OS 27.88197116 44.4619888
OS 27.86929402 44.4632588
OS 27.85534942 44.46579118
OS 27.8452072 44.46705864
OS 27.82239038 44.4683261
OS 27.80844578 44.46959356
OS 27.7843615 44.47086102
OS 27.75076746 44.47149602
OE
OB 27.45921102 43.58287448 H
OS 26.72841238 43.58224202
OS 26.71383278 43.58287448
OS 26.7100304 43.58160702
OS 26.69735326 43.58033956
OS 26.66122684 43.57843964
OS 26.65678946 43.57653718
OS 26.64728224 43.56702996
OS 26.64601478 43.56196012
OS 26.64411232 43.52329624
OS 26.64220986 43.50618172
OS 26.6415774 42.46227728
OS 26.64284486 42.44706522
OS 26.64601478 42.44262784
OS 26.6479147 42.44072538
OS 26.65298708 42.43945792
OS 26.90271226 42.44072538
OS 26.90714964 42.44516276
OS 26.9084171 42.45023514
OS 26.9090521 42.52566044
OS 26.9084171 42.53009782
OS 26.90968456 42.5339002
OS 26.9084171 42.5465748
OS 26.90968456 42.58587368
OS 26.9090521 43.31033248
OS 26.91031956 43.32174216
OS 26.91285448 43.325542
OS 26.91919432 43.32807946
OS 27.12201586 43.32680946
OS 27.1264507 43.32364462
OS 27.1277207 43.31857224
OS 27.12835316 43.31159994
OS 27.1277207 43.30462764
OS 27.12898816 43.30082526
OS 27.12835316 43.23934456
OS 27.12898816 43.23237226
OS 27.1277207 43.22856988
OS 27.12835316 43.20638298
OS 27.1277207 43.19307592
OS 27.12898816 43.18927354
OS 27.12835316 43.17089156
OS 27.12898816 42.5529121
OS 27.12898816 42.55164464
OS 27.13025562 42.49967116
OS 27.13152308 42.49586878
OS 27.13279054 42.45910736
OS 27.13912784 42.45023514
OS 27.14229776 42.44706522
OS 27.14483268 42.44579776
OS 27.15117252 42.44326284
OS 27.19427124 42.44199284
OS 27.19807362 42.44072538
OS 27.20694838 42.43945792
OS 27.22596282 42.44072538
OS 27.2297652 42.43945792
OS 27.36413628 42.44072538
OS 27.36984112 42.44516276
OS 27.37110858 42.45023514
OS 27.37237604 43.32110716
OS 27.37681342 43.32680946
OS 27.38568564 43.32807946
OS 27.43639166 43.32934692
OS 27.44019404 43.33061438
OS 27.45033626 43.33188184
OS 27.45287118 43.33441676
OS 27.4554061 43.33568422
OS 27.46111094 43.34138906
OS 27.4623784 43.34392398
OS 27.46491586 43.35026382
OS 27.46681578 43.39272754
OS 27.46808324 43.39906738
OS 27.4687157 43.4149119
OS 27.46745078 43.41871682
OS 27.4687157 43.43139396
OS 27.46745078 43.57717218
OS 27.46554832 43.58033956
OS 27.45921102 43.58287448
OE
OB 28.81812626 43.58287448 H
OS 28.81432388 43.58160702
OS 28.80164674 43.58287448
OS 28.26163004 43.58160702
OS 28.25782512 43.58033956
OS 28.21916378 43.57843964
OS 28.20902156 43.57463472
OS 28.19507696 43.56956488
OS 28.19063958 43.56639496
OS 28.1881072 43.56386258
OS 28.18557228 43.56259512
OS 28.18303736 43.5600602
OS 28.1804999 43.55879274
OS 28.1747976 43.5530879
OS 28.1735276 43.55055298
OS 28.17036022 43.54738306
OS 28.1678253 43.5461156
OS 28.160853 43.5391433
OS 28.159583 43.53660838
OS 28.15768308 43.53470592
OS 28.15514816 43.53343846
OS 28.14944332 43.52773362
OS 28.14817586 43.5251987
OS 28.1462734 43.52329624
OS 28.14373848 43.52202878
OS 28.13676618 43.51505648
OS 28.13549872 43.51252156
OS 28.13106134 43.50935164
OS 28.12535904 43.50364934
OS 28.12409158 43.50111442
OS 28.12218912 43.49921196
OS 28.1196542 43.4979445
OS 28.11394936 43.49223966
OS 28.1126819 43.48970474
OS 28.10951198 43.48653482
OS 28.10697706 43.48526736
OS 28.10000476 43.47829506
OS 28.0987373 43.47576014
OS 28.09683484 43.47385768
OS 28.09429992 43.47259022
OS 28.08859508 43.46688538
OS 28.08732762 43.46435046
OS 28.08542516 43.46245054
OS 28.08289024 43.46118054
OS 28.0771854 43.45547824
OS 28.07591794 43.45294078
OS 28.07275056 43.4497734
OS 28.0702131 43.44850594
OS 28.0645108 43.44280364
OS 28.06324334 43.44026618
OS 28.06134342 43.43836626
OS 28.05880596 43.4370988
OS 28.05310366 43.43139396
OS 28.05183366 43.4288565
OS 28.0442289 43.41744936
OS 28.04169398 43.40730714
OS 28.04042652 43.39082762
OS 28.03915652 43.3870227
OS 28.03788906 43.3819554
OS 28.03535414 43.3756181
OS 28.03408668 43.37054572
OS 28.03281922 43.35786858
OS 28.03091676 43.325542
OS 28.0296493 43.28751312
OS 28.02901684 42.72277968
OS 28.0302843 42.7189773
OS 28.03155176 42.66700128
OS 28.03281922 42.6631989
OS 28.03408668 42.63784716
OS 28.03915652 42.62643748
OS 28.04105898 42.61819772
OS 28.04296144 42.60615304
OS 28.04929874 42.59601336
OS 28.05183366 42.58967606
OS 28.05563858 42.57953384
OS 28.06134342 42.57256154
OS 28.0645108 42.56939162
OS 28.06577826 42.5668567
OS 28.07275056 42.5598844
OS 28.07528548 42.55861694
OS 28.08162278 42.55227964
OS 28.08796262 42.54974472
OS 28.09620238 42.5465748
OS 28.10063976 42.54340742
OS 28.10380714 42.53897004
OS 28.10697706 42.53580012
OS 28.10951198 42.53453266
OS 28.11141444 42.53263274
OS 28.11394936 42.5262929
OS 28.11585182 42.5193206
OS 28.11775174 42.51742068
OS 28.1190192 42.51488322
OS 28.12218912 42.51171584
OS 28.12472404 42.51044838
OS 28.12789396 42.506011
OS 28.13106134 42.50284108
OS 28.1469084 42.49713624
OS 28.14944332 42.49460132
OS 28.15071078 42.4920664
OS 28.15514816 42.48762902
OS 28.15768308 42.48636156
OS 28.159583 42.4844591
OS 28.16212046 42.47812434
OS 28.16528784 42.46988458
OS 28.16845776 42.4654472
OS 28.17289514 42.46227728
OS 28.1747976 42.46037482
OS 28.17606506 42.4578399
OS 28.17923244 42.45466998
OS 28.18557228 42.45213506
OS 28.19761188 42.44769768
OS 28.20585164 42.4445303
OS 28.2223337 42.44326284
OS 28.25465774 42.44136038
OS 28.30789868 42.44009292
OS 28.66474328 42.43945792
OS 28.66601074 42.43945792
OS 28.8992564 42.44072538
OS 28.90242632 42.4438953
OS 28.90496124 42.45403752
OS 28.90369378 42.66446636
OS 28.8992564 42.6689012
OS 28.89418656 42.6701712
OS 28.44860706 42.67080366
OS 28.43276 42.6701712
OS 28.42895762 42.67143866
OS 28.40804326 42.67080366
OS 28.39346366 42.67143866
OS 28.38966128 42.6701712
OS 28.37761914 42.67207112
OS 28.37444922 42.67270612
OS 28.37064684 42.67143866
OS 28.36050716 42.6701712
OS 28.35670478 42.67143866
OS 28.34656256 42.67397358
OS 28.31360098 42.67524104
OS 28.30156138 42.68728318
OS 28.30029392 42.69235556
OS 28.29902646 42.70122778
OS 28.297759 42.7303819
OS 28.29649154 42.73418682
OS 28.297759 42.75573618
OS 28.29649154 42.7595411
OS 28.297124 42.84003624
OS 28.29649154 42.85334584
OS 28.297759 42.85714822
OS 28.29902646 42.86602298
OS 28.30029392 42.89391218
OS 28.30663122 42.9027844
OS 28.31233352 42.9084867
OS 28.32247574 42.91102162
OS 28.35416732 42.91229162
OS 28.35797224 42.91355908
OS 28.3788866 42.91292408
OS 28.80608412 42.91419154
OS 28.81368888 42.915459
OS 28.81749126 42.91926392
OS 28.82002872 42.92813614
OS 28.81939372 43.02131096
OS 28.82002872 43.03335056
OS 28.81876126 43.03715294
OS 28.81749126 43.053635
OS 28.8162238 43.0663096
OS 28.81559134 43.0808892
OS 28.8162238 43.08532404
OS 28.81495634 43.08912642
OS 28.81115396 43.09546626
OS 28.80418166 43.10243856
OS 28.7953069 43.10497348
OS 28.75347564 43.10624094
OS 28.74967326 43.1075084
OS 28.7407985 43.10877586
OS 28.72432152 43.1075084
OS 28.71544676 43.10877586
OS 28.69960224 43.1081434
OS 28.3040963 43.10941086
OS 28.29965892 43.11131078
OS 28.29649154 43.11828308
OS 28.297124 43.25075424
OS 28.29649154 43.26532876
OS 28.297759 43.26913368
OS 28.297124 43.29005058
OS 28.29839146 43.29638788
OS 28.29965892 43.31793978
OS 28.30092638 43.33441676
OS 28.30282884 43.33631922
OS 28.3040963 43.33885414
OS 28.31106606 43.34582644
OS 28.31360098 43.3470939
OS 28.3174059 43.34836136
OS 28.3522674 43.35026382
OS 28.35733724 43.35153128
OS 28.36937938 43.35216374
OS 28.37318176 43.35089628
OS 28.39600112 43.35216374
OS 28.3998035 43.35089628
OS 28.41248064 43.35216374
OS 28.89798894 43.3534312
OS 28.90242632 43.35660112
OS 28.90496124 43.36547588
OS 28.90432624 43.4700553
OS 28.90496124 43.4846349
OS 28.90369378 43.48843728
OS 28.90496124 43.50998664
OS 28.90369378 43.51378902
OS 28.90242632 43.51885886
OS 28.90052386 43.56259512
OS 28.89862394 43.56702996
OS 28.89608648 43.56956488
OS 28.89481902 43.5720998
OS 28.8929191 43.57400226
OS 28.89038164 43.57526972
OS 28.88784672 43.57780464
OS 28.88277688 43.5790721
OS 28.84031062 43.58097456
OS 28.83397332 43.58224202
OS 28.81812626 43.58287448
OE
OB 26.0191631 43.58287448 H
OS 26.01536072 43.58160702
OS 26.00268358 43.58287448
OS 25.23575852 43.58160702
OS 25.23132114 43.57717218
OS 25.23005368 43.56829742
OS 25.23068868 43.41427944
OS 25.23005368 43.4009673
OS 25.23132114 43.39716492
OS 25.2325886 43.3882927
OS 25.23449106 43.34836136
OS 25.23639352 43.34392398
OS 25.24146336 43.33885414
OS 25.24209836 43.33695168
OS 25.24463328 43.33568422
OS 25.2471682 43.3331493
OS 25.25604042 43.33188184
OS 25.2947043 43.32997938
OS 25.3010416 43.32871192
OS 25.31688612 43.32807946
OS 25.3206885 43.32934692
OS 25.33336564 43.32807946
OS 25.4113284 43.32744446
OS 25.42210308 43.32807946
OS 25.42590546 43.32680946
OS 25.44681982 43.32744446
OS 25.46266688 43.32680946
OS 25.46646926 43.32807946
OS 25.47724648 43.326177
OS 25.51717528 43.32300962
OS 25.52921742 43.31096748
OS 25.53048742 43.3058951
OS 25.53048742 43.29448542
OS 25.53048742 43.29321796
OS 25.53175488 43.28434574
OS 25.53302234 43.26532876
OS 25.5342898 43.26152892
OS 25.53302234 43.24885178
OS 25.5342898 43.22983734
OS 25.53302234 43.22603242
OS 25.5342898 43.20448306
OS 25.53302234 43.20068068
OS 25.5342898 43.18800608
OS 25.53555726 42.44516276
OS 25.53872718 42.44199284
OS 25.54379702 42.44072538
OS 25.55266924 42.43945792
OS 25.68894024 42.44009292
OS 25.70351984 42.43945792
OS 25.70732222 42.44072538
OS 25.72760666 42.43945792
OS 25.7314065 42.44072538
OS 25.74028126 42.44199284
OS 25.7802126 42.4438953
OS 25.78655244 42.44643022
OS 25.79542212 42.45530498
OS 25.79795958 42.46417974
OS 25.79922704 42.50474354
OS 25.8004945 42.50854592
OS 25.80176196 42.52122306
OS 25.8004945 42.5339002
OS 25.80176196 42.54277242
OS 25.80112696 42.55861694
OS 25.80239442 43.22032758
OS 25.80302942 43.22729988
OS 25.80176196 43.2311048
OS 25.80302942 43.25392162
OS 25.80176196 43.25772654
OS 25.80302942 43.2716686
OS 25.80429688 43.27547098
OS 25.80493188 43.30019026
OS 25.80429688 43.30082526
OS 25.80556434 43.30462764
OS 25.8068318 43.31096748
OS 25.81887648 43.32300962
OS 25.8277487 43.32427454
OS 25.84739814 43.32490954
OS 25.85056552 43.32427454
OS 25.8543679 43.325542
OS 25.86514512 43.32744446
OS 25.87211742 43.32807946
OS 25.8759198 43.32680946
OS 25.89937162 43.32744446
OS 25.91141122 43.32680946
OS 25.91521614 43.32807946
OS 25.93232812 43.32744446
OS 25.9982462 43.32871192
OS 26.0052185 43.32934692
OS 26.00902342 43.32807946
OS 26.02803786 43.32934692
OS 26.0318377 43.33061438
OS 26.0743065 43.3325143
OS 26.09015102 43.34202406
OS 26.09332094 43.34519144
OS 26.09839078 43.3540662
OS 26.10219316 43.36294096
OS 26.10409562 43.40667214
OS 26.10536308 43.41301198
OS 26.10599554 43.42505412
OS 26.10472808 43.4288565
OS 26.10599554 43.45420824
OS 26.10472808 43.45801316
OS 26.10599554 43.47449268
OS 26.10472808 43.49731204
OS 26.10599554 43.50111442
OS 26.10472808 43.51505648
OS 26.10346062 43.51885886
OS 26.1015607 43.56259512
OS 26.09965824 43.56702996
OS 26.0939534 43.57400226
OS 26.08634864 43.5790721
OS 26.04134746 43.58097456
OS 26.03500762 43.58224202
OS 26.0191631 43.58287448
OE
OB 26.4565003 43.58287448 H
OS 26.24987638 43.58287448
OS 26.22198718 43.58160702
OS 26.2175498 43.57843964
OS 26.21628234 43.57336726
OS 26.21564734 43.56892988
OS 26.21628234 43.56069266
OS 26.21501488 43.55689028
OS 26.21628234 43.54801552
OS 26.2175498 42.44516276
OS 26.22198718 42.44072538
OS 26.23466432 42.43945792
OS 26.4641076 42.44072538
OS 26.46854244 42.4438953
OS 26.4710799 42.45277006
OS 26.46981244 43.57717218
OS 26.46537506 43.58160702
OS 26.4565003 43.58287448
OE
OB 29.68519844 42.2936797 H
OS 29.68139352 42.29241224
OS 29.66237908 42.2936797
OS 29.6585767 42.29241224
OS 29.6376598 42.29304724
OS 29.6300525 42.29177978
OS 29.61230806 42.29051232
OS 29.60787068 42.28987732
OS 29.60660322 42.28987732
OS 29.59202362 42.28924486
OS 29.58505132 42.28987732
OS 29.58124894 42.28860986
OS 29.57871402 42.2873424
OS 29.5749091 42.28354002
OS 29.57237418 42.28227256
OS 29.57047426 42.2803701
OS 29.5692068 42.27783518
OS 29.56667188 42.27149534
OS 29.56477196 42.23410146
OS 29.5635045 42.22395924
OS 29.5622345 41.1781498
OS 29.56160204 41.16991004
OS 29.5628695 41.16610766
OS 29.56413696 41.15470052
OS 29.56730688 41.1515306
OS 29.5761791 41.15026314
OS 30.28922822 41.15089814
OS 30.30634274 41.15026314
OS 30.31014512 41.1515306
OS 30.32282226 41.15279806
OS 30.35894868 41.15470052
OS 30.36845844 41.16040536
OS 30.37099336 41.16167282
OS 30.37543074 41.1648402
OS 30.3766982 41.16737512
OS 30.4996596 41.29033652
OS 30.50092706 41.29287144
OS 30.50853182 41.30047874
OS 30.51106928 41.30681604
OS 30.51550666 41.31886072
OS 30.51740658 41.32456556
OS 30.51867404 41.3296354
OS 30.5205765 41.35942452
OS 30.52247896 41.39682094
OS 30.52374642 41.50837266
OS 30.52311142 42.026205
OS 30.52374642 42.0344473
OS 30.52247896 42.03824968
OS 30.52311142 42.06043404
OS 30.52184396 42.06677134
OS 30.51930904 42.10099784
OS 30.51867404 42.10670268
OS 30.5199415 42.11050506
OS 30.51867404 42.11557744
OS 30.51233674 42.12698458
OS 30.5066319 42.13395688
OS 30.4996596 42.13965918
OS 30.49839214 42.14219664
OS 30.4926873 42.14790148
OS 30.49015238 42.14916894
OS 30.48698246 42.15233632
OS 30.485715 42.15487378
OS 30.48001016 42.16057608
OS 30.47747524 42.16184608
OS 30.47557278 42.163746
OS 30.47430532 42.16628092
OS 30.46860048 42.17198576
OS 30.4660681 42.17325322
OS 30.46289818 42.17642314
OS 30.46163072 42.17895806
OS 30.45592588 42.18466036
OS 30.45339096 42.18592782
OS 30.4514885 42.18783028
OS 30.45022104 42.1903652
OS 30.4445162 42.19607004
OS 30.44198128 42.1973375
OS 30.43881136 42.20050742
OS 30.4375439 42.20304234
OS 30.43183906 42.20874718
OS 30.42930414 42.21001464
OS 30.42613422 42.21318456
OS 30.42486676 42.21571948
OS 30.41916192 42.22142432
OS 30.416627 42.22269178
OS 30.41472708 42.22459424
OS 30.41345708 42.22712916
OS 30.40775478 42.232834
OS 30.40521986 42.23410146
OS 30.40205248 42.23727138
OS 30.40078248 42.2398063
OS 30.39508018 42.2455086
OS 30.39254272 42.24677606
OS 30.3906428 42.24867852
OS 30.38937534 42.25121344
OS 30.3836705 42.25691828
OS 30.38113558 42.25818574
OS 30.37796566 42.26135566
OS 30.3766982 42.26389058
OS 30.37099336 42.26959542
OS 30.36845844 42.27086288
OS 30.3621186 42.27720018
OS 30.35958368 42.27846764
OS 30.35070892 42.28227256
OS 30.3424717 42.28543994
OS 30.3361344 42.28797486
OS 30.3285271 42.28924486
OS 30.32535718 42.28987732
OS 30.3215548 42.28860986
OS 30.31775242 42.28987732
OS 30.28289346 42.29177978
OS 30.22711506 42.29304724
OS 29.68519844 42.2936797
OE
OB 27.03454842 42.2936797 H
OS 27.03074604 42.29241224
OS 27.00602676 42.29304724
OS 27.00539176 42.29241224
OS 26.9698978 42.2936797
OS 26.48185458 42.29241224
OS 26.4780522 42.29114478
OS 26.44192324 42.28924486
OS 26.42797864 42.28797486
OS 26.42164134 42.28543994
OS 26.41149912 42.28163756
OS 26.40516182 42.27910264
OS 26.40072444 42.27593272
OS 26.39692206 42.27213034
OS 26.3943846 42.27086288
OS 26.39184968 42.26832796
OS 26.38931476 42.26705796
OS 26.38741484 42.26515804
OS 26.38614738 42.26262312
OS 26.38044254 42.25691828
OS 26.37790762 42.25565082
OS 26.3747377 42.2524809
OS 26.37347024 42.24994598
OS 26.3677654 42.24424368
OS 26.36523048 42.24297622
OS 26.3620631 42.2398063
OS 26.3607931 42.23727138
OS 26.35508826 42.23156654
OS 26.35255334 42.23029908
OS 26.35065342 42.22839662
OS 26.34938596 42.2258617
OS 26.34241366 42.2188894
OS 26.3398762 42.21762194
OS 26.33797628 42.21571948
OS 26.33670882 42.21318456
OS 26.33100398 42.20747972
OS 26.32846906 42.20621226
OS 26.32530168 42.20304234
OS 26.32403422 42.20050742
OS 26.31832938 42.19480258
OS 26.31579446 42.19353512
OS 26.313892 42.19163266
OS 26.31262454 42.18909774
OS 26.3069197 42.18339544
OS 26.30438478 42.18212798
OS 26.30121486 42.17895806
OS 26.2999474 42.17642314
OS 26.29551002 42.17198576
OS 26.2929751 42.1707183
OS 26.28980518 42.16754838
OS 26.28853772 42.16501346
OS 26.28283288 42.15930862
OS 26.28029796 42.15804116
OS 26.27712804 42.15487378
OS 26.27586058 42.15233632
OS 26.2714232 42.14790148
OS 26.26888828 42.14663148
OS 26.26445344 42.14219664
OS 26.26065106 42.1358568
OS 26.25431122 42.12698458
OS 26.25304376 42.12191474
OS 26.25114384 42.1098726
OS 26.24733892 42.09973038
OS 26.245439 42.09275808
OS 26.24417154 42.08768824
OS 26.24226908 42.05155928
OS 26.24100162 42.01606532
OS 26.24036662 41.41583538
OS 26.24163662 41.41203046
OS 26.24290408 41.35878952
OS 26.24417154 41.35498714
OS 26.245439 41.33597524
OS 26.2517763 41.3220281
OS 26.25304376 41.31695826
OS 26.2593836 41.3080835
OS 26.26318598 41.30428112
OS 26.26445344 41.3017462
OS 26.2714232 41.2947739
OS 26.27395812 41.29350644
OS 26.27586058 41.29160398
OS 26.27712804 41.28906906
OS 26.28410034 41.2820993
OS 26.28663526 41.28083184
OS 26.28980518 41.27639446
OS 26.29551002 41.27068962
OS 26.29804494 41.26942216
OS 26.2999474 41.2675197
OS 26.30121486 41.26498478
OS 26.30818716 41.25801248
OS 26.31072208 41.25674502
OS 26.31262454 41.25484256
OS 26.313892 41.25230764
OS 26.3208643 41.24533534
OS 26.32339922 41.24406788
OS 26.32656914 41.2396305
OS 26.33227144 41.23392566
OS 26.33480636 41.2326582
OS 26.33797628 41.22822336
OS 26.34494858 41.22125106
OS 26.3474835 41.2199836
OS 26.35065342 41.21554876
OS 26.35635826 41.20984392
OS 26.35889318 41.20857646
OS 26.3607931 41.206674
OS 26.3620631 41.20413908
OS 26.3690354 41.19716678
OS 26.37157032 41.19589932
OS 26.37347024 41.19399686
OS 26.3747377 41.19146194
OS 26.38171 41.18448964
OS 26.38424746 41.18322218
OS 26.38741484 41.1787848
OS 26.39311714 41.17307996
OS 26.3956546 41.1718125
OS 26.39755452 41.16991004
OS 26.39882198 41.16737512
OS 26.40072444 41.16420774
OS 26.40325936 41.16294028
OS 26.41720396 41.15406552
OS 26.46093768 41.1521656
OS 26.46854244 41.15089814
OS 26.48565696 41.15026314
OS 26.48945934 41.1515306
OS 26.4983341 41.15026314
OS 27.11060618 41.1515306
OS 27.1137761 41.15470052
OS 27.11631102 41.1648402
OS 27.11567602 41.28083184
OS 27.11631102 41.29160398
OS 27.11504356 41.2954089
OS 27.11567602 41.31759326
OS 27.11440856 41.32519802
OS 27.1131411 41.34294754
OS 27.11187364 41.35942452
OS 27.11123864 41.3638619
OS 27.1125061 41.36766428
OS 27.11123864 41.37273412
OS 27.10997118 41.37653904
OS 27.10426888 41.38351134
OS 27.10173396 41.38604626
OS 27.09539666 41.38858118
OS 27.05419532 41.39048364
OS 27.03708334 41.39238356
OS 27.02250628 41.3917511
OS 26.67897382 41.39301856
OS 26.60418352 41.39428602
OS 26.56995448 41.39555348
OS 26.54206782 41.39682094
OS 26.53699798 41.3980884
OS 26.53065814 41.40062332
OS 26.52241838 41.40379324
OS 26.51734854 41.40505816
OS 26.50910878 41.40949554
OS 26.50784132 41.41456538
OS 26.50847632 41.96282438
OS 26.50784132 41.97740144
OS 26.50910878 41.98120636
OS 26.51037624 41.9862762
OS 26.5116437 42.0192327
OS 26.51734854 42.026205
OS 26.52368584 42.03254484
OS 26.53382806 42.03507976
OS 26.5667871 42.03634722
OS 26.57058948 42.03761468
OS 26.59150638 42.03698222
OS 26.93376884 42.03824968
OS 27.00856168 42.03951714
OS 27.06180262 42.04331952
OS 27.06687246 42.04458698
OS 27.07764714 42.0477569
OS 27.08271952 42.04902436
OS 27.09539666 42.05029182
OS 27.11060618 42.05155928
OS 27.1137761 42.0547292
OS 27.11631102 42.06486888
OS 27.11567602 42.18086052
OS 27.11631102 42.19290012
OS 27.11504356 42.19670504
OS 27.11567602 42.2188894
OS 27.11440856 42.2252267
OS 27.11187364 42.26072066
OS 27.11123864 42.26515804
OS 27.1125061 42.26896042
OS 27.11123864 42.27403026
OS 27.10997118 42.27656772
OS 27.10426888 42.28354002
OS 27.1004665 42.2873424
OS 27.09159174 42.28987732
OS 27.08271952 42.28860986
OS 27.0789146 42.28987732
OS 27.04786056 42.29177978
OS 27.04025326 42.29304724
OS 27.03454842 42.2936797
OE
OB 28.0296493 42.2936797 H
OS 28.02584692 42.29241224
OS 28.0163397 42.29051232
OS 27.99986272 42.28924486
OS 27.99542534 42.2873424
OS 27.99289042 42.28480748
OS 27.99035296 42.28354002
OS 27.98148074 42.27720018
OS 27.9751409 42.26959542
OS 27.96943606 42.26515804
OS 27.9681686 42.26262312
OS 27.9611963 42.25565082
OS 27.95866138 42.25438336
OS 27.95675892 42.2524809
OS 27.95549146 42.24994598
OS 27.94978662 42.24424368
OS 27.94725424 42.24297622
OS 27.94408432 42.2398063
OS 27.94281686 42.23727138
OS 27.93711202 42.23156654
OS 27.9345771 42.23029908
OS 27.93267718 42.22839662
OS 27.93140718 42.2258617
OS 27.92443488 42.2188894
OS 27.92189996 42.21762194
OS 27.92000004 42.21571948
OS 27.91873258 42.21318456
OS 27.91302774 42.20747972
OS 27.91049028 42.20621226
OS 27.90859036 42.2043098
OS 27.9073229 42.20177488
OS 27.9003506 42.19480258
OS 27.89781314 42.19353512
OS 27.89591322 42.19163266
OS 27.89464576 42.18909774
OS 27.88894092 42.18339544
OS 27.88640854 42.18212798
OS 27.88323862 42.17895806
OS 27.88197116 42.17642314
OS 27.87626632 42.1707183
OS 27.8737314 42.16945084
OS 27.87182894 42.16754838
OS 27.87056148 42.16501346
OS 27.86358918 42.15804116
OS 27.86105426 42.1567737
OS 27.8591518 42.15487378
OS 27.85788434 42.15233632
OS 27.8521795 42.14663148
OS 27.84964458 42.14536402
OS 27.84774212 42.1434641
OS 27.84647466 42.14092918
OS 27.83950236 42.13395688
OS 27.83696744 42.13268688
OS 27.83506498 42.13078696
OS 27.83379752 42.12825204
OS 27.82809522 42.12254974
OS 27.8255603 42.12128228
OS 27.82239038 42.11811236
OS 27.82112292 42.11557744
OS 27.81541808 42.1098726
OS 27.81288316 42.10860514
OS 27.8109807 42.10670268
OS 27.80971324 42.10416776
OS 27.80274094 42.09719546
OS 27.80020602 42.095928
OS 27.7983061 42.09402554
OS 27.7970361 42.09149062
OS 27.7900638 42.08451832
OS 27.78752888 42.08325086
OS 27.77802166 42.06993872
OS 27.78119158 42.06423642
OS 27.7900638 42.06296896
OS 27.79957356 42.0623365
OS 27.8458422 42.06296896
OS 27.84964458 42.0617015
OS 27.8661241 42.06296896
OS 27.9136602 42.06106904
OS 27.92380242 42.0623365
OS 27.92697234 42.06296896
OS 27.93077472 42.0617015
OS 27.94345186 42.06043404
OS 27.97197098 42.05853158
OS 27.97894582 42.05409674
OS 27.98718558 42.04585444
OS 27.98845304 42.0407846
OS 27.99035296 42.0059231
OS 27.99162042 42.0008558
OS 27.99225542 41.98881112
OS 27.99098796 41.98500874
OS 27.99225542 41.96218938
OS 27.99098796 41.958387
OS 27.99225542 41.94951224
OS 27.99162042 41.8347906
OS 27.99225542 41.81894608
OS 27.99098796 41.8151437
OS 27.99225542 41.7948618
OS 27.9897205 41.78852196
OS 27.98781804 41.75239554
OS 27.98148074 41.74225332
OS 27.97640836 41.73464856
OS 27.97387344 41.7333811
OS 27.96373122 41.72704126
OS 27.954859 41.72450634
OS 27.94788924 41.72514134
OS 27.92506988 41.72387134
OS 27.92000004 41.72260388
OS 27.90542044 41.72197142
OS 27.90161806 41.72323888
OS 27.88894092 41.72197142
OS 27.62970852 41.72260388
OS 27.61386146 41.72197142
OS 27.60752416 41.72450634
OS 27.58407488 41.72514134
OS 27.57710258 41.72450634
OS 27.57329766 41.7257738
OS 27.57076274 41.72704126
OS 27.56315798 41.73211364
OS 27.56062052 41.7333811
OS 27.55491568 41.73781594
OS 27.55364822 41.7403534
OS 27.54731092 41.74922562
OS 27.54350854 41.75810038
OS 27.54223854 41.78218466
OS 27.54097108 41.79739672
OS 27.53653624 41.8018341
OS 27.53146386 41.80056664
OS 27.52892894 41.79802918
OS 27.52639656 41.79676172
OS 27.5111845 41.78154966
OS 27.50864704 41.7802822
OS 27.50674712 41.77838228
OS 27.50547966 41.77584482
OS 27.49850736 41.76887252
OS 27.49597244 41.76760506
OS 27.4896326 41.76000284
OS 27.48456276 41.75493046
OS 27.4820253 41.753663
OS 27.47885792 41.74922562
OS 27.47442054 41.74478824
OS 27.47188562 41.74352078
OS 27.4687157 41.73908594
OS 27.4630134 41.7333811
OS 27.46047848 41.73211364
OS 27.45857602 41.73021118
OS 27.45730856 41.72767626
OS 27.45033626 41.72070396
OS 27.44780134 41.7194365
OS 27.44589888 41.71753404
OS 27.44463142 41.71499912
OS 27.43765912 41.70802682
OS 27.4357592 41.70739182
OS 27.4344892 41.7048569
OS 27.42624944 41.69661968
OS 27.42371452 41.69535222
OS 27.4205446 41.6921823
OS 27.41927714 41.68964738
OS 27.41230484 41.68267508
OS 27.41040492 41.68204008
OS 27.40913746 41.67950516
OS 27.4008977 41.6712654
OS 27.39836278 41.66999794
OS 27.39519286 41.66556056
OS 27.38949056 41.65985572
OS 27.3869531 41.65858826
OS 27.38505318 41.6566858
OS 27.38378572 41.65415088
OS 27.37681342 41.64717858
OS 27.37427596 41.64591112
OS 27.37237604 41.6440112
OS 27.37110858 41.64147628
OS 27.36286882 41.63323652
OS 27.36096636 41.63260406
OS 27.3596989 41.6300666
OS 27.35145914 41.62182684
OS 27.34892422 41.62055938
OS 27.34575684 41.616122
OS 27.34131946 41.61168716
OS 27.33878454 41.61041716
OS 27.33688208 41.60851724
OS 27.33561462 41.60598232
OS 27.32864232 41.59901002
OS 27.3261074 41.59774256
OS 27.32420494 41.5958401
OS 27.32293748 41.59330518
OS 27.31596518 41.58633288
OS 27.31343026 41.58506542
OS 27.31026034 41.58063058
OS 27.30328804 41.57365828
OS 27.30075312 41.57239082
OS 27.29885066 41.57048836
OS 27.28997844 41.55147392
OS 27.2912459 41.5413317
OS 27.28997844 41.53752932
OS 27.28807852 41.5077402
OS 27.28681106 41.5001329
OS 27.28617606 41.4931606
OS 27.28744352 41.48935822
OS 27.28681106 41.4659064
OS 27.28744352 41.4525968
OS 27.28617606 41.44879442
OS 27.28681106 41.4316799
OS 27.28617606 41.16357528
OS 27.28744352 41.15977036
OS 27.28871098 41.15470052
OS 27.29187836 41.1515306
OS 27.29695074 41.15026314
OS 27.53653624 41.1515306
OS 27.53970362 41.15470052
OS 27.54223854 41.1648402
OS 27.54287354 41.38984864
OS 27.54223854 41.39935586
OS 27.54350854 41.40316078
OS 27.544776 41.45766918
OS 27.54604346 41.46147156
OS 27.54731092 41.47541362
OS 27.55238076 41.4868233
OS 27.55364822 41.49189314
OS 27.55618568 41.49823298
OS 27.55935306 41.50140036
OS 27.56442544 41.50266782
OS 27.57646758 41.5071052
OS 27.58280488 41.50964012
OS 27.58787726 41.51091012
OS 27.61576392 41.51217758
OS 27.65125788 41.51344504
OS 27.72478072 41.5147125
OS 27.80908078 41.51534496
OS 27.81288316 41.5140775
OS 27.91809758 41.51281004
OS 27.92189996 41.51154258
OS 27.95105408 41.51027512
OS 27.96499868 41.50393782
OS 27.97324098 41.50203536
OS 27.97767582 41.49886544
OS 27.98084574 41.49189314
OS 27.9827482 41.48365338
OS 27.98845304 41.47034378
OS 27.99035296 41.4316799
OS 27.99162042 41.38097388
OS 27.99289042 41.16040536
OS 27.99415788 41.15533552
OS 27.99796026 41.1515306
OS 28.0030301 41.15026314
OS 28.2426156 41.1515306
OS 28.24578552 41.15470052
OS 28.24705298 41.15977036
OS 28.24768544 41.23646312
OS 28.24705298 41.24089796
OS 28.24832044 41.24470288
OS 28.24705298 41.2535751
OS 28.24832044 41.30428112
OS 28.24832044 41.9659943
OS 28.24832044 41.96726176
OS 28.24705298 41.9799389
OS 28.24578552 42.06613634
OS 28.24451806 42.06993872
OS 28.2432506 42.10416776
OS 28.23817822 42.11557744
OS 28.23691076 42.12064728
OS 28.23437584 42.12698458
OS 28.23310838 42.1295195
OS 28.22676854 42.1358568
OS 28.22550108 42.13839172
OS 28.21979624 42.14536402
OS 28.21282394 42.15106886
OS 28.20712164 42.15804116
OS 28.20014934 42.163746
OS 28.1944445 42.1707183
OS 28.18747474 42.17642314
OS 28.1817699 42.18339544
OS 28.17923244 42.18466036
OS 28.1747976 42.18909774
OS 28.1735276 42.19163266
OS 28.16909276 42.19607004
OS 28.1665553 42.1973375
OS 28.16212046 42.20177488
OS 28.160853 42.2043098
OS 28.15768308 42.20747972
OS 28.15514816 42.20874718
OS 28.15071078 42.21318456
OS 28.14944332 42.21571948
OS 28.14500594 42.22015686
OS 28.14247102 42.22142432
OS 28.13803364 42.2258617
OS 28.13676618 42.22839662
OS 28.1323288 42.232834
OS 28.12979388 42.23410146
OS 28.12535904 42.23853884
OS 28.12409158 42.24107376
OS 28.12092166 42.24424368
OS 28.11838674 42.2455086
OS 28.11394936 42.24994598
OS 28.1126819 42.2524809
OS 28.10824452 42.25691828
OS 28.1057096 42.25818574
OS 28.10127222 42.26262312
OS 28.10000476 42.26515804
OS 28.09556738 42.26959542
OS 28.09303246 42.27086288
OS 28.08986254 42.27403026
OS 28.08859508 42.27656772
OS 28.0841577 42.28100256
OS 28.08162278 42.28227256
OS 28.07275056 42.28860986
OS 28.06768072 42.28987732
OS 28.04993374 42.29114478
OS 28.04613136 42.29241224
OS 28.0296493 42.2936797
OE
OB 27.61512892 44.24078528 H
OS 27.61132654 44.23951528
OS 27.60498924 44.2357129
OS 27.60308678 44.2287406
OS 27.60245178 42.5408725
OS 27.60308678 42.52502544
OS 27.60181932 42.52122306
OS 27.60308678 42.50220608
OS 27.60181932 42.4984037
OS 27.60308678 42.47685688
OS 27.60055186 42.47051704
OS 27.59991686 42.46227728
OS 27.60055186 42.45530498
OS 27.5992844 42.4515026
OS 27.59801694 42.43248562
OS 27.5916771 42.42361594
OS 27.58787726 42.4172761
OS 27.5859748 42.41537364
OS 27.58343988 42.41410618
OS 27.57773504 42.40840134
OS 27.57646758 42.40586642
OS 27.57456512 42.4039665
OS 27.5720302 42.40269904
OS 27.56632536 42.3969942
OS 27.5650579 42.39445674
OS 27.56188798 42.39128936
OS 27.55935306 42.3900219
OS 27.55364822 42.38431706
OS 27.55238076 42.3817796
OS 27.54921084 42.37861222
OS 27.54667592 42.37734476
OS 27.54223854 42.37290738
OS 27.54097108 42.37037246
OS 27.5378037 42.36720254
OS 27.53526624 42.36593508
OS 27.52956394 42.36023278
OS 27.52829648 42.35769786
OS 27.5251291 42.35452794
OS 27.52259164 42.35326048
OS 27.51688934 42.34755564
OS 27.51561934 42.34502072
OS 27.51245196 42.3418508
OS 27.50611212 42.33804842
OS 27.49977482 42.33170858
OS 27.49090006 42.32917366
OS 27.48456276 42.32537128
OS 27.47949038 42.3202989
OS 27.47695546 42.31903144
OS 27.46998316 42.3133266
OS 27.46428086 42.3063543
OS 27.45730856 42.300652
OS 27.4560411 42.29811708
OS 27.45033626 42.29241224
OS 27.44780134 42.29114478
OS 27.44463142 42.28797486
OS 27.44336396 42.28543994
OS 27.43892658 42.28100256
OS 27.43639166 42.2797351
OS 27.43322174 42.27656772
OS 27.43195428 42.27403026
OS 27.42624944 42.26832796
OS 27.42371452 42.26705796
OS 27.4205446 42.26389058
OS 27.41927714 42.26135566
OS 27.4148423 42.25691828
OS 27.41230484 42.25565082
OS 27.40913746 42.2524809
OS 27.40787 42.24994598
OS 27.40216516 42.24424368
OS 27.39963024 42.24297622
OS 27.39646286 42.2398063
OS 27.39519286 42.23727138
OS 27.39075802 42.232834
OS 27.38822056 42.23156654
OS 27.38505318 42.22839662
OS 27.38378572 42.2258617
OS 27.37808088 42.22015686
OS 27.37554596 42.2188894
OS 27.37237604 42.21571948
OS 27.37110858 42.21318456
OS 27.3666712 42.20874718
OS 27.36413628 42.20747972
OS 27.3596989 42.20304234
OS 27.35843144 42.20050742
OS 27.35399406 42.19607004
OS 27.35145914 42.19480258
OS 27.34829176 42.19163266
OS 27.3470243 42.18909774
OS 27.34131946 42.18339544
OS 27.33878454 42.18212798
OS 27.33561462 42.17895806
OS 27.33434716 42.17642314
OS 27.32864232 42.1707183
OS 27.3261074 42.16945084
OS 27.32293748 42.16628092
OS 27.32167002 42.163746
OS 27.31723264 42.15930862
OS 27.31469772 42.15804116
OS 27.3115278 42.15487378
OS 27.31026034 42.15233632
OS 27.30582296 42.14790148
OS 27.30328804 42.14663148
OS 27.29885066 42.14219664
OS 27.2975832 42.13965918
OS 27.29314582 42.13522434
OS 27.2906109 42.13395688
OS 27.28744352 42.13078696
OS 27.28617606 42.12825204
OS 27.28047122 42.12254974
OS 27.2779363 42.12128228
OS 27.27476892 42.11811236
OS 27.27349892 42.11557744
OS 27.26779408 42.1098726
OS 27.26525916 42.10860514
OS 27.26335924 42.10670268
OS 27.26209178 42.10416776
OS 27.25638694 42.09846292
OS 27.25384948 42.09719546
OS 27.24941464 42.09275808
OS 27.24814718 42.09022316
OS 27.24497726 42.08705324
OS 27.24244234 42.08578578
OS 27.23800496 42.0813484
OS 27.2367375 42.07881348
OS 27.23230012 42.0743761
OS 27.2297652 42.07310864
OS 27.22659782 42.06993872
OS 27.22533036 42.0674038
OS 27.21962552 42.0617015
OS 27.2170906 42.06043404
OS 27.21392068 42.05726412
OS 27.21265322 42.0547292
OS 27.20694838 42.04902436
OS 27.20441346 42.0477569
OS 27.202511 42.04585444
OS 27.20124354 42.04331952
OS 27.1955387 42.03761468
OS 27.19300378 42.03634722
OS 27.1885664 42.03190984
OS 27.18729894 42.02937492
OS 27.18412902 42.026205
OS 27.1815941 42.02493754
OS 27.17715672 42.0205027
OS 27.17588926 42.01796524
OS 27.17145188 42.0135304
OS 27.16891696 42.0122604
OS 27.16574958 42.00909302
OS 27.16448212 42.0065581
OS 27.15877728 42.0008558
OS 27.15624236 41.9995858
OS 27.15307244 41.99641842
OS 27.15180498 41.9938835
OS 27.14737014 41.98944612
OS 27.14483268 41.98817866
OS 27.14039784 41.98374128
OS 27.13912784 41.98120636
OS 27.134693 41.97676898
OS 27.13215554 41.97550152
OS 27.12898816 41.9723316
OS 27.1277207 41.96979668
OS 27.12201586 41.96409184
OS 27.1194784 41.96282438
OS 27.11757848 41.96092192
OS 27.11631102 41.958387
OS 27.11060618 41.95268216
OS 27.1080738 41.9514147
OS 27.10490388 41.94824478
OS 27.10363642 41.94570986
OS 27.09793158 41.94000756
OS 27.09539666 41.9387401
OS 27.09222674 41.93557018
OS 27.09095928 41.93303526
OS 27.08525444 41.92733042
OS 27.08271952 41.92606296
OS 27.08081706 41.9241605
OS 27.0795496 41.92162558
OS 27.07384476 41.91592074
OS 27.07130984 41.91465328
OS 27.06813992 41.91148336
OS 27.06687246 41.90894844
OS 27.06116762 41.9032436
OS 27.0586327 41.90197614
OS 27.05546278 41.89880876
OS 27.05419532 41.8962713
OS 27.04849302 41.89056646
OS 27.0459581 41.889299
OS 27.04405564 41.88739908
OS 27.04278818 41.88486162
OS 27.04025326 41.88232924
OS 27.0389858 41.87979432
OS 27.03391596 41.87472448
OS 27.03264596 41.87218702
OS 27.03011104 41.86584972
OS 27.02884358 41.86077988
OS 27.02377374 41.8493702
OS 27.02250628 41.83669306
OS 27.02060382 41.79929918
OS 27.01933636 41.75619792
OS 27.01870136 41.72387134
OS 27.01997136 41.72006896
OS 27.02123882 41.65922326
OS 27.02250628 41.65541834
OS 27.02377374 41.6300666
OS 27.02884358 41.61865946
OS 27.03011104 41.61358708
OS 27.03645088 41.6021774
OS 27.04152072 41.59710756
OS 27.04278818 41.59457264
OS 27.04722556 41.5888678
OS 27.04975794 41.58760034
OS 27.05673024 41.58063058
OS 27.05736524 41.57872812
OS 27.05990016 41.57746066
OS 27.06497 41.57239082
OS 27.06750746 41.57112336
OS 27.07004238 41.5685859
OS 27.07511222 41.56731844
OS 27.07764714 41.56985336
OS 27.0801846 41.57112336
OS 27.08398698 41.57492574
OS 27.0865219 41.5761932
OS 27.09095928 41.58063058
OS 27.09222674 41.5831655
OS 27.09666412 41.58760034
OS 27.09919904 41.5888678
OS 27.10363642 41.59330518
OS 27.10490388 41.5958401
OS 27.10933872 41.60027748
OS 27.11187364 41.60154494
OS 27.11631102 41.60598232
OS 27.11757848 41.60851724
OS 27.1207484 41.61168716
OS 27.12328332 41.61295462
OS 27.1277207 41.617392
OS 27.12898816 41.61992692
OS 27.13342554 41.6243643
OS 27.13596046 41.62563176
OS 27.14039784 41.6300666
OS 27.1416653 41.63260406
OS 27.14610014 41.6370389
OS 27.1486376 41.6383089
OS 27.15180498 41.64147628
OS 27.15307244 41.6440112
OS 27.15750982 41.64844604
OS 27.16004474 41.6497135
OS 27.16448212 41.65415088
OS 27.16574958 41.6566858
OS 27.17018442 41.66112318
OS 27.17271934 41.66239064
OS 27.17715672 41.66682802
OS 27.17842418 41.66936294
OS 27.1815941 41.67253286
OS 27.18412902 41.67380032
OS 27.19110132 41.67950516
OS 27.19427124 41.68267508
OS 27.20061108 41.68521
OS 27.20885084 41.68837992
OS 27.21582314 41.69535222
OS 27.21835806 41.69661968
OS 27.22533036 41.70232452
OS 27.22659782 41.7048569
OS 27.23356758 41.7118292
OS 27.2361025 41.71309666
OS 27.23927242 41.71753404
OS 27.24497726 41.72323888
OS 27.24751218 41.72450634
OS 27.24941464 41.7264088
OS 27.2506821 41.72894372
OS 27.25638694 41.73464856
OS 27.25892186 41.73591602
OS 27.26082178 41.73781594
OS 27.26209178 41.7403534
OS 27.26906408 41.7473257
OS 27.271599 41.74859316
OS 27.27349892 41.75049308
OS 27.27476892 41.75303054
OS 27.28047122 41.75873538
OS 27.28300868 41.76000284
OS 27.2849086 41.76190276
OS 27.28617606 41.76443768
OS 27.29314582 41.77140998
OS 27.29568328 41.77267744
OS 27.29885066 41.77711228
OS 27.30582296 41.78408458
OS 27.30772542 41.78471958
OS 27.30899288 41.7872545
OS 27.31723264 41.79549426
OS 27.31976756 41.79676172
OS 27.32167002 41.79866418
OS 27.32293748 41.8011991
OS 27.32990978 41.8081714
OS 27.3324447 41.80943886
OS 27.33434716 41.81134132
OS 27.33561462 41.81387624
OS 27.34258692 41.82084854
OS 27.34512184 41.822116
OS 27.35145914 41.82972076
OS 27.35526152 41.83352314
OS 27.35779644 41.8347906
OS 27.36413628 41.8423979
OS 27.3666712 41.84493282
OS 27.36857366 41.84556782
OS 27.36984112 41.84810274
OS 27.37808088 41.8563425
OS 27.3806158 41.85760996
OS 27.38251826 41.85951242
OS 27.38378572 41.86204734
OS 27.39075802 41.86901964
OS 27.39329294 41.8702871
OS 27.39519286 41.87218702
OS 27.39646286 41.87472448
OS 27.40343516 41.88169678
OS 27.40597008 41.88296424
OS 27.40913746 41.88739908
OS 27.41610976 41.89437138
OS 27.41864468 41.89563884
OS 27.4218146 41.90007622
OS 27.4275169 41.90578106
OS 27.42941936 41.90641352
OS 27.43068682 41.90894844
OS 27.43892658 41.9171882
OS 27.4414615 41.91845566
OS 27.44336396 41.92035812
OS 27.44463142 41.92289304
OS 27.45160372 41.92986534
OS 27.45413864 41.9311328
OS 27.4560411 41.93303526
OS 27.45730856 41.93557018
OS 27.46428086 41.94254248
OS 27.46681578 41.94380994
OS 27.46998316 41.94824478
OS 27.475688 41.95394962
OS 27.47822292 41.95521708
OS 27.48012538 41.95711954
OS 27.48139284 41.95965446
OS 27.48836514 41.96662676
OS 27.49090006 41.96789422
OS 27.4972399 41.97550152
OS 27.49977482 41.97803644
OS 27.50230974 41.9793039
OS 27.5042122 41.98120636
OS 27.50547966 41.98374128
OS 27.51245196 41.99071358
OS 27.51498688 41.99198104
OS 27.51688934 41.9938835
OS 27.5181568 41.99641842
OS 27.5251291 42.00339072
OS 27.52766402 42.00465564
OS 27.5308314 42.00909302
OS 27.53653624 42.01479786
OS 27.53907116 42.01606532
OS 27.54097108 42.01796524
OS 27.54223854 42.0205027
OS 27.54921084 42.027475
OS 27.5517483 42.02874246
OS 27.55491568 42.0331773
OS 27.56062052 42.03888214
OS 27.56315798 42.04015214
OS 27.5650579 42.04205206
OS 27.56632536 42.04458698
OS 27.5720302 42.05029182
OS 27.57456512 42.05155928
OS 27.57773504 42.0547292
OS 27.5790025 42.05726412
OS 27.5859748 42.06423642
OS 27.58787726 42.06486888
OS 27.58914218 42.0674038
OS 27.59738194 42.07564356
OS 27.59991686 42.07691102
OS 27.60181932 42.07881348
OS 27.60308678 42.0813484
OS 27.60879162 42.08705324
OS 27.61132654 42.0883207
OS 27.613229 42.09022316
OS 27.61449646 42.09275808
OS 27.62146876 42.09973038
OS 27.62400368 42.10099784
OS 27.62590614 42.1029003
OS 27.6271736 42.10543522
OS 27.63287844 42.11114006
OS 27.63541336 42.11240752
OS 27.63858328 42.11557744
OS 27.63985074 42.11811236
OS 27.64682304 42.12508212
OS 27.64935542 42.12634958
OS 27.65125788 42.12825204
OS 27.65252534 42.13078696
OS 27.65949764 42.13775926
OS 27.66139756 42.13839172
OS 27.66266502 42.14092918
OS 27.66963732 42.14790148
OS 27.67217478 42.14916894
OS 27.6740747 42.15106886
OS 27.67534216 42.15360378
OS 27.68231446 42.16057608
OS 27.68485192 42.16184608
OS 27.68675184 42.163746
OS 27.6880193 42.16628092
OS 27.6949916 42.17325322
OS 27.69752906 42.17452322
OS 27.69942898 42.17642314
OS 27.70069644 42.17895806
OS 27.70640128 42.18466036
OS 27.70893366 42.18592782
OS 27.71083612 42.18783028
OS 27.71210358 42.1903652
OS 27.71907588 42.1973375
OS 27.7216108 42.19860496
OS 27.72351326 42.20050742
OS 27.72478072 42.20304234
OS 27.73175302 42.21001464
OS 27.73428794 42.2112821
OS 27.73745786 42.21571948
OS 27.7431627 42.22142432
OS 27.74569762 42.22269178
OS 27.74760008 42.22459424
OS 27.74886754 42.22712916
OS 27.75583984 42.23410146
OS 27.75837476 42.23536892
OS 27.76027722 42.23727138
OS 27.76154468 42.2398063
OS 27.76724952 42.2455086
OS 27.7697819 42.24677606
OS 27.77168436 42.24867852
OS 27.77295182 42.25121344
OS 27.77992412 42.25818574
OS 27.78245904 42.2594532
OS 27.7843615 42.26135566
OS 27.78562896 42.26389058
OS 27.79260126 42.27086288
OS 27.79513618 42.27213034
OS 27.80147348 42.2797351
OS 27.8040084 42.28227256
OS 27.80654586 42.28354002
OS 27.80844578 42.28543994
OS 27.80971324 42.28797486
OS 27.81668554 42.29494716
OS 27.819223 42.29621716
OS 27.82112292 42.29811708
OS 27.82239038 42.300652
OS 27.82809522 42.30762176
OS 27.8312626 42.31079168
OS 27.83379752 42.31713152
OS 27.83696744 42.32537128
OS 27.84203728 42.33297604
OS 27.8452072 42.33994834
OS 27.84774212 42.34628818
OS 27.85091204 42.35452794
OS 27.85408196 42.36530008
OS 27.85598188 42.40269904
OS 27.85724934 42.436923
OS 27.85788434 42.44769768
OS 27.85788434 42.44896514
OS 27.85724934 43.99232502
OS 27.85788434 44.010707
OS 27.85661688 44.01450938
OS 27.85534942 44.02338414
OS 27.85344696 44.06331294
OS 27.84774212 44.07282016
OS 27.84647466 44.07535762
OS 27.84203728 44.08106246
OS 27.83950236 44.08232992
OS 27.83379752 44.08803476
OS 27.83253006 44.09056968
OS 27.8306276 44.0924696
OS 27.82809522 44.0937396
OS 27.81985546 44.10197936
OS 27.818588 44.10451174
OS 27.81415062 44.10768166
OS 27.80844578 44.1133865
OS 27.80717832 44.11592142
OS 27.8052784 44.11782134
OS 27.80274094 44.1190888
OS 27.79576864 44.1260611
OS 27.79450118 44.12859856
OS 27.7900638 44.13176594
OS 27.7843615 44.13747078
OS 27.7830915 44.1400057
OS 27.78119158 44.14190816
OS 27.77865666 44.14317562
OS 27.77168436 44.15014792
OS 27.7704169 44.15268284
OS 27.76281214 44.15902268
OS 27.75900976 44.16282506
OS 27.75773976 44.16535744
OS 27.750135 44.17169728
OS 27.74760008 44.1742322
OS 27.74633262 44.17676712
OS 27.74443016 44.17866958
OS 27.74189524 44.17993704
OS 27.73492294 44.18690934
OS 27.73365548 44.18944426
OS 27.7292181 44.19261418
OS 27.72351326 44.19831902
OS 27.7222458 44.20085394
OS 27.72034334 44.2027564
OS 27.71780842 44.20402386
OS 27.71083612 44.21099616
OS 27.70956866 44.21353108
OS 27.70766874 44.21543354
OS 27.70513382 44.216701
OS 27.69816152 44.22240584
OS 27.69625906 44.22430322
OS 27.69372414 44.22557068
OS 27.68738684 44.22810814
OS 27.67534216 44.23254298
OS 27.66836986 44.2357129
OS 27.6601301 44.23761536
OS 27.6537928 44.23888282
OS 27.63858328 44.24015028
OS 27.61512892 44.24078528
OE
OB 29.00320336 42.2936797 H
OS 28.4137481 42.29241224
OS 28.40804326 42.28797486
OS 28.4067758 42.28290502
OS 28.40804326 41.15470052
OS 28.41121318 41.1515306
OS 28.41628302 41.15026314
OS 28.58551306 41.15089814
OS 28.60262758 41.15026314
OS 28.60642996 41.1515306
OS 28.61910456 41.15279806
OS 28.65396606 41.15470052
OS 28.65840344 41.15660298
OS 28.66791066 41.16610766
OS 28.66917558 41.1711775
OS 28.67107804 41.20984392
OS 28.67361296 41.23012328
OS 28.6729805 41.25104018
OS 28.67424796 41.25484256
OS 28.6729805 41.25864748
OS 28.67361296 41.28336676
OS 28.6723455 41.36956674
OS 28.67107804 41.38604626
OS 28.66981058 41.40759308
OS 28.66854312 41.42280768
OS 28.6672782 41.42787752
OS 28.66474328 41.43421482
OS 28.66157336 41.44499204
OS 28.66284082 41.45766918
OS 28.6729805 41.479216
OS 28.67488042 41.49633052
OS 28.67805034 41.5007679
OS 28.68502264 41.50266782
OS 28.81495634 41.50203536
OS 28.8308034 41.50266782
OS 28.83460578 41.50140036
OS 28.85615514 41.50266782
OS 28.86249244 41.5001329
OS 28.89862394 41.49823298
OS 28.9062287 41.4931606
OS 28.90939608 41.48999322
OS 28.911931 41.48872322
OS 28.91510092 41.48555584
OS 28.91763584 41.47668108
OS 28.92270568 41.46780632
OS 28.92904552 41.46147156
OS 28.93031298 41.45893664
OS 28.93601782 41.45196434
OS 28.93918774 41.44879442
OS 28.94172266 41.44245458
OS 28.94299012 41.43738474
OS 28.95186234 41.42344014
OS 28.95629972 41.411398
OS 28.95946964 41.40696062
OS 28.96453948 41.40189078
OS 28.96580948 41.39935586
OS 28.97151178 41.39238356
OS 28.97594662 41.38794618
OS 28.98165146 41.37210166
OS 28.98482138 41.36893174
OS 28.98608884 41.36639682
OS 28.98989122 41.35752206
OS 28.99306114 41.3492823
OS 29.0013009 41.34104508
OS 29.00510328 41.33470524
OS 29.01144312 41.32836794
OS 29.0152455 41.31949318
OS 29.01651296 41.31442334
OS 29.0228528 41.30554858
OS 29.02412026 41.30301366
OS 29.02665518 41.29667636
OS 29.02982256 41.2884366
OS 29.0348924 41.28083184
OS 29.03806232 41.27385954
OS 29.04123224 41.26561978
OS 29.04439962 41.2611824
OS 29.05073946 41.25484256
OS 29.05454184 41.24850526
OS 29.06088168 41.24216796
OS 29.06531652 41.23012328
OS 29.07165636 41.2199836
OS 29.07482628 41.21174384
OS 29.08116358 41.20033416
OS 29.08623342 41.19526432
OS 29.08750342 41.1927294
OS 29.09320572 41.1857571
OS 29.0963731 41.18258718
OS 29.09764056 41.18005226
OS 29.10017802 41.17371242
OS 29.10144548 41.16864258
OS 29.10588286 41.16294028
OS 29.10841778 41.16167282
OS 29.1109527 41.1591379
OS 29.11348762 41.15787044
OS 29.11602254 41.15533552
OS 29.1248973 41.15406552
OS 29.16229118 41.1521656
OS 29.16989848 41.15089814
OS 29.18828046 41.15026314
OS 29.19208284 41.1515306
OS 29.19715268 41.15026314
OS 29.38729962 41.1515306
OS 29.38919954 41.15343306
OS 29.390467 41.1585029
OS 29.38919954 41.16864258
OS 29.38286478 41.17751734
OS 29.38032732 41.18385464
OS 29.37715994 41.1920944
OS 29.37525748 41.19399686
OS 29.37399002 41.19653178
OS 29.36892018 41.20160416
OS 29.36765018 41.20413908
OS 29.36194788 41.21111138
OS 29.3575105 41.21554876
OS 29.35307312 41.22758836
OS 29.3499032 41.23202574
OS 29.34610082 41.23582812
OS 29.34483336 41.23836304
OS 29.33912852 41.2466028
OS 29.33722606 41.2472378
OS 29.3365936 41.24914026
OS 29.33469114 41.24977272
OS 29.33342368 41.25230764
OS 29.33088876 41.25864748
OS 29.32772138 41.26688724
OS 29.32581892 41.2687897
OS 29.32455146 41.27132462
OS 29.32201654 41.27385954
OS 29.3163117 41.28970406
OS 29.3093394 41.29667636
OS 29.30807194 41.29921128
OS 29.29919718 41.31062096
OS 29.29666226 41.31315588
OS 29.29412734 41.31949318
OS 29.29285988 41.32456556
OS 29.28398512 41.33851016
OS 29.27954774 41.35054976
OS 29.27638036 41.35498714
OS 29.27384544 41.3562546
OS 29.27257544 41.35878952
OS 29.27004052 41.36132444
OS 29.26624068 41.36766428
OS 29.25990084 41.37400158
OS 29.255466 41.38604626
OS 29.24912616 41.39618594
OS 29.24595624 41.40442824
OS 29.24342132 41.410763
OS 29.23771648 41.4177353
OS 29.2345491 41.42090522
OS 29.23074418 41.42724252
OS 29.22440688 41.43358236
OS 29.22187196 41.43991966
OS 29.21870204 41.44815942
OS 29.21553212 41.4525968
OS 29.21046228 41.4602041
OS 29.20855982 41.46717386
OS 29.20602744 41.47351116
OS 29.2003226 41.48428838
OS 29.19778768 41.4931606
OS 29.19905514 41.51851488
OS 29.20539244 41.5273871
OS 29.2079299 41.52992202
OS 29.21172974 41.53625932
OS 29.21489966 41.53942924
OS 29.21679958 41.54006424
OS 29.21743458 41.5406967
OS 29.2206045 41.54386662
OS 29.22187196 41.54640154
OS 29.2275768 41.55210638
OS 29.23011172 41.55337384
OS 29.2332791 41.55654376
OS 29.2345491 41.55907868
OS 29.2402514 41.56478352
OS 29.24278886 41.56605098
OS 29.24468878 41.56795344
OS 29.24595624 41.57048836
OS 29.25166108 41.5761932
OS 29.25419854 41.57746066
OS 29.25736592 41.58063058
OS 29.25863338 41.5831655
OS 29.26433822 41.5888678
OS 29.26687314 41.59013526
OS 29.26877306 41.59203772
OS 29.27004052 41.59457264
OS 29.27574536 41.60027748
OS 29.27828028 41.60154494
OS 29.2814502 41.60471486
OS 29.28271766 41.60724978
OS 29.2884225 41.61295462
OS 29.29095742 41.61422208
OS 29.29412734 41.617392
OS 29.2953948 41.61992692
OS 29.30109964 41.62563176
OS 29.30363456 41.62689922
OS 29.30553702 41.62879914
OS 29.30680448 41.6313366
OS 29.31250932 41.6370389
OS 29.31504424 41.6383089
OS 29.31821416 41.64147628
OS 29.31948162 41.6440112
OS 29.32518646 41.6497135
OS 29.32772138 41.6509835
OS 29.33088876 41.65415088
OS 29.33215622 41.6566858
OS 29.3365936 41.66112318
OS 29.33912852 41.66239064
OS 29.3435659 41.66682802
OS 29.34483336 41.66936294
OS 29.3505382 41.67633524
OS 29.35243812 41.6782377
OS 29.35497558 41.68457754
OS 29.35624304 41.68964738
OS 29.36131288 41.70105706
OS 29.36258034 41.70612436
OS 29.3644828 41.73591602
OS 29.36638272 41.7733099
OS 29.36701772 41.822116
OS 29.36638272 41.822751
OS 29.36765018 41.82655084
OS 29.36701772 41.9856412
OS 29.36765018 41.99515096
OS 29.36638272 41.99895334
OS 29.36511526 42.07247364
OS 29.3638478 42.07627856
OS 29.36194788 42.10606768
OS 29.35624304 42.11937982
OS 29.35307312 42.12761704
OS 29.34863574 42.13458934
OS 29.34483336 42.13839172
OS 29.3435659 42.14092918
OS 29.3365936 42.14790148
OS 29.33405868 42.14916894
OS 29.33215622 42.15106886
OS 29.33088876 42.15360378
OS 29.323919 42.16057608
OS 29.32138408 42.16184608
OS 29.31948162 42.163746
OS 29.31821416 42.16628092
OS 29.29856472 42.18592782
OS 29.29666226 42.18656282
OS 29.2953948 42.18909774
OS 29.28715504 42.1973375
OS 29.28462012 42.19860496
OS 29.2814502 42.20304234
OS 29.27574536 42.20874718
OS 29.27321044 42.21001464
OS 29.27130798 42.2119171
OS 29.27004052 42.21445202
OS 29.26307076 42.22142432
OS 29.26053584 42.22269178
OS 29.25863338 42.22459424
OS 29.25736592 42.22712916
OS 29.23898394 42.2455086
OS 29.23644902 42.24677606
OS 29.2345491 42.24867852
OS 29.2332791 42.25121344
OS 29.2263068 42.25818574
OS 29.22377188 42.2594532
OS 29.21743458 42.26705796
OS 29.21489966 42.26959542
OS 29.2123622 42.27086288
OS 29.20602744 42.27720018
OS 29.20349252 42.27846764
OS 29.19461776 42.28227256
OS 29.186378 42.28543994
OS 29.1800407 42.28797486
OS 29.1724334 42.28924486
OS 29.14454674 42.29051232
OS 29.10715032 42.29241224
OS 29.00320336 42.2936797
OE
OB 25.69464508 42.29241224 H
OS 25.6845054 42.29114478
OS 25.68260294 42.28924486
OS 25.68006802 42.28290502
OS 25.68196794 42.1973375
OS 25.6832354 42.1707183
OS 25.6845054 42.14916894
OS 25.68577286 42.13902672
OS 25.68704032 42.13395688
OS 25.68830778 42.12761704
OS 25.68957524 42.12001228
OS 25.6914777 42.1029003
OS 25.69274516 42.09402554
OS 25.69401262 42.07374364
OS 25.69718 42.0553642
OS 25.69908246 42.0483919
OS 25.7041523 42.02810746
OS 25.7054223 42.01543032
OS 25.70668976 42.00148826
OS 25.70922468 41.99515096
OS 25.71302706 41.98120636
OS 25.71429452 41.97613398
OS 25.71682944 41.96092192
OS 25.7187319 41.94507486
OS 25.71999936 41.9387401
OS 25.72126682 41.93367026
OS 25.7257042 41.91909066
OS 25.72697166 41.91402082
OS 25.72950404 41.8962713
OS 25.7314065 41.88169678
OS 25.73267396 41.87535694
OS 25.73647634 41.86521472
OS 25.7383788 41.85824242
OS 25.74091372 41.84810274
OS 25.74218118 41.8354256
OS 25.74408364 41.82718584
OS 25.74852102 41.81641116
OS 25.7523234 41.80753894
OS 25.75359086 41.79866418
OS 25.75485832 41.79359434
OS 25.75802824 41.78535458
OS 25.76373308 41.77204244
OS 25.766268 41.76317022
OS 25.76753546 41.754298
OS 25.77514276 41.73781594
OS 25.77767768 41.72894372
OS 25.7802126 41.71753404
OS 25.78655244 41.70359198
OS 25.78908482 41.69471722
OS 25.79035228 41.68964738
OS 25.79225474 41.68140762
OS 25.79859204 41.66746302
OS 25.8004945 41.66175818
OS 25.80302942 41.65161596
OS 25.80429688 41.6440112
OS 25.81063418 41.63387152
OS 25.8138041 41.62563176
OS 25.82014394 41.61168716
OS 25.82584878 41.59837502
OS 25.8277487 41.58760034
OS 25.83091862 41.57936312
OS 25.83979338 41.56034614
OS 25.84993052 41.53879678
OS 25.85119798 41.52992202
OS 25.85310044 41.52295226
OS 25.85880528 41.51217758
OS 25.86260766 41.50330282
OS 25.92472336 41.3778065
OS 25.92852574 41.37146666
OS 25.93486558 41.36512936
OS 25.93613304 41.36259444
OS 25.94183788 41.35562214
OS 25.9437378 41.35371968
OS 25.94500526 41.35118476
OS 25.95007764 41.33977762
OS 25.95514748 41.33090286
OS 25.96148732 41.31695826
OS 25.96782462 41.30554858
OS 25.97289446 41.2941389
OS 25.9779643 41.28526668
OS 25.9843016 41.27892938
OS 25.98556906 41.27639446
OS 25.9912739 41.26942216
OS 25.99444382 41.26625224
OS 25.99697874 41.25991494
OS 25.9982462 41.25484256
OS 26.00712096 41.24089796
OS 26.00838842 41.23582812
OS 26.01472826 41.22442098
OS 26.0197981 41.21935114
OS 26.02106556 41.21681622
OS 26.03627508 41.20160416
OS 26.03754254 41.1990667
OS 26.04134746 41.19526432
OS 26.04261492 41.1927294
OS 26.04514984 41.18638956
OS 26.05148714 41.17498242
OS 26.05782698 41.16864258
OS 26.05909444 41.16610766
OS 26.06289682 41.16230782
OS 26.06416428 41.15977036
OS 26.0679692 41.15596798
OS 26.07240404 41.14392584
OS 26.07874388 41.13631854
OS 26.0819138 41.13188116
OS 26.08444872 41.12934624
OS 26.08508118 41.12744632
OS 26.08761864 41.12617632
OS 26.09585586 41.11793656
OS 26.09712332 41.11540164
OS 26.10219316 41.1103318
OS 26.10346062 41.10779688
OS 26.10726554 41.09892466
OS 26.108533 41.09512228
OS 26.11423784 41.08814998
OS 26.11740522 41.08498006
OS 26.11867268 41.08244514
OS 26.14656188 41.05455594
OS 26.14783188 41.05201848
OS 26.15163172 41.0482161
OS 26.15289918 41.04568118
OS 26.15796902 41.03300658
OS 26.16430886 41.02666674
OS 26.16557632 41.02413182
OS 26.17128116 41.01715952
OS 26.17825346 41.01145468
OS 26.1839583 41.00448238
OS 26.1909306 40.99877754
OS 26.19219806 40.99624262
OS 26.19663544 40.99180524
OS 26.19917036 40.99053778
OS 26.2048752 40.98483294
OS 26.20614266 40.98230056
OS 26.20804258 40.98040064
OS 26.2105775 40.97913064
OS 26.3747377 40.81497044
OS 26.3760077 40.81243552
OS 26.37790762 40.81053306
OS 26.38044254 40.8092656
OS 26.38614738 40.8035633
OS 26.38741484 40.80102838
OS 26.39184968 40.796591
OS 26.3943846 40.79532354
OS 26.39755452 40.79215362
OS 26.39882198 40.7896187
OS 26.40452682 40.78391386
OS 26.40706174 40.7826464
OS 26.41023166 40.77947648
OS 26.41149912 40.77694156
OS 26.4159365 40.77250418
OS 26.41847142 40.77123672
OS 26.4229088 40.76679934
OS 26.42417626 40.76426442
OS 26.42734618 40.7610945
OS 26.4298811 40.75982704
OS 26.43241602 40.75729212
OS 26.43495094 40.75602466
OS 26.44002332 40.75095228
OS 26.44636062 40.74841736
OS 26.45143046 40.7471499
OS 26.45396538 40.74461498
OS 26.4565003 40.74335006
OS 26.45903522 40.74081514
OS 26.46157014 40.73954768
OS 26.4780522 40.72306562
OS 26.48058712 40.72179816
OS 26.48692442 40.71546086
OS 26.48945934 40.7141934
OS 26.49579918 40.71165848
OS 26.50086902 40.71038848
OS 26.50340648 40.70785356
OS 26.5059414 40.7065861
OS 26.5110087 40.70151626
OS 26.51354362 40.7002488
OS 26.52305338 40.69073904
OS 26.52368584 40.68883912
OS 26.52622076 40.68757166
OS 26.53319306 40.68186936
OS 26.53763044 40.67743198
OS 26.54460274 40.67552952
OS 26.55094258 40.6729946
OS 26.55410996 40.66982468
OS 26.55664488 40.66855722
OS 26.56171726 40.66348738
OS 26.56425218 40.66221992
OS 26.56932202 40.65714754
OS 26.57185694 40.65588008
OS 26.57439186 40.65334516
OS 26.58072916 40.65081024
OS 26.58896892 40.64764032
OS 26.5934063 40.64320294
OS 26.59594122 40.64193548
OS 26.61242328 40.62545596
OS 26.6149582 40.62419104
OS 26.6212955 40.6178512
OS 26.63016772 40.61404882
OS 26.63523756 40.61278136
OS 26.64411232 40.60644406
OS 26.65045216 40.6039066
OS 26.65869192 40.60073922
OS 26.66629668 40.59439938
OS 26.66819914 40.59249946
OS 26.67073406 40.591232
OS 26.67770636 40.58552716
OS 26.68087628 40.58235724
OS 26.6834112 40.58108978
OS 26.69228342 40.5772874
OS 26.70622802 40.5696801
OS 26.7176377 40.5646128
OS 26.72904484 40.55827296
OS 26.7379196 40.55447058
OS 26.74932674 40.54813074
OS 26.75439658 40.5430609
OS 26.7569315 40.54179344
OS 26.7639038 40.5360886
OS 26.76834118 40.53165122
OS 26.77658094 40.5284813
OS 26.78292078 40.52594638
OS 26.792428 40.52024154
OS 26.79876784 40.51770662
OS 26.90397972 40.46573314
OS 26.9229967 40.45686092
OS 26.93440384 40.45559092
OS 26.96102558 40.44291632
OS 26.98004002 40.4340441
OS 26.98510986 40.43277664
OS 26.99841946 40.42960672
OS 27.02694366 40.41629712
OS 27.04342318 40.40868982
OS 27.05419532 40.40678736
OS 27.05926516 40.4055199
OS 27.06624 40.40234998
OS 27.06877492 40.40108252
OS 27.07764714 40.39728014
OS 27.09539666 40.39347776
OS 27.10933872 40.38713792
OS 27.12201586 40.38333808
OS 27.12962062 40.38207062
OS 27.13596046 40.3795357
OS 27.14990506 40.37319586
OS 27.1549749 40.3719284
OS 27.16384966 40.37066094
OS 27.17018442 40.36812602
OS 27.18412902 40.36178618
OS 27.19427124 40.35925126
OS 27.20377846 40.35735134
OS 27.22089298 40.35037904
OS 27.23103266 40.34784158
OS 27.24560972 40.34594166
OS 27.25575194 40.34340674
OS 27.26209178 40.34086928
OS 27.27286646 40.3377019
OS 27.2906109 40.33516444
OS 27.30265558 40.33326452
OS 27.31279526 40.33199706
OS 27.31786764 40.3307296
OS 27.3261074 40.32755968
OS 27.33434716 40.32565722
OS 27.34068446 40.3243923
OS 27.34829176 40.32312484
OS 27.35843144 40.32185738
OS 27.37491096 40.31932246
OS 27.3799808 40.318055
OS 27.38822056 40.31488508
OS 27.39646286 40.31298262
OS 27.40280016 40.31171516
OS 27.41674222 40.3104477
OS 27.43068682 40.30791278
OS 27.4357592 40.30664532
OS 27.4420965 40.30537786
OS 27.4490688 40.3034754
OS 27.45921102 40.30094048
OS 27.47188562 40.29967302
OS 27.49406998 40.29777056
OS 27.50547966 40.2965031
OS 27.52195918 40.29396818
OS 27.53463378 40.29143326
OS 27.54604346 40.2901658
OS 27.57393266 40.28889834
OS 27.59040964 40.28762834
OS 27.6601301 40.28636088
OS 27.87246394 40.28572842
OS 27.87626632 40.28699588
OS 27.95992884 40.28826334
OS 27.96373122 40.2895308
OS 27.99922772 40.29079826
OS 28.0030301 40.29206572
OS 28.01126732 40.29396818
OS 28.0372566 40.2971381
OS 28.04613136 40.29840556
OS 28.06261088 40.29967302
OS 28.0778204 40.30094048
OS 28.08162278 40.30220794
OS 28.08669516 40.3034754
OS 28.09556738 40.30601032
OS 28.10253968 40.30791278
OS 28.10887952 40.30918024
OS 28.1259915 40.3110827
OS 28.13803364 40.31298262
OS 28.14310348 40.31425008
OS 28.15007578 40.31615254
OS 28.15641562 40.31868746
OS 28.16528784 40.31995492
OS 28.17036022 40.32122238
OS 28.18620474 40.32312484
OS 28.1938095 40.3243923
OS 28.20014934 40.32565722
OS 28.21028902 40.32819214
OS 28.22106624 40.33136206
OS 28.22613608 40.33262952
OS 28.24388306 40.33516444
OS 28.25846012 40.3370669
OS 28.26479742 40.33833436
OS 28.27113726 40.34086928
OS 28.28571432 40.34530666
OS 28.2907867 40.34657412
OS 28.30663122 40.34847658
OS 28.31170106 40.34974404
OS 28.32184328 40.35354642
OS 28.33261796 40.3579838
OS 28.35036494 40.36178618
OS 28.36430954 40.36812602
OS 28.37064684 40.37066094
OS 28.37951906 40.3719284
OS 28.38459144 40.37319586
OS 28.39853604 40.3795357
OS 28.40487334 40.38207062
OS 28.41945294 40.385238
OS 28.42959262 40.38904038
OS 28.43656492 40.3922103
OS 28.44290222 40.39474522
OS 28.4536769 40.39664768
OS 28.45874928 40.39791514
OS 28.47142642 40.40425244
OS 28.47649626 40.4055199
OS 28.48346856 40.40742236
OS 28.49677816 40.41059228
OS 28.50628538 40.41629712
OS 28.51452514 40.4194645
OS 28.52149744 40.42263442
OS 28.54051188 40.43150918
OS 28.55318648 40.43277664
OS 28.56459616 40.43911394
OS 28.57600584 40.44418632
OS 28.58234314 40.4467187
OS 28.60136012 40.45559092
OS 28.61023234 40.45686092
OS 28.61720464 40.45876084
OS 28.63051424 40.46573314
OS 28.63685408 40.46826806
OS 28.70150216 40.50122964
OS 28.71037692 40.50502948
OS 28.72685644 40.51390424
OS 28.73572866 40.51770662
OS 28.74967326 40.52531392
OS 28.75854802 40.5291163
OS 28.76995516 40.5354536
OS 28.776295 40.54179344
OS 28.7826323 40.54559582
OS 28.78770468 40.55066566
OS 28.79657436 40.55447058
OS 28.8029142 40.5570055
OS 28.81051896 40.56207534
OS 28.81939372 40.56587772
OS 28.82573356 40.56841264
OS 28.83270586 40.57411748
OS 28.83460578 40.5760174
OS 28.8371407 40.5772874
OS 28.83967816 40.57982232
OS 28.84221308 40.58108978
OS 28.84854784 40.58742708
OS 28.86122498 40.59249946
OS 28.8637599 40.59376692
OS 28.87390212 40.60010422
OS 28.8859468 40.6045416
OS 28.89608648 40.6108789
OS 28.90305878 40.61404882
OS 28.91129854 40.61721874
OS 28.91319846 40.6191212
OS 28.91573338 40.62038866
OS 28.92207322 40.62672342
OS 28.92460814 40.62799088
OS 28.94108766 40.64447294
OS 28.94362258 40.6457404
OS 28.94616004 40.64827532
OS 28.95249734 40.65081024
OS 28.9607371 40.65398016
OS 28.9677094 40.66095246
OS 28.97024178 40.66221992
OS 28.98165146 40.67109214
OS 28.98418638 40.6736296
OS 28.99623106 40.67806444
OS 29.00066844 40.68123436
OS 29.00573828 40.6863042
OS 29.0082732 40.68757166
OS 29.02348526 40.70278372
OS 29.02602018 40.70405118
OS 29.03109002 40.70912102
OS 29.03742732 40.71165848
OS 29.04566962 40.71482586
OS 29.04756954 40.71672832
OS 29.05010446 40.71799578
OS 29.0564443 40.72433308
OS 29.05897922 40.72560308
OS 29.06721898 40.73384284
OS 29.06848644 40.73637776
OS 29.07292382 40.73954768
OS 29.07609374 40.74271506
OS 29.0773612 40.74524998
OS 29.08053112 40.74841736
OS 29.08306604 40.74968482
OS 29.08686842 40.75348974
OS 29.0894008 40.7547572
OS 29.09320572 40.75855958
OS 29.10715032 40.76362942
OS 29.11348762 40.76996926
OS 29.11602254 40.77123672
OS 29.12299484 40.77694156
OS 29.1242623 40.77947648
OS 29.12996714 40.78518132
OS 29.13250206 40.78644878
OS 29.13567198 40.7896187
OS 29.13693944 40.79215362
OS 29.14264428 40.79785846
OS 29.1451792 40.79912592
OS 29.14708166 40.80102838
OS 29.14834658 40.8035633
OS 29.15531888 40.81053306
OS 29.1578538 40.81180052
OS 29.16165872 40.8156029
OS 29.16419364 40.81687036
OS 29.16672856 40.81940782
OS 29.1787707 40.82384266
OS 29.18320808 40.82701258
OS 29.18828046 40.83208242
OS 29.19081538 40.83335242
OS 29.19778768 40.84032472
OS 29.19905514 40.84285964
OS 29.20539244 40.84919694
OS 29.2066599 40.85173186
OS 29.20919482 40.8580717
OS 29.21046228 40.86314154
OS 29.21616712 40.8701113
OS 29.22503934 40.87898606
OS 29.23137918 40.88152098
OS 29.23961894 40.8846909
OS 29.24405632 40.88786082
OS 29.24912616 40.89293066
OS 29.25166108 40.89419812
OS 29.25863338 40.90117042
OS 29.25990084 40.90370534
OS 29.26750814 40.91131264
OS 29.27004052 40.92145486
OS 29.27384544 40.92778962
OS 29.27574536 40.92969208
OS 29.28081774 40.93095954
OS 29.28779004 40.932862
OS 29.28968996 40.93476192
OS 29.29222488 40.93602938
OS 29.29729726 40.94110176
OS 29.29983218 40.94236922
OS 29.30807194 40.95060898
OS 29.3093394 40.9531439
OS 29.31567924 40.9594812
OS 29.31821416 40.96582104
OS 29.32138408 40.9740608
OS 29.32581892 40.98230056
OS 29.32455146 40.9873704
OS 29.31884662 40.98927032
OS 29.31124186 40.98800286
OS 29.30616948 40.98293556
OS 29.30363456 40.9816681
OS 29.30109964 40.97913064
OS 29.29856472 40.97786318
OS 29.2953948 40.9746958
OS 29.29412734 40.97215834
OS 29.2884225 40.9664535
OS 29.28588758 40.96518604
OS 29.28271766 40.96201866
OS 29.2814502 40.9594812
OS 29.2744779 40.9525089
OS 29.27194298 40.95124144
OS 29.27004052 40.94934152
OS 29.26877306 40.9468066
OS 29.25166108 40.92969208
OS 29.24976116 40.92905708
OS 29.2484937 40.92652216
OS 29.2402514 40.91828494
OS 29.23771648 40.91701748
OS 29.2345491 40.91384756
OS 29.2332791 40.91131264
OS 29.2263068 40.90434034
OS 29.22377188 40.90307288
OS 29.22187196 40.90117042
OS 29.2206045 40.8986355
OS 29.19208284 40.8701113
OS 29.18954792 40.86884384
OS 29.186378 40.86567646
OS 29.18511054 40.86314154
OS 29.1794057 40.8574367
OS 29.17687078 40.85616924
OS 29.17370086 40.85300186
OS 29.1724334 40.8504644
OS 29.16672856 40.84475956
OS 29.16419364 40.8434921
OS 29.16165872 40.84095718
OS 29.15912126 40.83968972
OS 29.15405142 40.83461988
OS 29.1451792 40.83208242
OS 29.1388419 40.82828004
OS 29.13250206 40.82194274
OS 29.12996714 40.82067528
OS 29.12552976 40.81750536
OS 29.1242623 40.81497044
OS 29.07355882 40.76426442
OS 29.07292382 40.76236196
OS 29.0703889 40.7610945
OS 29.06658652 40.75729212
OS 29.06404906 40.75602466
OS 29.05897922 40.75095228
OS 29.0564443 40.74968482
OS 29.05010446 40.7471499
OS 29.04503462 40.74588244
OS 29.04123224 40.7420826
OS 29.03932978 40.7414476
OS 29.03869732 40.73954768
OS 29.03615986 40.73827768
OS 29.03362494 40.73574276
OS 29.03109002 40.7344753
OS 29.02538772 40.72877046
OS 29.02412026 40.72623554
OS 29.02095034 40.72306562
OS 29.01841542 40.72179816
OS 29.01334558 40.71672832
OS 29.01080812 40.71546086
OS 29.0082732 40.71292594
OS 29.00320336 40.71165848
OS 28.9949636 40.70848856
OS 28.9879913 40.70151626
OS 28.98545638 40.7002488
OS 28.97848408 40.69454396
OS 28.97531416 40.69137404
OS 28.97277924 40.69010658
OS 28.96390702 40.6863042
OS 28.95503226 40.68123436
OS 28.94869496 40.67489706
OS 28.94616004 40.6736296
OS 28.92967798 40.65714754
OS 28.92714306 40.65588008
OS 28.92460814 40.65334516
OS 28.91827084 40.65081024
OS 28.91002854 40.64764032
OS 28.90305878 40.64066802
OS 28.90052386 40.63940056
OS 28.89355156 40.63369572
OS 28.89165164 40.6317958
OS 28.88911418 40.63052834
OS 28.88657926 40.62799088
OS 28.87453712 40.62355604
OS 28.87009974 40.62038866
OS 28.86629736 40.61658374
OS 28.8637599 40.61531628
OS 28.86122498 40.61278136
OS 28.85869006 40.6115139
OS 28.85235276 40.6051766
OS 28.8498153 40.6039066
OS 28.84094562 40.60010422
OS 28.8168588 40.58869454
OS 28.80798404 40.5836247
OS 28.7686877 40.5646128
OS 28.7623504 40.56080788
OS 28.75728056 40.55573804
OS 28.7547431 40.55447058
OS 28.75220818 40.55193566
OS 28.74967326 40.55066566
OS 28.74587088 40.54686328
OS 28.74333342 40.54559582
OS 28.7407985 40.5430609
OS 28.73255874 40.53989098
OS 28.72622398 40.53735606
OS 28.71798422 40.53165122
OS 28.71164438 40.5291163
OS 28.70340462 40.52594638
OS 28.69579732 40.52087654
OS 28.68882502 40.51770662
OS 28.68058526 40.5145367
OS 28.67044558 40.5081994
OS 28.66347328 40.50502948
OS 28.65713598 40.5024971
OS 28.6457263 40.49615726
OS 28.63431662 40.49108742
OS 28.61276726 40.4809452
OS 28.60072512 40.47904528
OS 28.59438782 40.47650782
OS 28.56142624 40.4600283
OS 28.54558426 40.453056
OS 28.52656728 40.44418632
OS 28.5151576 40.44291632
OS 28.49867808 40.43531156
OS 28.49234078 40.43277664
OS 28.48346856 40.43150918
OS 28.4676215 40.42580434
OS 28.4543119 40.4200995
OS 28.44543714 40.41883204
OS 28.4403673 40.41756458
OS 28.42262286 40.40995728
OS 28.41628302 40.40742236
OS 28.40424088 40.4055199
OS 28.39790104 40.40298498
OS 28.38205652 40.39601268
OS 28.36240962 40.3915753
OS 28.35670478 40.38840538
OS 28.35036494 40.38587046
OS 28.34149272 40.38333808
OS 28.33642034 40.38207062
OS 28.32944804 40.38016816
OS 28.32311074 40.37763324
OS 28.31613844 40.37573078
OS 28.31550344 40.37509832
OS 28.30853114 40.37319586
OS 28.30346384 40.3719284
OS 28.28698178 40.37066094
OS 28.28191194 40.36939348
OS 28.2698698 40.36749102
OS 28.26479742 40.36622356
OS 28.25846012 40.36368864
OS 28.24768544 40.36051872
OS 28.2426156 40.35925126
OS 28.23374084 40.3579838
OS 28.2216987 40.35608388
OS 28.2077541 40.3510115
OS 28.2007818 40.34911158
OS 28.19063958 40.34657412
OS 28.17226014 40.34340674
OS 28.1671903 40.34213674
OS 28.160853 40.33960182
OS 28.15578062 40.33833436
OS 28.14817586 40.3370669
OS 28.13803364 40.33579944
OS 28.13042634 40.33453198
OS 28.1190192 40.33326452
OS 28.09366746 40.32946214
OS 28.08669516 40.32755968
OS 28.0778204 40.32629222
OS 28.07275056 40.32502476
OS 28.04993374 40.32375984
OS 28.04613136 40.32248984
OS 28.0036651 40.32058992
OS 27.99098796 40.31932246
OS 27.97957828 40.318055
OS 27.97197098 40.31678754
OS 27.96563368 40.31551754
OS 27.95549146 40.31425008
OS 27.94028194 40.31298262
OS 27.92000004 40.31171516
OS 27.87563132 40.3104477
OS 27.86485664 40.30981524
OS 27.86105426 40.3110827
OS 27.82936014 40.30981524
OS 27.66646994 40.3104477
OS 27.66203256 40.30981524
OS 27.65823018 40.3110827
OS 27.65442526 40.30981524
OS 27.6341459 40.3110827
OS 27.5986494 40.31235016
OS 27.59484702 40.31361762
OS 27.56949528 40.31488508
OS 27.5656929 40.31615254
OS 27.55681814 40.31742
OS 27.5517483 40.31868746
OS 27.53146386 40.31995492
OS 27.5105495 40.32185738
OS 27.48519522 40.32312484
OS 27.475053 40.3243923
OS 27.45857602 40.32565722
OS 27.44463142 40.32819214
OS 27.43765912 40.3300946
OS 27.40723754 40.33389698
OS 27.3806158 40.3377019
OS 27.37554596 40.33896936
OS 27.3666712 40.34150428
OS 27.35652898 40.3440392
OS 27.34448938 40.34594166
OS 27.32737486 40.34784158
OS 27.31406272 40.3510115
OS 27.30709042 40.35418142
OS 27.29441582 40.3579838
OS 27.28617606 40.35988626
OS 27.28110622 40.36115372
OS 27.27413392 40.36432364
OS 27.26779408 40.36685856
OS 27.25258202 40.36939348
OS 27.23990488 40.37066094
OS 27.23103266 40.3719284
OS 27.22279544 40.37383086
OS 27.20885084 40.3789007
OS 27.19807362 40.38207062
OS 27.18983386 40.38397308
OS 27.18476402 40.385238
OS 27.17779172 40.38840538
OS 27.16638458 40.39347776
OS 27.15434244 40.39537768
OS 27.14420022 40.3991826
OS 27.13088808 40.40488744
OS 27.12581824 40.4061549
OS 27.1125061 40.40932228
OS 27.09856404 40.41566212
OS 27.08778936 40.41883204
OS 27.07828214 40.42073196
OS 27.0719423 40.42326942
OS 27.0586327 40.42897172
OS 27.04849302 40.43150918
OS 27.04088826 40.43277664
OS 27.01172906 40.4467187
OS 26.99524954 40.45432346
OS 26.98637732 40.45559092
OS 26.98130748 40.45686092
OS 26.95722066 40.46826806
OS 26.95088336 40.47080552
OS 26.93440384 40.47841028
OS 26.92933146 40.47967774
OS 26.91982678 40.4815802
OS 26.91348948 40.48411512
OS 26.90397972 40.48981996
OS 26.89573996 40.49298988
OS 26.88940266 40.4955248
OS 26.88179536 40.50059464
OS 26.87545806 40.50312956
OS 26.861516 40.50946686
OS 26.85961354 40.51136932
OS 26.85707862 40.51263678
OS 26.84566894 40.51770662
OS 26.83425926 40.52404646
OS 26.82284958 40.5291163
OS 26.80890498 40.53672106
OS 26.79749784 40.54179344
OS 26.79116054 40.54559582
OS 26.78418824 40.55130066
OS 26.7784834 40.55573804
OS 26.77594848 40.5570055
OS 26.76960864 40.5633428
OS 26.76263634 40.56524272
OS 26.75503158 40.5690451
OS 26.7455269 40.57474994
OS 26.73918706 40.5772874
OS 26.7100304 40.591232
OS 26.70749548 40.59249946
OS 26.70496056 40.59503438
OS 26.7024231 40.59630184
OS 26.69735326 40.60137168
OS 26.69481834 40.60263914
OS 26.68784858 40.60834398
OS 26.68467866 40.6115139
OS 26.67834136 40.61404882
OS 26.67326898 40.61531628
OS 26.66629668 40.62102112
OS 26.66312676 40.62419104
OS 26.66059184 40.62545596
OS 26.65361954 40.6311608
OS 26.65045216 40.63433072
OS 26.6479147 40.63559818
OS 26.63523756 40.64066802
OS 26.63270264 40.64193548
OS 26.62383042 40.64827532
OS 26.61876058 40.64954278
OS 26.6073509 40.65588008
OS 26.6003786 40.66158492
OS 26.59594122 40.66475484
OS 26.59087138 40.66982468
OS 26.58833646 40.67109214
OS 26.57692678 40.67616452
OS 26.57439186 40.67743198
OS 26.5674221 40.68313682
OS 26.56298472 40.6863042
OS 26.54777266 40.70151626
OS 26.54523774 40.70278372
OS 26.5388979 40.70912102
OS 26.53002568 40.71165848
OS 26.52115092 40.71672832
OS 26.51608108 40.72179816
OS 26.51354362 40.72306562
OS 26.50657386 40.73003792
OS 26.5053064 40.73257538
OS 26.50340648 40.7344753
OS 26.50086902 40.73574276
OS 26.4983341 40.73827768
OS 26.49579918 40.73954768
OS 26.48945934 40.74588244
OS 26.48058712 40.74841736
OS 26.47424728 40.75222228
OS 26.4704449 40.75602466
OS 26.46790998 40.75729212
OS 26.46537506 40.75982704
OS 26.46284014 40.7610945
OS 26.46093768 40.76299696
OS 26.45967022 40.76553188
OS 26.43875586 40.78644878
OS 26.4368534 40.78708378
OS 26.43558594 40.7896187
OS 26.40325936 40.82194274
OS 26.40072444 40.8232102
OS 26.3943846 40.8295475
OS 26.39184968 40.83081496
OS 26.38804984 40.83208242
OS 26.37981008 40.83525234
OS 26.37220278 40.84159218
OS 26.3677654 40.84475956
OS 26.23656424 40.97596326
OS 26.23529678 40.97849818
OS 26.23022694 40.98356802
OS 26.22769202 40.98990532
OS 26.22578956 40.99687762
OS 26.2238871 40.99877754
OS 26.22261964 41.001315
OS 26.21628234 41.0076523
OS 26.21501488 41.01018722
OS 26.18269084 41.0425138
OS 26.18078838 41.0431488
OS 26.17952092 41.04568118
OS 26.1624064 41.0627957
OS 26.15987148 41.06406316
OS 26.15416664 41.069768
OS 26.15289918 41.07230292
OS 26.15036426 41.07483784
OS 26.1490968 41.07737276
OS 26.14529442 41.08117768
OS 26.14402696 41.0837126
OS 26.14149204 41.0900499
OS 26.14022458 41.09512228
OS 26.13261728 41.10272704
OS 26.13134982 41.10525942
OS 26.12564498 41.11223172
OS 26.12311006 41.11349918
OS 26.11613776 41.12047402
OS 26.1148703 41.12300894
OS 26.10980046 41.12807878
OS 26.108533 41.1306137
OS 26.10599554 41.13695354
OS 26.10282816 41.1451933
OS 26.09585586 41.1521656
OS 26.0945884 41.15470052
OS 26.07810888 41.1711775
OS 26.07684142 41.17371242
OS 26.07303904 41.17751734
OS 26.07177158 41.18005226
OS 26.06923666 41.18638956
OS 26.06416428 41.19526432
OS 26.0603619 41.1990667
OS 26.05909444 41.20160416
OS 26.05655952 41.20413908
OS 26.05529206 41.206674
OS 26.04895222 41.2130113
OS 26.04768476 41.21554876
OS 26.04514984 41.22188606
OS 26.04197992 41.23012328
OS 26.03881 41.23456066
OS 26.03374016 41.24216796
OS 26.0318377 41.24914026
OS 26.02993778 41.2535751
OS 26.02423548 41.2605474
OS 26.02106556 41.26371732
OS 26.0197981 41.26625224
OS 26.01726318 41.2687897
OS 26.01599572 41.27132462
OS 26.01092334 41.27639446
OS 26.00838842 41.2827343
OS 26.00712096 41.2878016
OS 26.00141612 41.2947739
OS 25.9982462 41.29794382
OS 25.99697874 41.30047874
OS 25.9912739 41.30745104
OS 25.98937398 41.3093535
OS 25.98810652 41.31188842
OS 25.98556906 41.31442334
OS 25.9843016 41.31949318
OS 25.96275478 41.36132444
OS 25.95894986 41.3701992
OS 25.95388002 41.37907396
OS 25.94881018 41.3841438
OS 25.94754272 41.38667872
OS 25.94183788 41.39365102
OS 25.93993542 41.39555348
OS 25.93866796 41.3980884
OS 25.93359812 41.40949554
OS 25.92852574 41.4183703
OS 25.92218844 41.4323149
OS 25.9158486 41.44372458
OS 25.9095113 41.45766918
OS 25.90444146 41.46653886
OS 25.8968367 41.48302092
OS 25.89556924 41.48555584
OS 25.8892294 41.49569552
OS 25.88669448 41.50203536
OS 25.88352456 41.51027512
OS 25.87655226 41.52358472
OS 25.8752848 41.52865456
OS 25.87211742 41.54323416
OS 25.86514512 41.55654376
OS 25.86260766 41.56288106
OS 25.85119798 41.58696534
OS 25.84993052 41.5958401
OS 25.8486656 41.60090994
OS 25.84549568 41.6091497
OS 25.84359576 41.61105216
OS 25.83979338 41.61992692
OS 25.83725592 41.62626422
OS 25.82711624 41.64781358
OS 25.82584878 41.65288342
OS 25.82394632 41.66239064
OS 25.8214114 41.66873048
OS 25.8144391 41.685845
OS 25.81317164 41.69471722
OS 25.80873426 41.70675936
OS 25.80556434 41.71373166
OS 25.80302942 41.72006896
OS 25.80176196 41.72514134
OS 25.79859204 41.73845094
OS 25.79605712 41.74478824
OS 25.7928872 41.75176308
OS 25.79035228 41.75810038
OS 25.78908482 41.76317022
OS 25.7878199 41.77204244
OS 25.78148006 41.78598704
OS 25.77894514 41.79232688
OS 25.77767768 41.79739672
OS 25.77450776 41.81070632
OS 25.77197284 41.81704616
OS 25.77007038 41.822751
OS 25.76753546 41.83162322
OS 25.766268 41.83669306
OS 25.76500054 41.85317258
OS 25.76373308 41.85824242
OS 25.76183062 41.8702871
OS 25.76056316 41.87535694
OS 25.75802824 41.88169678
OS 25.75359086 41.8962713
OS 25.7523234 41.90894844
OS 25.75105594 41.91402082
OS 25.74978848 41.92162558
OS 25.7459861 41.93050034
OS 25.74218118 41.94570986
OS 25.74091372 41.95458462
OS 25.73964626 41.97106414
OS 25.7383788 41.97613398
OS 25.73647634 41.98310628
OS 25.73330896 41.9938835
OS 25.72950404 42.00909302
OS 25.7263392 42.03507976
OS 25.72126682 42.0553642
OS 25.7193669 42.07247364
OS 25.71746444 42.09212308
OS 25.71619698 42.1162099
OS 25.71492952 42.12761704
OS 25.71366206 42.1504364
OS 25.7123946 42.16057608
OS 25.7111246 42.16818338
OS 25.70985714 42.17325322
OS 25.70858968 42.18339544
OS 25.70732222 42.2049448
OS 25.70605476 42.22142432
OS 25.7047873 42.24424368
OS 25.70351984 42.28480748
OS 25.70161738 42.28924486
OS 25.69971746 42.29114478
OS 25.69464508 42.29241224
OE
SE
S P 0
OB 32.91135658 44.95700432 I
OS 32.98107704 44.95573686
OS 32.98488196 44.9544694
OS 33.00516132 44.95320194
OS 33.01403608 44.94939702
OS 33.0229083 44.9468621
OS 33.04129028 44.94496218
OS 33.04636266 44.94369218
OS 33.05269742 44.9411598
OS 33.06600956 44.93545496
OS 33.07488178 44.9341875
OS 33.07995416 44.93292004
OS 33.08819392 44.92975012
OS 33.09009384 44.9278502
OS 33.10150352 44.92277782
OS 33.10974074 44.91961044
OS 33.11671304 44.91517306
OS 33.13065764 44.90883322
OS 33.13699748 44.90503084
OS 33.14206732 44.899961
OS 33.14460224 44.89869354
OS 33.154112 44.89172124
OS 33.15474446 44.88981878
OS 33.15727938 44.88855132
OS 33.16995398 44.88348148
OS 33.17249144 44.88221402
OS 33.1800962 44.87460926
OS 33.18263112 44.8733418
OS 33.1870685 44.87017188
OS 33.18833596 44.86763696
OS 33.19087088 44.86510204
OS 33.19150588 44.86319958
OS 33.1940408 44.86193212
OS 33.20925286 44.84672006
OS 33.21115532 44.84608506
OS 33.21242278 44.84355014
OS 33.2149577 44.84101522
OS 33.2155927 44.83911276
OS 33.21812762 44.8378453
OS 33.22066254 44.83531038
OS 33.22319746 44.83404292
OS 33.2282673 44.82643562
OS 33.2352396 44.81946586
OS 33.24030944 44.80552126
OS 33.24601428 44.79854896
OS 33.2491842 44.79537904
OS 33.25045166 44.79284412
OS 33.2561565 44.78587182
OS 33.25932642 44.7827019
OS 33.26376126 44.77065976
OS 33.26693118 44.76622238
OS 33.27200102 44.76115508
OS 33.27327102 44.75862016
OS 33.27960832 44.7497454
OS 33.2834107 44.74594302
OS 33.28594562 44.7358008
OS 33.28721308 44.72565858
OS 33.2960853 44.70664414
OS 33.29862022 44.69650446
OS 33.29989022 44.6876297
OS 33.30622752 44.6736851
OS 33.30812998 44.65910804
OS 33.30939744 44.65150074
OS 33.3106649 44.62995138
OS 33.31193236 44.61727678
OS 33.31319982 44.6058671
OS 33.31446728 44.60079472
OS 33.31826966 44.59065504
OS 33.32143958 44.58241528
OS 33.32270704 44.57734544
OS 33.32143958 44.56593576
OS 33.31510228 44.55199116
OS 33.31383482 44.54692132
OS 33.31256482 44.53804656
OS 33.31129736 44.53297672
OS 33.3100299 44.51269482
OS 33.30812998 44.49938522
OS 33.30559252 44.48670808
OS 33.29989022 44.47339594
OS 33.29862022 44.46452372
OS 33.2960853 44.45438404
OS 33.289748 44.44424182
OS 33.28721308 44.43790452
OS 33.2840457 44.42966476
OS 33.28151078 44.42332492
OS 33.27960832 44.42142246
OS 33.27834086 44.41888754
OS 33.27453848 44.41001532
OS 33.27263602 44.39670572
OS 33.2701011 44.39036842
OS 33.2631288 44.38339612
OS 33.25805642 44.37452136
OS 33.25171912 44.36818406
OS 33.24664928 44.35423692
OS 33.23904198 44.34663216
OS 33.23777452 44.34409724
OS 33.23333714 44.33839494
OS 33.23080222 44.33712748
OS 33.17439136 44.28071662
OS 33.1737589 44.27881416
OS 33.17122144 44.2775467
OS 33.16868652 44.27501178
OS 33.16615414 44.27374432
OS 33.15981684 44.26740448
OS 33.153477 44.26486956
OS 33.14523724 44.26170218
OS 33.13762994 44.2566298
OS 33.13065764 44.25345988
OS 33.12241788 44.2502925
OS 33.11544558 44.24585512
OS 33.10150352 44.23951528
OS 33.09009384 44.23317798
OS 33.0786867 44.22810814
OS 33.05459988 44.216701
OS 33.04255774 44.21479854
OS 33.03241806 44.21099616
OS 33.02671322 44.2090937
OS 33.01783846 44.20782624
OS 32.96966736 44.20529132
OS 32.86952278 44.20402386
OS 32.75797106 44.20402386
OS 32.47908922 44.20529132
OS 32.47528684 44.20655878
OS 32.44106034 44.20782624
OS 32.43725796 44.2090937
OS 32.4290182 44.21226362
OS 32.41824098 44.21543354
OS 32.40873376 44.21733346
OS 32.39859154 44.22113838
OS 32.39035178 44.22557068
OS 32.3802121 44.22810814
OS 32.37007242 44.2293756
OS 32.36119766 44.23444544
OS 32.34725306 44.24078528
OS 32.34091576 44.2433202
OS 32.332041 44.2496575
OS 32.31809894 44.25472988
OS 32.3123941 44.25916472
OS 32.31112664 44.26170218
OS 32.30035196 44.26867448
OS 32.29401212 44.27501178
OS 32.28894228 44.27627924
OS 32.28070252 44.27944916
OS 32.27246022 44.28768638
OS 32.26612546 44.29148876
OS 32.264223 44.29339122
OS 32.26295554 44.29592614
OS 32.2572507 44.30163098
OS 32.25471578 44.30289844
OS 32.25154586 44.30606836
OS 32.2502784 44.30860328
OS 32.24457356 44.31430812
OS 32.24203864 44.31557558
OS 32.24013872 44.31747804
OS 32.23886872 44.32001296
OS 32.23316642 44.3257178
OS 32.23062896 44.32698526
OS 32.22746158 44.33015518
OS 32.22365666 44.33649248
OS 32.21731936 44.34283232
OS 32.21478444 44.34916708
OS 32.21351698 44.35423692
OS 32.20464476 44.36818406
OS 32.2033773 44.3732539
OS 32.19703746 44.38466358
OS 32.19196762 44.38973342
OS 32.19070016 44.39226834
OS 32.18499532 44.39924064
OS 32.18055794 44.40367802
OS 32.1748531 44.41952254
OS 32.16978326 44.4271273
OS 32.16661334 44.43790452
OS 32.16471088 44.4486792
OS 32.16217596 44.4550165
OS 32.15900858 44.4619888
OS 32.15647112 44.4683261
OS 32.15520366 44.47339594
OS 32.1539362 44.48607308
OS 32.15266874 44.4962153
OS 32.1475989 44.50889244
OS 32.14633398 44.51396228
OS 32.14443152 44.53487664
OS 32.14316406 44.55516108
OS 32.14252906 44.60649956
OS 32.14379652 44.61030448
OS 32.14506398 44.6407286
OS 32.14633398 44.64452844
OS 32.1475989 44.6534032
OS 32.15013382 44.6597405
OS 32.15266874 44.66861526
OS 32.15710612 44.69586946
OS 32.15964104 44.7022093
OS 32.16534588 44.71551636
OS 32.16661334 44.72439112
OS 32.1685158 44.73263088
OS 32.17041572 44.73453334
OS 32.17168318 44.73706826
OS 32.17675556 44.7421381
OS 32.17802302 44.74467556
OS 32.18372786 44.75164786
OS 32.18562778 44.75354778
OS 32.18689778 44.7560827
OS 32.19196762 44.76748984
OS 32.19703746 44.7763646
OS 32.2033773 44.7903092
OS 32.20781214 44.79854896
OS 32.21034706 44.79981642
OS 32.21224952 44.80171888
OS 32.21351698 44.8042538
OS 32.21922182 44.8112261
OS 32.22619412 44.81693094
OS 32.23189642 44.8239007
OS 32.23886872 44.82960554
OS 32.24457356 44.83657784
OS 32.24711102 44.8378453
OS 32.25154586 44.84228268
OS 32.25281332 44.8448176
OS 32.2572507 44.84925498
OS 32.25978562 44.85052244
OS 32.264223 44.85495982
OS 32.26549046 44.85749474
OS 32.26865784 44.86066466
OS 32.27119276 44.86193212
OS 32.27563014 44.8663695
OS 32.2768976 44.86890442
OS 32.28133498 44.8733418
OS 32.2838699 44.87460926
OS 32.28830728 44.87904664
OS 32.28957474 44.88158156
OS 32.29274466 44.88474894
OS 32.29527958 44.8860164
OS 32.2978145 44.88855132
OS 32.30035196 44.88981878
OS 32.30161942 44.8923537
OS 32.30415434 44.89362116
OS 32.30668926 44.89615608
OS 32.31366156 44.89805854
OS 32.32126886 44.90186092
OS 32.32887108 44.9069333
OS 32.3390133 44.91073568
OS 32.3453506 44.9132706
OS 32.34852052 44.91644052
OS 32.35105544 44.91770798
OS 32.3599302 44.92151036
OS 32.3662675 44.92404528
OS 32.36880496 44.92531528
OS 32.37767718 44.93165258
OS 32.38971932 44.93608996
OS 32.39605662 44.93862488
OS 32.40429638 44.94306226
OS 32.40936876 44.94432718
OS 32.42711574 44.9468621
OS 32.44042534 44.95003202
OS 32.44676518 44.95256694
OS 32.45309994 44.9538344
OS 32.47084946 44.95510186
OS 32.49239882 44.95636932
OS 32.5443723 44.95763678
OS 32.9075542 44.95827178
OS 32.91135658 44.95700432
OE
SE
S P 0
OB 33.63590682 41.42965806 I
OS 33.65102744 41.42410054
OS 33.66916558 41.39695302
OS 33.66954404 41.39637136
OS 33.67340738 41.38701908
OS 33.67847722 41.37941432
OS 33.68453766 41.37334118
OS 33.69019424 41.36465184
OS 33.69121786 41.3639508
OS 33.69128644 41.3638492
OS 33.69409568 41.35891906
OS 33.703387 41.351708
OS 33.70648834 41.34706742
OS 33.75719436 41.2963614
OS 33.75909682 41.29508886
OS 33.76036428 41.29319402
OS 33.76860404 41.28495172
OS 33.77242928 41.28239648
OS 33.77872086 41.27610236
OS 33.78166726 41.27413386
OS 33.78373228 41.27125858
OS 33.81463646 41.25209682
OS 33.81524098 41.25169042
OS 33.82160114 41.2467552
OS 33.82413606 41.24548774
OS 33.82478884 41.24530994
OS 33.82618838 41.24437268
OS 33.82693768 41.24362592
OS 33.83454244 41.23855862
OS 33.83544668 41.23818524
OS 33.84487008 41.23188604
OS 33.84811874 41.23123834
OS 33.84868262 41.23083448
OS 33.84958432 41.23042554
OS 33.85135216 41.22932826
OS 33.85338924 41.22856372
OS 33.85845654 41.22441844
OS 33.86587588 41.2204662
OS 33.86742274 41.21912254
OS 33.87175598 41.21664604
OS 33.8796503 41.20923178
OS 33.89902034 41.20190896
OS 33.90250268 41.19957978
OS 33.90664034 41.19875428
OS 33.92867992 41.18701694
OS 33.93764104 41.18614826
OS 33.9377782 41.1860873
OS 33.94258388 41.1850205
OS 33.9467444 41.18239414
OS 33.95498416 41.17922676
OS 33.96731332 41.17710078
OS 33.97862394 41.17175408
OS 33.98369632 41.17048408
OS 33.98410272 41.17046376
OS 33.98599248 41.16973732
OS 33.9983826 41.16759864
OS 34.00975418 41.16222654
OS 34.01482402 41.16095908
OS 34.02544122 41.16044346
OS 34.03546406 41.15691794
OS 34.04877366 41.15501802
OS 34.0519893 41.15519328
OS 34.05506016 41.15422046
OS 34.06580944 41.15302412
OS 34.07620058 41.14870358
OS 34.08254042 41.14743358
OS 34.09011216 41.14742342
OS 34.09730036 41.14503582
OS 34.10744004 41.14376836
OS 34.10888276 41.1438725
OS 34.11026198 41.14343562
OS 34.12737142 41.14153824
OS 34.14984534 41.14347372
OS 34.17231672 41.14153824
OS 34.1894287 41.14343562
OS 34.19080792 41.1438725
OS 34.19224556 41.14376836
OS 34.20238778 41.14503582
OS 34.2095836 41.14742596
OS 34.21717058 41.14743612
OS 34.22350788 41.14870612
OS 34.23317004 41.1527244
OS 34.24087894 41.1539436
OS 34.24414538 41.15441096
OS 34.25253246 41.15524916
OS 34.26679456 41.15960018
OS 34.28167896 41.16032154
OS 34.28674626 41.161589
OS 34.3701878 41.07650154
OS 34.37600948 41.06231056
OS 34.37772652 41.05754298
OS 34.22878346 40.6979628
OS 34.15000282 40.30190822
OS 34.15000282 39.89809394
OS 34.22878346 39.50203936
OS 34.38331706 39.12896162
OS 34.60766256 38.7932041
OS 34.73961556 38.6612511
OS 34.69101266 38.54391834
OS 24.4984143 38.54391834
OS 24.47837624 38.55555154
OS 24.44327344 38.5962398
OS 24.40533346 38.67092088
OS 24.40766264 38.6806567
OS 24.4089301 38.71361574
OS 24.4084221 38.71680344
OS 24.408257 38.72020196
OS 24.40893518 38.72494668
OS 24.4086126 38.7308725
OS 24.40897328 38.73428118
OS 24.41173426 38.74435228
OS 24.41057602 38.75355978
OS 24.41049474 38.75445132
OS 24.41087574 38.75609216
OS 24.4115082 38.77573906
OS 24.4104541 38.78209922
OS 24.4115209 38.78846192
OS 24.41093162 38.8079742
OS 24.41161488 38.81140828
OS 24.41161742 38.82052434
OS 24.4117368 38.8214743
OS 24.41161742 38.82191118
OS 24.41168092 39.09385374
OS 24.4193949 39.12344474
OS 24.4345333 39.15231438
OS 24.44182564 39.16166666
OS 24.49878006 39.20444788
OS 24.53871394 39.21788194
OS 25.06819726 39.21727488
OS 25.07174564 39.21797592
OS 25.07307406 39.21787432
OS 25.07367604 39.21794544
OS 25.07425516 39.21778796
OS 25.08372174 39.21898176
OS 25.08498158 39.21868204
OS 25.1020961 39.21804958
OS 25.10861374 39.2190986
OS 25.1151263 39.21798354
OS 25.1212223 39.21814864
OS 25.12258882 39.21777526
OS 25.12668838 39.21829596
OS 25.13857558 39.218616
OS 25.14080316 39.21912146
OS 25.15137718 39.2177905
OS 25.1589159 39.21985552
OS 25.15923594 39.21983266
OS 25.175464 39.2177905
OS 25.17943402 39.21887762
OS 25.18353612 39.2185271
OS 25.18923842 39.2191621
OS 25.19162348 39.21991902
OS 25.21730034 39.22142778
OS 25.23900972 39.22708944
OS 25.2613541 39.22892332
OS 25.27022632 39.23145824
OS 25.28067588 39.2368278
OS 25.29219732 39.23911634
OS 25.31045992 39.25131342
OS 25.31566946 39.25290092
OS 25.3218315 39.2579733
OS 25.34099834 39.26782088
OS 25.34859802 39.27677946
OS 25.35836432 39.28330218
OS 25.36343416 39.28837202
OS 25.36915424 39.29692674
OS 25.37709936 39.30346724
OS 25.38280674 39.31044208
OS 25.39235714 39.32837194
OS 25.39246382 39.32849894
OS 25.39252478 39.3286869
OS 25.39386844 39.33121166
OS 25.40814832 39.34993908
OS 25.41240028 39.36600712
OS 25.42020824 39.38066546
OS 25.42248154 39.40408934
OS 25.42850642 39.42685536
OS 25.42977388 39.4471398
OS 25.42951734 39.44904226
OS 25.42956052 39.44943088
OS 25.4289687 39.45631428
OS 25.42881122 39.46135364
OS 25.43030982 39.47324084
OS 25.43324606 39.4907643
OS 25.43261106 39.51167866
OS 25.43226054 39.51320012
OS 25.43352038 39.52285466
OS 25.4327914 39.53378936
OS 25.43380994 39.54024604
OS 25.43334766 39.55183098
OS 25.43366008 39.72935666
OS 25.78402768 39.72894264
OS 25.89076102 39.67687518
OS 25.89329594 39.59194774
OS 25.89491138 39.58492464
OS 25.89421542 39.57774406
OS 25.89548288 39.56506692
OS 25.90517552 39.5332839
OS 25.90973228 39.5138529
OS 25.91122072 39.50521436
OS 25.91259994 39.50162788
OS 25.91275742 39.50095478
OS 25.91340766 39.49952476
OS 25.9143881 39.4969746
OS 25.91503072 39.4959586
OS 25.91592734 39.49398502
OS 25.9166233 39.49301728
OS 25.91730656 39.48978894
OS 25.92111402 39.48091418
OS 25.92454302 39.47591546
OS 25.92614322 39.47007346
OS 25.92741068 39.467536
OS 25.94745382 39.44170928
OS 25.96560974 39.4145389
OS 25.96834024 39.4118084
OS 25.96905906 39.41054602
OS 25.97093358 39.4090906
OS 25.97324498 39.40563366
OS 25.97894982 39.39993136
OS 25.98232802 39.39767584
OS 25.98373518 39.39585974
OS 25.98502804 39.39512314
OS 25.98782204 39.39232914
OS 25.99163204 39.38978406
OS 25.99222894 39.38918716
OS 25.9944235 39.38772158
OS 25.99594496 39.38556512
OS 26.0195187 39.37066802
OS 26.04078866 39.35416056
OS 26.04332358 39.3528931
OS 26.04878712 39.35139704
OS 26.05838578 39.34498354
OS 26.06097658 39.34446792
OS 26.06320416 39.34306076
OS 26.0678422 39.34127768
OS 26.07764914 39.33707398
OS 26.09365368 39.33368816
OS 26.10844156 39.32669554
OS 26.11351394 39.32542554
OS 26.13386442 39.32442732
OS 26.15364848 39.31953528
OS 26.19484728 39.31763536
OS 26.20183736 39.31869454
OS 26.2106156 39.31680732
OS 26.24933536 39.31621296
OS 26.27848694 39.3150471
OS 26.28356694 39.3158472
OS 26.28861646 39.3148947
OS 26.39249738 39.31590308
OS 26.43216456 39.31524268
OS 26.45656888 39.31351294
OS 26.54222022 39.25457224
OS 26.54348768 39.25203732
OS 26.5467338 39.24785394
OS 26.54987578 39.24024918
OS 26.55494816 39.23264188
OS 26.56791232 39.21965232
OS 26.57605556 39.2074654
OS 26.57879876 39.2026521
OS 26.5797792 39.2018901
OS 26.5816842 39.19904022
OS 26.5886565 39.19206792
OS 26.59150638 39.19016292
OS 26.59226838 39.18918248
OS 26.59353076 39.18846366
OS 26.59626126 39.18573062
OS 26.60571514 39.17941364
OS 26.60693434 39.17768644
OS 26.61676922 39.17146852
OS 26.63096782 39.15788968
OS 26.63794012 39.1534523
OS 26.65377194 39.14730296
OS 26.6624181 39.141527
OS 26.66492762 39.14102662
OS 26.67221742 39.13641906
OS 26.67286004 39.13596694
OS 26.6731115 39.13585518
OS 26.67418846 39.13517446
OS 26.67758698 39.13386636
OS 26.68426972 39.1308971
OS 26.71943094 39.12296722
OS 26.75435594 39.11372416
OS 26.77464038 39.1124567
OS 26.7779246 39.11289866
OS 26.78745214 39.11082348
OS 26.85717514 39.10955602
OS 26.8578457 39.10967794
OS 26.8650593 39.10825554
OS 27.21049422 39.10889054
OS 27.2128488 39.10936298
OS 27.21521354 39.10895404
OS 27.26591702 39.1102215
OS 27.26820556 39.11073712
OS 27.27052458 39.11038914
OS 27.31045846 39.1122916
OS 27.33004694 39.1171684
OS 27.350212 39.11814884
OS 27.3552793 39.1194163
OS 27.37190614 39.12726998
OS 27.38328788 39.1290683
OS 27.39006714 39.13156512
OS 27.39016366 39.13158798
OS 27.39031352 39.13165656
OS 27.3953351 39.13350568
OS 27.39561958 39.13368094
OS 27.40019412 39.13160068
OS 27.43651104 39.12308914
OS 27.4725892 39.11368098
OS 27.49413856 39.11241352
OS 27.49702908 39.11281484
OS 27.50614006 39.11082602
OS 27.5745956 39.10955856
OS 27.57520012 39.10966778
OS 27.58232482 39.10825554
OS 28.43988216 39.10889054
OS 28.44228754 39.1093706
OS 28.44470308 39.1089515
OS 28.49667656 39.11021896
OS 28.49972202 39.11090222
OS 28.50281828 39.11046026
OS 28.53767978 39.11236272
OS 28.5420562 39.1134854
OS 28.54231528 39.11344222
OS 28.54709048 39.11455982
OS 28.55539882 39.1141077
OS 28.56427358 39.11537516
OS 28.59159636 39.12498652
OS 28.60101722 39.12719124
OS 28.6129349 39.12907592
OS 28.61968368 39.13156512
OS 28.61978274 39.13158798
OS 28.61993768 39.1316591
OS 28.6249745 39.13351584
OS 28.6314515 39.13748332
OS 28.63885306 39.13921814
OS 28.64582282 39.14238806
OS 28.66952864 39.1594213
OS 28.69491086 39.17386374
OS 28.70143866 39.18226098
OS 28.70584302 39.18477304
OS 28.70713842 39.18644436
OS 28.71043788 39.18881418
OS 28.71222858 39.19170216
OS 28.7138618 39.19333538
OS 28.71696314 39.19797596
OS 28.72625446 39.20518702
OS 28.73892906 39.22742218
OS 28.75461356 39.24763804
OS 28.75714594 39.25271042
OS 28.75976214 39.26226844
OS 28.76073496 39.26380768
OS 28.76354928 39.2677269
OS 28.76441796 39.26963698
OS 28.76505804 39.27065044
OS 28.76604864 39.273226
OS 28.76988658 39.28166896
OS 28.77881468 39.31975626
OS 28.78800186 39.35790198
OS 28.78926932 39.38959356
OS 28.78901532 39.39121154
OS 28.7906841 39.39911602
OS 28.79195156 39.5055979
OS 28.79193124 39.50570712
OS 28.79323426 39.51234414
OS 28.79291676 39.6388717
OS 28.88259908 39.72879532
OS 32.47278494 39.72940492
OS 32.47682608 39.7302101
OS 32.4808977 39.72956748
OS 32.51193396 39.73080954
OS 32.55031336 39.73204652
OS 32.55479646 39.73309046
OS 32.55937862 39.73253928
OS 32.5758556 39.73380674
OS 32.59245958 39.73845748
OS 32.60967824 39.73929568
OS 32.61474554 39.74056314
OS 32.62193882 39.74396166
OS 32.62982552 39.74495734
OS 32.63552782 39.7468598
OS 32.6371204 39.74776912
OS 32.63791542 39.74798502
OS 32.64218008 39.750111
OS 32.64669874 39.75095174
OS 32.65303858 39.75348666
OS 32.65475054 39.75460172
OS 32.67352876 39.75857682
OS 32.68240352 39.76238428
OS 32.68747844 39.76586662
OS 32.69299532 39.76807388
OS 32.69512384 39.76945818
OS 32.69761558 39.7699865
OS 32.70649034 39.77379396
OS 32.71151954 39.77724328
OS 32.71740472 39.77885872
OS 32.7199371 39.78012618
OS 32.72283778 39.78237916
OS 32.72572068 39.7829532
OS 32.7472802 39.79735754
OS 32.7490201 39.79783506
OS 32.75155756 39.79910252
OS 32.7596881 39.80541188
OS 32.76565456 39.8090644
OS 32.77998524 39.8166971
OS 32.78550212 39.82121068
OS 32.78602028 39.82152818
OS 32.78621332 39.82179234
OS 32.78695754 39.82240194
OS 32.78964232 39.8256633
OS 32.79187752 39.82715682
OS 32.79293416 39.82821346
OS 32.7971404 39.83061122
OS 32.7999344 39.83421294
OS 32.80455466 39.83729904
OS 32.80772458 39.84046896
OS 32.80947972 39.84309532
OS 32.80981754 39.84328836
OS 32.81169714 39.84571152
OS 32.81199178 39.84600362
OS 32.8144124 39.84788322
OS 32.81460544 39.84822104
OS 32.8172318 39.84997618
OS 32.82040172 39.8531461
OS 32.82276392 39.85668178
OS 32.82309666 39.85711104
OS 32.82466892 39.85868076
OS 32.82708954 39.86056036
OS 32.82731052 39.86094898
OS 32.83000292 39.86274984
OS 32.83190538 39.8646523
OS 32.83444538 39.86845976
OS 32.83733844 39.87135282
OS 32.83976668 39.8732375
OS 32.84131862 39.87596038
OS 32.84319822 39.87721514
OS 32.84994192 39.8839563
OS 32.85238794 39.88585368
OS 32.85240826 39.88588924
OS 32.85244128 39.88591464
OS 32.85399322 39.88863752
OS 32.85589314 39.88990752
OS 32.85676182 39.89077366
OS 32.8580496 39.89151026
OS 32.85995714 39.89397152
OS 32.86261906 39.8966309
OS 32.8630788 39.8969865
OS 32.8665713 39.89931822
OS 32.8684763 39.90121814
OS 32.87104424 39.90505608
OS 32.87411256 39.9081244
OS 32.87456976 39.90847746
OS 32.87808004 39.91082442
OS 32.87997996 39.91272434
OS 32.88351056 39.91800754
OS 32.88804446 39.92153306
OS 32.89041428 39.92569866
OS 32.89204242 39.9273268
OS 32.89349784 39.92950612
OS 32.89564414 39.93101996
OS 32.90489482 39.94566052
OS 32.91063268 39.95198258
OS 32.9144376 39.95832242
OS 32.91550948 39.96130946
OS 32.92025674 39.9671159
OS 32.92207792 39.97053728
OS 32.92291866 39.9711545
OS 32.92315488 39.97154312
OS 32.92466364 39.97278518
OS 32.93037102 39.97976002
OS 32.94161814 40.00087758
OS 32.94472456 40.004873
OS 32.94599456 40.00740792
OS 32.94689372 40.01067944
OS 32.94886984 40.01393826
OS 32.95247664 40.01791336
OS 32.95817894 40.02742058
OS 32.95981216 40.0319748
OS 32.9641835 40.03918332
OS 32.96782078 40.04917822
OS 32.97266964 40.05663566
OS 32.97520456 40.0629755
OS 32.97759978 40.07584822
OS 32.98138438 40.08444866
OS 32.98244356 40.08922132
OS 32.98505214 40.09335136
OS 32.98822206 40.10159112
OS 32.99036074 40.11398124
OS 32.99573284 40.12535282
OS 32.9970003 40.13042266
OS 32.9971527 40.1335748
OS 32.99989336 40.14778864
OS 33.00104144 40.15105
OS 33.00202696 40.15795372
OS 33.01007876 40.18335118
OS 33.01118874 40.19333592
OS 33.01355348 40.21224368
OS 33.01310136 40.21850986
OS 33.0147168 40.22457792
OS 33.01600712 40.24480902
OS 33.0250673 40.27550746
OS 33.02633476 40.2894546
OS 33.02435356 40.3081363
OS 33.02525526 40.31239842
OS 33.02232918 40.3281134
OS 33.01997968 40.36159314
OS 33.01807976 40.3685629
OS 33.01541784 40.3738969
OS 33.01461266 40.3851872
OS 33.01316232 40.39047802
OS 33.01355602 40.39594664
OS 33.01245874 40.40472996
OS 33.01071122 40.42044748
OS 33.00655832 40.4335488
OS 33.00589538 40.44728004
OS 33.00463046 40.45234988
OS 32.99924566 40.4637621
OS 32.99709936 40.47620302
OS 32.99075698 40.49268254
OS 32.98889262 40.49563148
OS 32.98424696 40.51622834
OS 32.97917712 40.52763548
OS 32.97658378 40.53131086
OS 32.9739879 40.53554758
OS 32.9737847 40.5361267
OS 32.97215148 40.54310154
OS 32.9689841 40.55007384
OS 32.96455434 40.55624096
OS 32.96413524 40.55733316
OS 32.9634088 40.55848124
OS 32.96315988 40.55982236
OS 32.96062496 40.5661622
OS 32.95992646 40.56723408
OS 32.95967754 40.56849138
OS 32.95640348 40.57339104
OS 32.95624092 40.5738203
OS 32.95217692 40.58032524
OS 32.95174004 40.58266712
OS 32.94920512 40.58900188
OS 32.94855488 40.59000264
OS 32.9483212 40.59117866
OS 32.94261382 40.59973084
OS 32.9407266 40.60303538
OS 32.93936516 40.60460256
OS 32.93279672 40.61444506
OS 32.92619272 40.62840744
OS 32.92403118 40.63036578
OS 32.92311424 40.6324816
OS 32.91741194 40.64072136
OS 32.91560346 40.64247142
OS 32.91196872 40.64884174
OS 32.90853718 40.65150112
OS 32.90581176 40.65569212
OS 32.9048237 40.6563703
OS 32.90416076 40.65736344
OS 32.90226084 40.65926844
OS 32.90085622 40.66020824
OS 32.89738912 40.66938018
OS 32.88962942 40.67764026
OS 32.88956084 40.67780536
OS 32.88933478 40.67803142
OS 32.88409984 40.6882219
OS 32.8655426 40.70396482
OS 32.86415322 40.70690614
OS 32.85286292 40.7171525
OS 32.84438948 40.7298144
OS 32.84248702 40.73171686
OS 32.82105196 40.74601706
OS 32.81149394 40.7546937
OS 32.80744772 40.75874754
OS 32.80666794 40.75907266
OS 32.8052303 40.76037568
OS 32.7997058 40.76235688
OS 32.79967532 40.76239498
OS 32.79231186 40.7665936
OS 32.78573072 40.77507212
OS 32.78004366 40.7783157
OS 32.77858824 40.779446
OS 32.7741915 40.78165072
OS 32.7702418 40.78390116
OS 32.75703888 40.7958798
OS 32.75069904 40.79968218
OS 32.73504756 40.8052905
OS 32.7312147 40.80702278
OS 32.7162414 40.81618456
OS 32.7111741 40.81804892
OS 32.70813118 40.82003012
OS 32.70292926 40.82376646
OS 32.70112332 40.82458688
OS 32.70057722 40.82494248
OS 32.69862396 40.82572226
OS 32.6975724 40.82620232
OS 32.6968866 40.82659348
OS 32.69667578 40.8266646
OS 32.69650814 40.82680938
OS 32.69549468 40.8271472
OS 32.68898212 40.8301063
OS 32.6808084 40.832024
OS 32.66416886 40.8375485
OS 32.65012266 40.84426934
OS 32.64327228 40.84601686
OS 32.6415781 40.84688808
OS 32.63270334 40.849423
OS 32.63076024 40.84958302
OS 32.61579964 40.85704554
OS 32.60882734 40.858948
OS 32.60659722 40.85910548
OS 32.604583 40.86005544
OS 32.59951062 40.8613229
OS 32.59602574 40.86149308
OS 32.58301586 40.8639137
OS 32.57890614 40.86535896
OS 32.57003392 40.86662642
OS 32.56880202 40.86656038
OS 32.56745836 40.8668093
OS 32.5335519 40.87487126
OS 32.49932794 40.87614126
OS 32.49707496 40.87578058
OS 32.48824592 40.87754842
OS 31.57126528 40.87881588
OS 31.45788476 40.88001984
OS 31.409513 40.88274018
OS 31.40769944 40.88290528
OS 31.40405454 40.88428196
OS 31.39644978 40.88554942
OS 31.3900312 40.88534876
OS 31.38389202 40.8872436
OS 31.36551004 40.88914352
OS 31.36054688 40.8886787
OS 31.34999826 40.89127966
OS 31.33564472 40.89193244
OS 31.3277504 40.896667
OS 31.32537042 40.89752044
OS 31.3233435 40.8988006
OS 31.31639914 40.90147268
OS 31.31184238 40.9032964
OS 31.30322416 40.90920952
OS 31.30156554 40.90992072
OS 31.29605628 40.91542998
OS 31.29263744 40.91771344
OS 31.29035906 40.92112466
OS 31.2694447 40.94204156
OS 31.2564526 41.04272716
OS 31.34700868 41.1385131
OS 31.37200482 41.13908206
OS 31.37460578 41.13966118
OS 32.925385 41.14029618
OS 32.9311254 41.14143918
OS 32.93380002 41.14094642
OS 32.98007374 41.14158142
OS 32.98400566 41.14241962
OS 32.98799092 41.14184304
OS 33.03616202 41.14437796
OS 33.04088134 41.14557684
OS 33.04573528 41.14510694
OS 33.05840988 41.1463744
OS 33.07409184 41.15115722
OS 33.07989828 41.15090322
OS 33.09217664 41.15279298
OS 33.09730236 41.15336194
OS 33.10918702 41.15444144
OS 33.1120496 41.15528726
OS 33.1150341 41.15505612
OS 33.13088116 41.15695858
OS 33.15976858 41.16639722
OS 33.18941038 41.17308758
OS 33.19729962 41.17659532
OS 33.2064106 41.18024022
OS 33.21107658 41.18327552
OS 33.21561048 41.1844109
OS 33.22382992 41.18829202
OS 33.22433538 41.18843934
OS 33.22641564 41.1895163
OS 33.23167852 41.19200042
OS 33.24900894 41.19591456
OS 33.26041608 41.20098694
OS 33.2622652 41.2022925
OS 33.26438864 41.20305704
OS 33.2685644 41.20557164
OS 33.27334468 41.2065216
OS 33.30105354 41.22503566
OS 33.30179014 41.22523886
OS 33.30432506 41.22650886
OS 33.30771596 41.22914284
OS 33.31065982 41.23091576
OS 33.32428438 41.23774328
OS 33.33211774 41.2438342
OS 33.33255208 41.24409582
OS 33.33268416 41.24427362
OS 33.33569152 41.24661296
OS 33.3381477 41.24945014
OS 33.34060134 41.25135514
OS 33.34666686 41.25481208
OS 33.34758888 41.2560008
OS 33.37578034 41.27434976
OS 33.376489 41.27538354
OS 33.37752786 41.27607696
OS 33.3815309 41.28008
OS 33.38279328 41.28079882
OS 33.384236 41.2826581
OS 33.38767262 41.28495426
OS 33.39337746 41.29065656
OS 33.39566346 41.29408048
OS 33.39907976 41.2963614
OS 33.41746428 41.31474338
OS 33.41921942 41.3173672
OS 33.4195547 41.31756024
OS 33.4203167 41.31854068
OS 33.42316658 41.32044568
OS 33.43013888 41.32741798
OS 33.43204388 41.33026786
OS 33.43302432 41.33102986
OS 33.4332199 41.3313753
OS 33.43584118 41.33312536
OS 33.44154602 41.33882766
OS 33.44384472 41.34226682
OS 33.44569892 41.343707
OS 33.4458818 41.34402704
OS 33.44847514 41.34575932
OS 33.45291252 41.35019416
OS 33.45468798 41.35284846
OS 33.45504866 41.3530542
OS 33.45581066 41.35403464
OS 33.45866054 41.35593964
OS 33.46563284 41.36291194
OS 33.46753784 41.36576182
OS 33.46851828 41.36652382
OS 33.46923456 41.36778112
OS 33.47324014 41.3717867
OS 33.48898306 41.39535028
OS 33.50730408 41.4169479
OS 33.50772318 41.41770228
OS 33.5297526 41.42972156
OS 33.53654202 41.4326959
OS 33.55536342 41.43944722
OS 33.56749446 41.44055212
OS 33.5816829 41.4409382
OS 33.63590682 41.42965806
OE
SE
S P 0
OB 34.19865144 42.10797014 I
OS 34.20372128 42.10670268
OS 34.21005858 42.10543522
OS 34.21829834 42.1022653
OS 34.22844056 42.09973038
OS 34.24428762 42.09782792
OS 34.2544273 42.095293
OS 34.2607646 42.09275808
OS 34.26266706 42.09085562
OS 34.2753442 42.08705324
OS 34.28548388 42.08578578
OS 34.30450086 42.07691102
OS 34.31464054 42.0743761
OS 34.32478022 42.07310864
OS 34.33175252 42.0674038
OS 34.33492244 42.06423642
OS 34.3437972 42.05916658
OS 34.3501345 42.05282674
OS 34.35647434 42.05029182
OS 34.35837426 42.04965936
OS 34.35900926 42.04902436
OS 34.3640791 42.0477569
OS 34.37168386 42.04015214
OS 34.37421878 42.03888214
OS 34.3767537 42.03634722
OS 34.37928862 42.03507976
OS 34.38245854 42.03064238
OS 34.38816338 42.02493754
OS 34.3906983 42.02367008
OS 34.39703814 42.01733278
OS 34.39957306 42.01606532
OS 34.40591036 42.0135304
OS 34.41098274 42.0122604
OS 34.41795504 42.0065581
OS 34.42239242 42.00212326
OS 34.42492734 42.0008558
OS 34.4318971 41.9938835
OS 34.43316456 41.99134604
OS 34.43506702 41.98944612
OS 34.43760194 41.98817866
OS 34.44330678 41.98247382
OS 34.44457424 41.9799389
OS 34.45091154 41.97359906
OS 34.452179 41.97106414
OS 34.45471646 41.9647243
OS 34.45598392 41.95965446
OS 34.45851884 41.95711954
OS 34.4597863 41.95458462
OS 34.4661236 41.94824478
OS 34.4673936 41.94570986
OS 34.4730959 41.9387401
OS 34.47626582 41.93557018
OS 34.4807032 41.92352804
OS 34.48387312 41.91909066
OS 34.48767296 41.91528828
OS 34.48894042 41.91275336
OS 34.49781518 41.90134368
OS 34.5003501 41.89880876
OS 34.50288502 41.88866654
OS 34.50415248 41.87852686
OS 34.51302724 41.85951242
OS 34.51556216 41.8493702
OS 34.51682962 41.84049544
OS 34.52443692 41.82401846
OS 34.52633684 41.81704616
OS 34.52760684 41.80310156
OS 34.5288743 41.79549426
OS 34.53077422 41.78852196
OS 34.53330914 41.78218466
OS 34.5358466 41.7733099
OS 34.53711406 41.7606353
OS 34.53964898 41.7264088
OS 34.53774652 41.70168952
OS 34.53647906 41.68647746
OS 34.5352116 41.6788727
OS 34.53140922 41.66873048
OS 34.53014176 41.6636581
OS 34.5282393 41.6566858
OS 34.52697184 41.6440112
OS 34.52570438 41.63513898
OS 34.52443692 41.6313366
OS 34.51809708 41.617392
OS 34.51556216 41.60851724
OS 34.5142947 41.59837502
OS 34.50161756 41.57175582
OS 34.49654772 41.56288106
OS 34.48894042 41.54640154
OS 34.48387312 41.53752932
OS 34.47880074 41.52611964
OS 34.4737309 41.51724742
OS 34.46866106 41.51217758
OS 34.4673936 41.50964012
OS 34.46295622 41.50393782
OS 34.4604213 41.50266782
OS 34.452179 41.49442806
OS 34.45154654 41.49252814
OS 34.44901162 41.49126068
OS 34.44077186 41.48302092
OS 34.43950186 41.48048346
OS 34.4318971 41.47414616
OS 34.3913333 41.43358236
OS 34.3906983 41.4316799
OS 34.38816338 41.43041244
OS 34.37992362 41.42217268
OS 34.37865616 41.41963776
OS 34.37421878 41.41646784
OS 34.36724648 41.410763
OS 34.3640791 41.40759308
OS 34.3577418 41.40505816
OS 34.35266942 41.40379324
OS 34.34633212 41.39999086
OS 34.3437972 41.39745594
OS 34.33492244 41.39365102
OS 34.32668268 41.39048364
OS 34.31971038 41.38604626
OS 34.30576832 41.37970642
OS 34.28675388 41.3708342
OS 34.2816815 41.36956674
OS 34.26520198 41.36829674
OS 34.26013214 41.36702928
OS 34.24808746 41.36259444
OS 34.23731532 41.35942452
OS 34.23224294 41.35815706
OS 34.21956834 41.3568896
OS 34.21069358 41.35562214
OS 34.19865144 41.35371968
OS 34.19357906 41.35245222
OS 34.18343938 41.34864984
OS 34.17710208 41.34737984
OS 34.16695986 41.34611238
OS 34.14984534 41.344215
OS 34.13273336 41.34611238
OS 34.12259368 41.34737984
OS 34.11625384 41.34864984
OS 34.10928154 41.35181722
OS 34.10230924 41.35371968
OS 34.09470448 41.35498714
OS 34.07758996 41.3568896
OS 34.06428036 41.35878952
OS 34.05921052 41.36005698
OS 34.05097076 41.3632269
OS 34.042096 41.36702928
OS 34.03322378 41.36829674
OS 34.0281514 41.36956674
OS 34.01991164 41.37273412
OS 34.00406712 41.37970642
OS 33.9951949 41.38097388
OS 33.9875876 41.38224134
OS 33.9806153 41.38794618
OS 33.97744792 41.3911161
OS 33.96857316 41.39618594
OS 33.96223332 41.40252578
OS 33.95589602 41.40505816
OS 33.94765626 41.40822808
OS 33.9400515 41.41329792
OS 33.9330792 41.41646784
OS 33.92293698 41.42027022
OS 33.91533222 41.42787752
OS 33.9127973 41.42914498
OS 33.90455754 41.43738474
OS 33.90392254 41.4392872
OS 33.90138762 41.44055466
OS 33.8506816 41.49126068
OS 33.84814668 41.49252814
OS 33.84307684 41.5001329
OS 33.83610454 41.5071052
OS 33.83356708 41.51344504
OS 33.8297647 41.52358472
OS 33.82722978 41.52611964
OS 33.82596486 41.52865456
OS 33.82215994 41.53752932
OS 33.81899256 41.54576908
OS 33.8107528 41.55400884
OS 33.8094828 41.55654376
OS 33.8031455 41.56541852
OS 33.80061058 41.56795344
OS 33.79807566 41.57429074
OS 33.7968082 41.5831655
OS 33.79490574 41.59013526
OS 33.79237082 41.59647256
OS 33.78539852 41.61231962
OS 33.78349606 41.6243643
OS 33.77969368 41.63450398
OS 33.77779122 41.64147628
OS 33.77652376 41.64654612
OS 33.7746213 41.67633524
OS 33.77335384 41.70929428
OS 33.77272138 41.74542324
OS 33.77398884 41.74922562
OS 33.7752563 41.7948618
OS 33.77652376 41.79866418
OS 33.77779122 41.81641116
OS 33.7815936 41.82528338
OS 33.78413106 41.83415814
OS 33.78603098 41.84493282
OS 33.7885659 41.85127012
OS 33.7955382 41.86584972
OS 33.7968082 41.87472448
OS 33.79870812 41.88296424
OS 33.80124304 41.889299
OS 33.80441296 41.89246892
OS 33.80821534 41.90134368
OS 33.8094828 41.90641352
OS 33.81328772 41.91275336
OS 33.81962502 41.91909066
OS 33.82089248 41.92162558
OS 33.82659732 41.92986534
OS 33.82849724 41.93050034
OS 33.8297647 41.93303526
OS 33.83356708 41.94191002
OS 33.83863946 41.9507797
OS 33.84497676 41.95711954
OS 33.84624422 41.95965446
OS 33.90265508 42.01606532
OS 33.90455754 42.01669778
OS 33.905825 42.0192327
OS 33.91406476 42.027475
OS 33.91659968 42.02874246
OS 33.92293698 42.03507976
OS 33.92927682 42.03761468
OS 33.93751658 42.0407846
OS 33.94322142 42.04648944
OS 33.94575634 42.0477569
OS 33.94828872 42.05029182
OS 33.95462856 42.05409674
OS 33.96096586 42.06043404
OS 33.97491046 42.06550134
OS 33.98378522 42.07184118
OS 33.99582736 42.07627856
OS 34.00026474 42.07817848
OS 34.01040442 42.08451832
OS 34.02561648 42.08705324
OS 34.03766116 42.09149062
OS 34.04463346 42.09466054
OS 34.05477314 42.09719546
OS 34.07125266 42.09846292
OS 34.0763225 42.09973038
OS 34.08899964 42.10099784
OS 34.09280202 42.1022653
OS 34.10547916 42.10606768
OS 34.110549 42.10733768
OS 34.12322614 42.10860514
OS 34.15745264 42.11114006
OS 34.19865144 42.10797014
OE
SE
S P 0
OB 43.2467766 45.28782662 I
OS 43.5750081 45.19987658
OS 43.8889648 45.06983112
OS 44.18321872 44.89994068
OS 44.45280162 44.69308308
OS 44.693078 44.45280924
OS 44.89994068 44.18322126
OS 45.06983112 43.8889648
OS 45.19986896 43.57502842
OS 45.28782408 43.24677914
OS 45.33217502 42.90990402
OS 45.33217756 42.7399958
OS 45.33217502 -2.06000096
OS 45.33217502 -2.22990918
OS 45.28782662 -2.56677922
OS 45.19987658 -2.89501072
OS 45.06983112 -3.20896742
OS 44.89994068 -3.50322134
OS 44.69308308 -3.77280424
OS 44.45280924 -4.01308062
OS 44.18322126 -4.2199433
OS 43.8889648 -4.38983374
OS 43.57502842 -4.51987158
OS 43.24677914 -4.6078267
OS 42.90989132 -4.6521751
OS 42.7399958 -4.65217764
OS -2.06000096 -4.65218272
OS -2.22990918 -4.65218272
OS -2.56678938 -4.60783178
OS -2.89502088 -4.51988428
OS -3.20895472 -4.38984644
OS -3.50322388 -4.21994838
OS -3.77279916 -4.0130984
OS -4.0130984 -3.77279916
OS -4.21994584 -3.50322642
OS -4.38984136 -3.2089598
OS -4.51988174 -2.89502088
OS -4.60782924 -2.56679192
OS -4.65218018 -2.22991172
OS -4.65217764 -2.06000604
OS -4.65218526 42.73999834
OS -4.65218526 42.90990656
OS -4.60783432 43.24678422
OS -4.51988682 43.57501318
OS -4.38984644 43.88895464
OS -4.21995092 44.18321872
OS -4.01310094 44.452794
OS -3.77280932 44.69308562
OS -3.50323404 44.89993814
OS -3.20894964 45.06984128
OS -2.89502342 45.19987658
OS -2.56679192 45.28782408
OS -2.22992188 45.33217248
OS -2.07798416 45.33216486
OS -2.07795622 45.33216994
OS 42.74000088 45.33217502
OS 42.90990656 45.33217502
OS 43.2467766 45.28782662
OE
OB 32.90719606 45.1621906 H
OS 32.5440167 45.1615556
OS 32.54171292 45.16109332
OS 32.53940152 45.16149464
OS 32.48742804 45.16022718
OS 32.4839584 45.15944994
OS 32.4804278 45.15993762
OS 32.4588759 45.15866762
OS 32.4576186 45.15833996
OS 32.45632574 45.15850252
OS 32.43857622 45.15723506
OS 32.42606926 45.15380606
OS 32.4130924 45.15379082
OS 32.40675764 45.15252336
OS 32.39729106 45.1485889
OS 32.39698626 45.14854572
OS 32.39318134 45.14840348
OS 32.3889751 45.14740272
OS 32.38053468 45.14619622
OS 32.37057534 45.14269356
OS 32.36002672 45.14218556
OS 32.35495434 45.14092064
OS 32.33252868 45.13034154
OS 32.33167524 45.13031614
OS 32.33076084 45.12990466
OS 32.32032144 45.12795902
OS 32.31653176 45.12644264
OS 32.30716932 45.12299332
OS 32.29187598 45.11363088
OS 32.29053232 45.11337942
OS 32.28419756 45.1108445
OS 32.28208682 45.10947036
OS 32.27962048 45.10894966
OS 32.27074826 45.10514728
OS 32.26572668 45.10170304
OS 32.25986182 45.10009776
OS 32.25732436 45.0988303
OS 32.25135536 45.09419734
OS 32.23947324 45.0868288
OS 32.23780954 45.08637414
OS 32.22865284 45.08455296
OS 32.2226432 45.08053722
OS 32.2224908 45.08046102
OS 32.22225458 45.08027814
OS 32.2183125 45.07764416
OS 32.2171187 45.07714886
OS 32.21296072 45.07601094
OS 32.21042326 45.07474348
OS 32.19922694 45.06605414
OS 32.1818127 45.05736734
OS 32.17648632 45.05123578
OS 32.16801034 45.0464047
OS 32.1641851 45.04147456
OS 32.162496 45.0403468
OS 32.1601846 45.03803794
OS 32.15596566 45.03563256
OS 32.15383206 45.03288174
OS 32.15362124 45.03274204
OS 32.15241982 45.03154062
OS 32.14860982 45.02899808
OS 32.1454399 45.0258307
OS 32.14365682 45.02316624
OS 32.14328852 45.02295542
OS 32.14140892 45.0205348
OS 32.14110158 45.02022746
OS 32.14066216 45.01988456
OS 32.13714426 45.01753506
OS 32.13270434 45.01309768
OS 32.13034214 45.009562
OS 32.1300094 45.00913274
OS 32.12970714 45.00883048
OS 32.12728398 45.00695088
OS 32.1270757 45.00658512
OS 32.12440616 45.0047995
OS 32.12124132 45.00162958
OS 32.11951666 44.9990464
OS 32.11920424 44.9988686
OS 32.11732464 44.99644798
OS 32.11703762 44.99616096
OS 32.1165347 44.9957698
OS 32.11305998 44.99344824
OS 32.10862006 44.98901086
OS 32.10606228 44.98518054
OS 32.10563048 44.98475128
OS 32.1031997 44.98286406
OS 32.10206432 44.98087016
OS 32.09816034 44.97612798
OS 32.0905759 44.97024788
OS 32.08944306 44.9682616
OS 32.08858454 44.96721766
OS 32.0867532 44.96571144
OS 32.08137856 44.959143
OS 32.0799079 44.9583048
OS 32.07889698 44.95700178
OS 32.07406844 44.95302668
OS 32.06847282 44.946189
OS 32.06805626 44.9459096
OS 32.06764732 44.94550066
OS 32.06140146 44.9403597
OS 32.05630622 44.93413416
OS 32.05376114 44.93215804
OS 32.0425953 44.9125721
OS 32.02824938 44.89519342
OS 32.02381454 44.88695366
OS 32.02178508 44.88033188
OS 32.01774394 44.87470832
OS 32.015303 44.86933876
OS 32.01490422 44.86864026
OS 32.01467816 44.86796208
OS 32.0114041 44.86076118
OS 32.01123392 44.86003982
OS 31.94032474 44.81798758
OS 31.89052042 44.80990022
OS 31.80836412 44.86455594
OS 31.80832348 44.86477692
OS 31.80578856 44.87111168
OS 31.80510784 44.87215816
OS 31.804864 44.87338498
OS 31.80171948 44.87809414
OS 31.80117338 44.87949876
OS 31.79229862 44.8934459
OS 31.79084828 44.89496228
OS 31.78989832 44.8968622
OS 31.78824478 44.89899072
OS 31.78283458 44.91044104
OS 31.77639822 44.9162805
OS 31.7623952 44.93780192
OS 31.76136396 44.93851058
OS 31.76067054 44.9395469
OS 31.75432308 44.9458969
OS 31.75177546 44.94970944
OS 31.69536714 45.0061203
OS 31.69350532 45.0073649
OS 31.6922658 45.00922164
OS 31.68973342 45.01175656
OS 31.68505982 45.0148833
OS 31.67781066 45.02422288
OS 31.6729237 45.02700926
OS 31.6696725 45.02918096
OS 31.66949978 45.02943242
OS 31.668212 45.03027062
OS 31.66273576 45.03609992
OS 31.65829838 45.03926984
OS 31.64679218 45.04446414
OS 31.64662708 45.04457336
OS 31.63216432 45.05580016
OS 31.63183412 45.0561583
OS 31.6293881 45.05795408
OS 31.62081814 45.0646038
OS 31.61828322 45.06587126
OS 31.61385854 45.06708284
OS 31.61241836 45.0677534
OS 31.59904272 45.07988952
OS 31.59270288 45.0836919
OS 31.58359698 45.0869558
OS 31.58333282 45.08720726
OS 31.57636052 45.09164464
OS 31.57583728 45.09184784
OS 31.5722 45.0944615
OS 31.5582554 45.10080134
OS 31.55232196 45.10219326
OS 31.54004106 45.10995042
OS 31.53541826 45.11172588
OS 31.5301122 45.11400172
OS 31.5292486 45.1141846
OS 31.52323388 45.1181978
OS 31.52071166 45.11869818
OS 31.51853996 45.12006978
OS 31.5103002 45.1232397
OS 31.49791008 45.12537838
OS 31.4865385 45.13075048
OS 31.48146866 45.13201794
OS 31.47466146 45.13234814
OS 31.47133406 45.13308728
OS 31.45450148 45.14080634
OS 31.44119188 45.14397372
OS 31.43173546 45.14432678
OS 31.42281752 45.14746368
OS 31.41162628 45.14906134
OS 31.40480384 45.15189598
OS 31.39846654 45.15316344
OS 31.38356436 45.15317868
OS 31.36223344 45.15824852
OS 31.32800694 45.15951598
OS 31.32565744 45.15913752
OS 31.31669378 45.16092314
OS 24.38900888 45.1621906
OS 24.36236682 45.15689724
OS 24.33529042 45.15499732
OS 24.32832066 45.1530974
OS 24.31844006 45.14816726
OS 24.31096992 45.1466839
OS 24.29771112 45.13782692
OS 24.29464788 45.13630038
OS 24.26059918 45.12021456
OS 24.18411216 45.085508
OS 24.10065284 45.10646808
OS 24.09989592 45.10678812
OS 24.09939046 45.10688972
OS 24.09520454 45.1086601
OS 24.0882932 45.11131948
OS 24.08314208 45.11337942
OS 24.08215656 45.1135623
OS 24.07974864 45.1150863
OS 24.0774601 45.11694812
OS 24.07341388 45.11908934
OS 24.06987058 45.12132962
OS 24.0673509 45.1222999
OS 24.06668288 45.12265296
OS 24.06555766 45.12298824
OS 24.06293892 45.12399662
OS 24.05779034 45.12605656
OS 24.05118126 45.12728846
OS 24.04194836 45.1300469
OS 24.01848892 45.14080634
OS 24.00517932 45.14397372
OS 23.9957229 45.14432678
OS 23.98680496 45.14746368
OS 23.98505744 45.1477126
OS 23.98442752 45.14792342
OS 23.9813338 45.14831204
OS 23.97825024 45.14977
OS 23.97317786 45.15103746
OS 23.95379512 45.15197726
OS 23.9272191 45.15825868
OS 23.8917226 45.15952614
OS 23.88967028 45.1591934
OS 23.8810673 45.16092314
OS 23.26879268 45.1621906
OS 23.260812 45.16062088
OS 23.25273226 45.16159116
OS 23.2436924 45.1608952
OS 23.23678106 45.16187564
OS 23.21811968 45.16083932
OS 23.21072828 45.16190866
OS 23.19868868 45.16127366
OS 23.19349438 45.15995286
OS 23.19325816 45.15998588
OS 23.15839666 45.15808596
OS 23.13429206 45.15191122
OS 23.1231948 45.15190106
OS 23.1117775 45.14715888
OS 23.09375874 45.14380354
OS 23.08742398 45.14126862
OS 23.0839645 45.13901818
OS 23.08132036 45.13834
OS 23.07173694 45.1311518
OS 23.06942554 45.13051934
OS 23.06688808 45.12925188
OS 23.06485862 45.12767708
OS 23.04971514 45.12138804
OS 23.03645634 45.10810638
OS 23.02073374 45.09787526
OS 23.0142161 45.08837312
OS 23.00403324 45.08047118
OS 23.00130782 45.07569344
OS 22.99715238 45.0720968
OS 22.992715 45.0663945
OS 22.9832662 45.0475604
OS 22.97048492 45.0307964
OS 22.96595102 45.01366918
OS 22.96462768 45.01134762
OS 22.96446766 45.01008778
OS 22.95703816 44.9952745
OS 22.9555167 44.97425092
OS 22.95012428 44.95388012
OS 22.94885682 44.93359568
OS 22.94915146 44.93140112
OS 22.94866124 44.92598838
OS 22.9495731 44.91742096
OS 22.94843772 44.90841412
OS 22.94537702 44.89036996
OS 22.94600694 44.8681856
OS 22.94618474 44.86740582
OS 22.94533892 44.86356534
OS 22.94526526 44.8599941
OS 22.9450138 44.85817292
OS 22.94517382 44.85546528
OS 22.94470392 44.83250622
OS 22.9457123 44.8268344
OS 22.94564372 44.82566346
OS 22.94685276 44.8169538
OS 22.9453694 44.80828478
OS 22.94599932 44.78483296
OS 22.9464235 44.78296606
OS 22.94511286 44.77292036
OS 22.94574786 44.7634106
OS 22.94828532 44.7539872
OS 22.9479221 44.75182312
OS 22.94855456 44.73090622
OS 22.95164574 44.71748994
OS 22.9515035 44.7163571
OS 22.95341612 44.7093594
OS 22.95327642 44.70790652
OS 22.95565132 44.70012142
OS 22.95654032 44.6962657
OS 22.96307066 44.66126958
OS 22.96560812 44.65493228
OS 22.96631678 44.65384262
OS 22.966426 44.65337272
OS 22.968712 44.6501647
OS 22.97024616 44.64781012
OS 22.97248898 44.63960846
OS 22.97375644 44.637071
OS 22.97560556 44.63468848
OS 22.9764844 44.63180304
OS 22.9960043 44.6080896
OS 22.99931138 44.60108936
OS 23.0026337 44.59807692
OS 23.00902688 44.58825728
OS 23.01454122 44.58447776
OS 23.02251428 44.57419584
OS 23.02513556 44.57269978
OS 23.02705072 44.57037314
OS 23.03402556 44.56466576
OS 23.04719038 44.55765536
OS 23.05823938 44.54762998
OS 23.06457922 44.5438276
OS 23.07486114 44.54014206
OS 23.0836851 44.53370062
OS 23.0992553 44.52992364
OS 23.10424894 44.52726426
OS 23.11323546 44.52639304
OS 23.13948128 44.51698742
OS 23.1503982 44.51751828
OS 23.16100778 44.51494526
OS 23.18297878 44.51403086
OS 23.18678878 44.51293612
OS 23.2019983 44.51166866
OS 23.20325814 44.5118109
OS 23.20447734 44.51147816
OS 23.21249104 44.51248908
OS 23.23424614 44.51128004
OS 23.2411524 44.51225794
OS 23.2419271 44.51219952
OS 23.2495471 44.51311392
OS 23.25707058 44.51159754
OS 23.74674194 44.51033516
OS 23.75912952 44.5100329
OS 23.76038936 38.8278624
OS 23.7598966 38.81455026
OS 23.76101928 38.80756018
OS 23.7605824 38.7975094
OS 23.76171524 38.79014594
OS 23.76047318 38.7828028
OS 23.76110818 38.76061844
OS 23.7629065 38.75275968
OS 23.76257376 38.74666368
OS 23.76153744 38.74287908
OS 23.76211656 38.73828422
OS 23.76204036 38.73688722
OS 23.76026998 38.72284356
OS 23.76220292 38.71578236
OS 23.76180414 38.70846716
OS 23.76304874 38.6997448
OS 23.76368882 38.6818505
OS 23.766272 38.67092088
OS 23.7293531 38.59798224
OS 23.69360768 38.55596048
OS 23.67308702 38.54391834
OS 6.44999726 38.54391834
OS 6.44999726 38.80190614
OS 6.37121662 39.19796072
OS 6.21668302 39.57103846
OS 5.99233752 39.90679598
OS 5.7067958 40.1923377
OS 5.37103828 40.4166832
OS 4.99796054 40.5712168
OS 4.60190596 40.64999744
OS 4.19809168 40.64999744
OS 3.8020371 40.5712168
OS 3.42895936 40.4166832
OS 3.09320184 40.1923377
OS 2.80766012 39.90679598
OS 2.58331462 39.57103846
OS 2.42878102 39.19796072
OS 2.35000038 38.80190614
OS 2.35000038 38.54391834
OS -1.16000022 38.54391834
OS -1.23803664 38.5283964
OS -1.30419348 38.48419278
OS -1.3483971 38.41803594
OS -1.36391904 38.33999952
OS -1.36391904 2.3400004
OS -1.3483971 2.26196398
OS -1.30419348 2.19580714
OS -1.23803664 2.15160352
OS -1.16000022 2.13608158
OS 2.35000038 2.13608158
OS 2.35000038 1.79809394
OS 2.42878102 1.40203936
OS 2.58331462 1.02896162
OS 2.80766012 0.6932041
OS 3.09320184 0.40766238
OS 3.42895936 0.18331688
OS 3.8020371 0.02878328
OS 4.19809168 -0.04999736
OS 4.60190596 -0.04999736
OS 4.99796054 0.02878328
OS 5.37103828 0.18331688
OS 5.7067958 0.40766238
OS 5.99233752 0.6932041
OS 6.21668302 1.02896162
OS 6.37121662 1.40203936
OS 6.44999726 1.79809394
OS 6.44999726 2.13608158
OS 43.84000122 2.13608158
OS 43.91803764 2.15160352
OS 43.98419448 2.19580714
OS 44.0283981 2.26196398
OS 44.04392004 2.3400004
OS 44.04392004 38.33999952
OS 44.0283981 38.41803594
OS 43.98419448 38.48419278
OS 43.91803764 38.5283964
OS 43.84000122 38.54391834
OS 37.70898986 38.54391834
OS 37.66038696 38.6612511
OS 37.79233996 38.7932041
OS 38.01668546 39.12896162
OS 38.17121906 39.50203936
OS 38.2499997 39.89809394
OS 38.2499997 40.30190822
OS 38.17121906 40.6979628
OS 38.01668546 41.07104054
OS 37.79233996 41.40679806
OS 37.50679824 41.69233978
OS 37.17104072 41.91668528
OS 36.79796298 42.07121888
OS 36.4019084 42.14999952
OS 35.99809412 42.14999952
OS 35.60203954 42.07121888
OS 35.2289618 41.91668528
OS 34.89320428 41.69233978
OS 34.86683654 41.66597204
OS 34.82574188 41.67210614
OS 34.77918114 41.69384854
OS 34.74179234 41.72053378
OS 34.74112178 41.72611416
OS 34.74301154 41.741471
OS 34.74047662 41.7756975
OS 34.73976542 41.77826798
OS 34.74002196 41.78092482
OS 34.7387545 41.79359942
OS 34.73341034 41.8111178
OS 34.7319092 41.8293677
OS 34.72937174 41.83824246
OS 34.72759882 41.84168924
OS 34.72753532 41.84190514
OS 34.72752008 41.84213374
OS 34.72562016 41.84910604
OS 34.725102 41.8501449
OS 34.72433238 41.85275348
OS 34.7230827 41.87065794
OS 34.72118278 41.87763024
OS 34.71369486 41.89265434
OS 34.71339514 41.89881638
OS 34.71086022 41.9089586
OS 34.70248076 41.9267005
OS 34.70097454 41.9328473
OS 34.700718 41.93811272
OS 34.69818308 41.94825494
OS 34.69170608 41.9619684
OS 34.68874698 41.97684518
OS 34.67487096 41.99761222
OS 34.66420296 42.0201979
OS 34.66008054 42.02393678
OS 34.65877498 42.02654282
OS 34.64990022 42.0379525
OS 34.64902646 42.03870688
OS 34.64853878 42.03939014
OS 34.64844226 42.03958572
OS 34.64792664 42.0402512
OS 34.64663124 42.04206222
OS 34.64620706 42.042461
OS 34.64207956 42.04777214
OS 34.63858198 42.05348206
OS 34.63526728 42.05970506
OS 34.63456878 42.06225776
OS 34.63330132 42.06479522
OS 34.63092896 42.06785338
OS 34.63092134 42.06786608
OS 34.63085784 42.06794482
OS 34.6213811 42.0801546
OS 34.6185617 42.0861236
OS 34.61272986 42.09141442
OS 34.60278068 42.10630898
OS 34.5980893 42.1135175
OS 34.59786578 42.11367244
OS 34.59513274 42.11776184
OS 34.59237684 42.12052028
OS 34.59165294 42.12178774
OS 34.58979366 42.12323046
OS 34.5874975 42.12666708
OS 34.5817952 42.13237192
OS 34.57917138 42.13412452
OS 34.57897834 42.13446488
OS 34.57800806 42.13521672
OS 34.57611576 42.13805136
OS 34.569146 42.14502112
OS 34.56631898 42.14691088
OS 34.56556714 42.14788116
OS 34.56428698 42.14861268
OS 34.56210512 42.150792
OS 34.5535758 42.15648668
OS 34.54705308 42.16440894
OS 34.54008078 42.17011124
OS 34.53574246 42.17242264
OS 34.53244046 42.17606246
OS 34.51913086 42.18235658
OS 34.51841204 42.1830754
OS 34.5145995 42.18562302
OS 34.50827236 42.19195016
OS 34.4956638 42.20037534
OS 34.4854784 42.21160214
OS 34.46617948 42.2207182
OS 34.46555972 42.2212008
OS 34.46324324 42.22236158
OS 34.46088612 42.22522416
OS 34.45391128 42.23093154
OS 34.44650718 42.23487616
OS 34.44494762 42.23622998
OS 34.43607286 42.24129982
OS 34.43606016 42.2413049
OS 34.42558266 42.2503727
OS 34.41027154 42.25545778
OS 34.40971274 42.25583116
OS 34.40831066 42.25611056
OS 34.4038682 42.2575863
OS 34.3836879 42.26833304
OS 34.37463788 42.26921188
OS 34.37171942 42.27057332
OS 34.34474716 42.2771824
OS 34.33880102 42.28115496
OS 34.33755642 42.28140134
OS 34.33649724 42.28209222
OS 34.33015994 42.28462714
OS 34.31647696 42.28717476
OS 34.30388618 42.29312344
OS 34.29374396 42.29565836
OS 34.28086108 42.29628574
OS 34.27998732 42.29657022
OS 34.27788674 42.29756336
OS 34.2739091 42.29855904
OS 34.26859542 42.30029386
OS 34.25995688 42.30133018
OS 34.25317762 42.30453312
OS 34.25052332 42.30519606
OS 34.25004834 42.30539418
OS 34.248471 42.30570914
OS 34.24810778 42.30580058
OS 34.2479884 42.30580566
OS 34.24371358 42.30666164
OS 34.23075704 42.30667434
OS 34.2142953 42.31128698
OS 34.1730965 42.3144569
OS 34.15774728 42.31261286
OS 34.14239044 42.31450262
OS 34.10816394 42.3119677
OS 34.10559346 42.3112565
OS 34.10293916 42.31151304
OS 34.09026202 42.31024558
OS 34.07594404 42.30587932
OS 34.06099868 42.30514526
OS 34.05592884 42.30387526
OS 34.05163116 42.30184326
OS 34.04689406 42.30139114
OS 34.04564184 42.30101522
OS 34.0391369 42.30051484
OS 34.02895404 42.29766242
OS 34.02686362 42.29756082
OS 34.02179632 42.29629336
OS 34.02069904 42.2957752
OS 34.0053168 42.2950259
OS 33.99517712 42.29249098
OS 33.98281494 42.28665152
OS 33.97688658 42.28566346
OS 33.9767926 42.2856279
OS 33.97669354 42.28563044
OS 33.97086424 42.28342064
OS 33.96716854 42.28283644
OS 33.9603207 42.28031422
OS 33.96023434 42.2802939
OS 33.96009972 42.28023294
OS 33.95512132 42.27839906
OS 33.95105224 42.27590732
OS 33.94029534 42.27182808
OS 33.93191588 42.2686607
OS 33.92532204 42.2676193
OS 33.91327736 42.26318192
OS 33.90658446 42.2590849
OS 33.90246204 42.25752534
OS 33.90238838 42.25745676
OS 33.90229694 42.2574212
OS 33.89717122 42.25421572
OS 33.89131906 42.25208974
OS 33.88741508 42.24972246
OS 33.88292944 42.24883092
OS 33.8687156 42.23933132
OS 33.86525104 42.23776922
OS 33.85637628 42.23142938
OS 33.85624674 42.23129222
OS 33.84969354 42.22894272
OS 33.8433537 42.2251378
OS 33.8363179 42.21875478
OS 33.82327754 42.2108503
OS 33.82213708 42.20929836
OS 33.81261462 42.20190696
OS 33.78053442 42.18103832
OS 33.77981052 42.17998422
OS 33.77874372 42.17927048
OS 33.77367134 42.17420064
OS 33.77278488 42.17360882
OS 33.77221592 42.1732837
OS 33.77212448 42.17316686
OS 33.76984864 42.1716454
OS 33.76161142 42.1634031
OS 33.76035412 42.16152096
OS 33.75846182 42.16025604
OS 33.70205096 42.10384772
OS 33.69949318 42.10001994
OS 33.69441826 42.09494248
OS 33.679384 42.072433
OS 33.66162432 42.0520114
OS 33.6565494 42.04314172
OS 33.65612522 42.04187934
OS 33.6532347 42.03770612
OS 33.60962036 42.02262614
OS 33.56887114 42.02188954
OS 33.5171796 42.03017248
OS 33.50841406 42.03427966
OS 33.5066767 42.03570968
OS 33.5063846 42.03635738
OS 33.50511968 42.03812776
OS 33.50509682 42.03817348
OS 33.50497744 42.03832842
OS 33.50321468 42.04079476
OS 33.50265334 42.04132308
OS 33.5001616 42.04453364
OS 33.49855886 42.0469314
OS 33.47752258 42.07926052
OS 33.47646086 42.07998696
OS 33.47574966 42.08105376
OS 33.47050456 42.08629632
OS 33.46978574 42.0875587
OS 33.4688053 42.0883207
OS 33.4669003 42.09117058
OS 33.459928 42.09814288
OS 33.45802808 42.09941288
OS 33.45675808 42.1013128
OS 33.45369992 42.10437096
OS 33.44588942 42.12002752
OS 33.4360774 42.1285543
OS 33.42885872 42.13935438
OS 33.4130142 42.15519636
OS 33.40924992 42.15771096
OS 33.40657022 42.16136348
OS 33.38149534 42.176573
OS 33.37626294 42.18180794
OS 33.37282378 42.18410664
OS 33.3713836 42.18596084
OS 33.36847784 42.18761692
OS 33.36388044 42.19069286
OS 33.36181796 42.19369768
OS 33.35916112 42.19542742
OS 33.35550098 42.19987242
OS 33.34852614 42.2055798
OS 33.32725364 42.21691074
OS 33.32326584 42.22000446
OS 33.32073092 42.22127192
OS 33.3185008 42.22188152
OS 33.29512772 42.23709104
OS 33.29110436 42.23869886
OS 33.2853919 42.24114996
OS 33.28293064 42.2426257
OS 33.2764384 42.24695894
OS 33.27527508 42.24719008
OS 33.2742794 42.24783778
OS 33.26976582 42.24964626
OS 33.26875744 42.25042858
OS 33.26622252 42.25169604
OS 33.26069294 42.25320988
OS 33.25103586 42.25965386
OS 33.2485238 42.2601517
OS 33.2483333 42.26027362
OS 33.24769068 42.26072574
OS 33.24743922 42.2608375
OS 33.24636226 42.26151822
OS 33.24296374 42.26282632
OS 33.236281 42.26579558
OS 33.23411438 42.26628326
OS 33.22695158 42.27106354
OS 33.22577556 42.27129722
OS 33.22477226 42.27195
OS 33.21843496 42.27448492
OS 33.2029435 42.27737036
OS 33.18857726 42.28384228
OS 33.1866367 42.28428932
OS 33.18103854 42.2865296
OS 33.15537946 42.29130988
OS 33.13059922 42.29953948
OS 33.124267 42.30033196
OS 33.12332974 42.30064438
OS 33.12278872 42.30091362
OS 33.11581642 42.30281354
OS 33.09561072 42.30422324
OS 33.0938124 42.30445184
OS 33.06519422 42.3111422
OS 33.02716534 42.31240966
OS 33.02528574 42.31209978
OS 33.01684278 42.31379142
OS 32.06610808 42.31505888
OS 32.06540196 42.31491918
OS 32.061912 42.31566848
OS 32.02442922 42.31622982
OS 32.01896314 42.31749474
OS 32.00503632 42.31792908
OS 31.91720312 42.40934622
OS 31.91593566 42.41821844
OS 31.91241014 42.42823874
OS 31.91189452 42.43884578
OS 31.91139922 42.44082698
OS 31.91212312 42.44256942
OS 31.91339058 42.44890418
OS 31.91339312 42.45225444
OS 31.91457676 42.45538372
OS 31.91584422 42.46299102
OS 31.9156334 42.46974234
OS 31.91760698 42.47621426
OS 31.91855694 42.4857037
OS 31.91950182 42.48775348
OS 31.9202308 42.49078878
OS 31.92159732 42.49409078
OS 31.9268475 42.50174634
OS 31.93188178 42.5134913
OS 31.94197066 42.52945774
OS 31.94205448 42.52958474
OS 31.9427098 42.53009274
OS 31.94318986 42.53041278
OS 31.943421 42.53064392
OS 31.94417792 42.53123066
OS 31.97631146 42.5521501
OS 31.97701758 42.5531788
OS 31.97805136 42.55386968
OS 31.97942296 42.55524128
OS 31.980505 42.55549528
OS 31.98086568 42.55555878
OS 31.9810003 42.55561212
OS 31.9931288 42.55845692
OS 31.9948687 42.55854074
OS 31.999936 42.5598082
OS 32.01285952 42.56591182
OS 32.01513536 42.56614042
OS 32.02287474 42.56850008
OS 32.02653488 42.56867788
OS 32.03160472 42.56994534
OS 32.0353182 42.57169794
OS 32.0484881 42.57277998
OS 32.05187392 42.5729273
OS 32.05692852 42.57416428
OS 32.1142868 42.57531236
OS 32.11856924 42.5762547
OS 32.12291772 42.57566796
OS 32.12977826 42.57609722
OS 32.13388036 42.57527172
OS 32.13709854 42.57590418
OS 32.14774876 42.57590926
OS 32.14874444 42.5757848
OS 32.14920418 42.5759118
OS 34.7856683 42.57717164
OS 34.78810162 42.57765678
OS 34.79054256 42.5772326
OS 34.84251604 42.57850006
OS 34.84576216 42.57922904
OS 34.84906162 42.57876422
OS 34.88265312 42.58066414
OS 34.90132974 42.58549014
OS 34.92059564 42.5864274
OS 34.92566294 42.58769486
OS 34.93023748 42.5898564
OS 34.93096138 42.5899834
OS 34.93558164 42.59044314
OS 34.93740028 42.59099686
OS 34.94814194 42.59253102
OS 34.97640452 42.60247258
OS 35.00553324 42.60960744
OS 35.02377044 42.61811644
OS 35.03666348 42.62397876
OS 35.04274424 42.62834756
OS 35.04990196 42.6305853
OS 35.05661264 42.63424544
OS 35.06047344 42.63596248
OS 35.0628966 42.63767444
OS 35.06384402 42.63819006
OS 35.06502512 42.63917558
OS 35.06503782 42.63918574
OS 35.06599794 42.63955404
OS 35.07121764 42.64285096
OS 35.07722982 42.64426066
OS 35.08419958 42.64743058
OS 35.09021176 42.65175112
OS 35.09138524 42.65196956
OS 35.09772 42.65450448
OS 35.09877918 42.65519536
OS 35.10002378 42.65544174
OS 35.11029554 42.66230482
OS 35.11289142 42.6633767
OS 35.12049872 42.66844654
OS 35.12142836 42.66937618
OS 35.1233232 42.67032106
OS 35.12970368 42.67527152
OS 35.13213446 42.67689712
OS 35.14443822 42.6849032
OS 35.14576918 42.68540612
OS 35.14702394 42.68658468
OS 35.16441024 42.69789784
OS 35.16512652 42.69893924
OS 35.16618062 42.69964536
OS 35.17250776 42.7059725
OS 35.1763203 42.70852012
OS 35.18202514 42.71422242
OS 35.18431114 42.71764126
OS 35.18772998 42.71992726
OS 35.20864688 42.74084416
OS 35.20991942 42.74274662
OS 35.21181426 42.74401408
OS 35.22005656 42.75225384
OS 35.22132656 42.75415376
OS 35.22322648 42.75542376
OS 35.24287338 42.77507066
OS 35.24542862 42.7788959
OS 35.25047814 42.78394288
OS 35.26554034 42.80648538
OS 35.28332796 42.82694762
OS 35.2883978 42.83582238
OS 35.29072952 42.84279214
OS 35.3006152 42.85843346
OS 35.3013899 42.85959424
OS 35.30638608 42.86602552
OS 35.30765608 42.86856298
OS 35.30784404 42.86924878
OS 35.3212908 42.88936558
OS 35.32180896 42.89196908
OS 35.32262684 42.89326448
OS 35.32417116 42.8952533
OS 35.32543862 42.89778822
OS 35.32693468 42.9032543
OS 35.33334564 42.91284788
OS 35.33386634 42.91546408
OS 35.33528874 42.91771706
OS 35.33793796 42.92461316
OS 35.34072942 42.93158292
OS 35.34353612 42.9357917
OS 35.34377234 42.93698042
OS 35.34443274 42.93799642
OS 35.34696766 42.94433626
OS 35.35039158 42.96273094
OS 35.35757724 42.98002072
OS 35.3594797 42.9895254
OS 35.35948732 42.99528866
OS 35.36139486 43.0007141
OS 35.36392978 43.01846108
OS 35.36366308 43.02336836
OS 35.3706557 43.04978944
OS 35.37192316 43.07007388
OS 35.37161074 43.07238528
OS 35.37349796 43.08059964
OS 35.37476542 43.12369836
OS 35.37425488 43.12672604
OS 35.37609384 43.13683016
OS 35.37546138 43.17549404
OS 35.37497624 43.17774194
OS 35.37533692 43.18001016
OS 35.37406692 43.21296666
OS 35.37304838 43.2172237
OS 35.37355384 43.2215798
OS 35.37165392 43.24503416
OS 35.36992672 43.2511073
OS 35.37026962 43.25740904
OS 35.36900216 43.26628126
OS 35.36377484 43.28114534
OS 35.3634421 43.2844702
OS 35.36350814 43.28747756
OS 35.36267502 43.29219688
OS 35.36221528 43.29681714
OS 35.36166156 43.29863324
OS 35.3601274 43.30937998
OS 35.35018076 43.3376578
OS 35.3430459 43.36677636
OS 35.33658922 43.3806092
OS 35.33618282 43.38162774
OS 35.33594406 43.38199604
OS 35.33417114 43.38579334
OS 35.32910384 43.3926996
OS 35.3285552 43.39563838
OS 35.32601774 43.40197568
OS 35.323907 43.40521672
OS 35.32305864 43.408981
OS 35.3179888 43.42039068
OS 35.315271 43.42424132
OS 35.31402894 43.4287803
OS 35.31276148 43.43131776
OS 35.3104704 43.43426924
OS 35.30989382 43.43717246
OS 35.29040948 43.4663342
OS 35.287585 43.47102304
OS 35.28421188 43.47919676
OS 35.27914204 43.48680406
OS 35.27647504 43.48947614
OS 35.2723196 43.49637986
OS 35.26839784 43.49927546
OS 35.2663252 43.50237934
OS 35.2635058 43.50732472
OS 35.2613976 43.50896048
OS 35.26108518 43.50952182
OS 35.249358 43.52334704
OS 35.24622872 43.5302787
OS 35.2430588 43.53471608
OS 35.24127064 43.53639502
OS 35.2368866 43.54408614
OS 35.22840808 43.55066728
OS 35.22420946 43.55803074
OS 35.22235018 43.55947346
OS 35.22005402 43.56291008
OS 35.21435172 43.56861492
OS 35.21091256 43.57091362
OS 35.20947238 43.57276782
OS 35.20821254 43.57348664
OS 35.20737942 43.57431976
OS 35.19882216 43.5800373
OS 35.1922842 43.58797734
OS 35.1853119 43.59367964
OS 35.18098374 43.59598342
OS 35.1776919 43.59961562
OS 35.1643696 43.60591736
OS 35.16371682 43.60657014
OS 35.15988904 43.60913046
OS 35.15604094 43.6129811
OS 35.15079584 43.6164863
OS 35.14981286 43.61791886
OS 35.14104986 43.62361862
OS 35.13895182 43.6255922
OS 35.13038186 43.63471588
OS 35.12594448 43.6378858
OS 35.11080354 43.64472094
OS 35.1106486 43.64484032
OS 35.10811368 43.64610778
OS 35.10713578 43.64637702
OS 35.10382616 43.64787054
OS 35.0932242 43.65495206
OS 35.09057752 43.65719742
OS 35.07916784 43.66353472
OS 35.07167484 43.6659401
OS 35.06959966 43.66732694
OS 35.06950568 43.66734472
OS 35.06456538 43.67089564
OS 35.05062078 43.67723548
OS 35.04759564 43.67794414
OS 35.03968608 43.68322226
OS 35.03793094 43.68357024
OS 35.037903 43.68359056
OS 35.0360107 43.68445162
OS 35.03499216 43.68509424
OS 35.03239882 43.68609246
OS 35.0239584 43.68992786
OS 35.02200006 43.6903876
OS 35.01572626 43.6945786
OS 35.01446896 43.69482752
OS 35.01339708 43.69552602
OS 35.00705724 43.69806094
OS 34.99121272 43.70100988
OS 34.98915278 43.70194714
OS 34.98545454 43.70281582
OS 34.98373496 43.70352956
OS 34.98046344 43.70565808
OS 34.97412614 43.708193
OS 34.96867276 43.709209
OS 34.96661028 43.70962048
OS 34.96114674 43.710987
OS 34.9597726 43.71105304
OS 34.94782698 43.71669438
OS 34.9427546 43.71796184
OS 34.93454278 43.71836062
OS 34.92684404 43.72127146
OS 34.91923928 43.72253892
OS 34.91215014 43.72231794
OS 34.90536834 43.72436264
OS 34.89036202 43.72581552
OS 34.8860237 43.72643528
OS 34.88172856 43.7262016
OS 34.85761126 43.73295546
OS 34.83288944 43.73485538
OS 34.83069996 43.73459122
OS 34.82857144 43.73513986
OS 34.80575208 43.73640732
OS 34.80269392 43.73597298
OS 34.79966878 43.73665624
OS 34.75023276 43.7379237
OS 34.74764196 43.73747666
OS 34.7450664 43.73798974
OS 30.5833907 43.7392572
OS 30.53816854 43.74039004
OS 30.5156489 43.74161686
OS 30.51496056 43.74176926
OS 30.51200908 43.7436895
OS 30.50567178 43.74622442
OS 30.49413002 43.74837326
OS 30.48869696 43.75108344
OS 30.48744728 43.75210706
OS 30.483048 43.75445148
OS 30.4796952 43.75814464
OS 30.46714252 43.764073
OS 30.46548898 43.7653557
OS 30.46402594 43.76681874
OS 30.46213872 43.76924952
OS 30.4316638 43.89148956
OS 30.49166622 43.98386428
OS 30.5005359 43.9863992
OS 30.51400044 43.99331816
OS 30.51804666 43.99351374
OS 30.52818888 43.99604866
OS 30.53037582 43.9970799
OS 30.54958076 43.9976641
OS 30.5547268 43.99885028
OS 31.22703686 44.00010504
OS 31.22813414 44.00032602
OS 31.2292365 44.00012028
OS 31.32937854 44.00138774
OS 31.33342476 44.00224626
OS 31.33751416 44.00165444
OS 31.38568526 44.00418936
OS 31.39461336 44.00645758
OS 31.40380816 44.0059572
OS 31.41268038 44.00722466
OS 31.43006414 44.01333844
OS 31.44835214 44.0156473
OS 31.45405698 44.01754976
OS 31.45686114 44.01914742
OS 31.46003868 44.01965034
OS 31.46159316 44.02022438
OS 31.46646742 44.02062316
OS 31.47534472 44.02315808
OS 31.488126 44.02972398
OS 31.49032056 44.03027262
OS 31.49454712 44.03226906
OS 31.50076504 44.03334094
OS 31.50900226 44.03650832
OS 31.5113162 44.03796882
OS 31.53006902 44.0419363
OS 31.53894124 44.04573868
OS 31.54260138 44.0482482
OS 31.54799634 44.0501913
OS 31.5482859 44.05036656
OS 31.54982768 44.0507882
OS 31.55236514 44.05205566
OS 31.5535437 44.05297006
OS 31.55691428 44.05364062
OS 31.5826902 44.07085674
OS 31.59020098 44.07354914
OS 31.59653574 44.07735152
OS 31.60329214 44.08348308
OS 31.61615978 44.09123008
OS 31.61741962 44.09293442
OS 31.62725704 44.10056966
OS 31.65936772 44.1214637
OS 31.660084 44.1225051
OS 31.6611381 44.12321122
OS 31.66620032 44.12827344
OS 31.67001286 44.13082106
OS 31.73339602 44.19420168
OS 31.73466856 44.19610414
OS 31.7365634 44.1973716
OS 31.73909832 44.19990398
OS 31.74042674 44.2018928
OS 31.74578868 44.20605332
OS 31.74581154 44.20609396
OS 31.74584202 44.20611682
OS 31.75127254 44.21565198
OS 31.75424434 44.21781352
OS 31.7588646 44.2253624
OS 31.76717294 44.23316782
OS 31.77034286 44.2376052
OS 31.77608834 44.25033568
OS 31.78123438 44.25695238
OS 31.786068 44.26659676
OS 31.79618736 44.28260892
OS 31.80264658 44.2909325
OS 31.80391404 44.29346742
OS 31.8042417 44.29466376
OS 31.81689344 44.31359692
OS 31.89909292 44.34549678
OS 31.93870676 44.35338602
OS 31.95042378 44.34898166
OS 31.9921636 44.32563906
OS 32.00812496 44.30175036
OS 32.00831038 44.30107472
OS 32.00957784 44.29853726
OS 32.01327608 44.29377222
OS 32.02448764 44.27515148
OS 32.02559254 44.27307376
OS 32.02799538 44.26707174
OS 32.02866848 44.26603796
OS 32.02890724 44.264834
OS 32.0320416 44.26014262
OS 32.0325877 44.25873292
OS 32.04145992 44.24478578
OS 32.04423868 44.24188002
OS 32.04435552 44.24170222
OS 32.04776928 44.23447846
OS 32.04882846 44.23152444
OS 32.0504058 44.22889808
OS 32.0509392 44.22776778
OS 32.0512567 44.22747822
OS 32.05263338 44.22518714
OS 32.06190946 44.21496872
OS 32.0713989 44.20038912
OS 32.0724149 44.19969316
OS 32.07309816 44.19866954
OS 32.07421068 44.19755448
OS 32.0766313 44.19331522
OS 32.08017968 44.1905644
OS 32.08321244 44.18602034
OS 32.08637982 44.18285042
OS 32.08977072 44.1805822
OS 32.09041588 44.18008182
OS 32.09331148 44.17718622
OS 32.09584894 44.17338384
OS 32.09774886 44.17147884
OS 32.10044634 44.16967544
OS 32.10066478 44.16928936
OS 32.10308794 44.16740976
OS 32.1047999 44.16569526
OS 32.1073526 44.1618751
OS 32.11052252 44.15870518
OS 32.11434776 44.15614994
OS 32.11605718 44.15443798
OS 32.11793678 44.15201736
OS 32.11827968 44.15182178
OS 32.12003228 44.14919796
OS 32.1219322 44.1472955
OS 32.12714174 44.1438157
OS 32.13061392 44.13934022
OS 32.13483032 44.13693738
OS 32.13655498 44.13521272
OS 32.13871906 44.13376746
OS 32.14022528 44.13163386
OS 32.15484552 44.12239588
OS 32.16117774 44.11664786
OS 32.16675812 44.11330014
OS 32.16754298 44.112434
OS 32.17629582 44.10829888
OS 32.17872406 44.10516706
OS 32.18357546 44.10239846
OS 32.18723814 44.09816936
OS 32.19294552 44.09373452
OS 32.21489874 44.08273632
OS 32.22241206 44.0773693
OS 32.2319523 44.07306654
OS 32.24838102 44.06309958
OS 32.2547234 44.06079326
OS 32.25770028 44.05885524
OS 32.26285394 44.05515192
OS 32.26463702 44.05434166
OS 32.26518312 44.05398606
OS 32.26714654 44.0532012
OS 32.2682235 44.05271098
OS 32.268922 44.0523122
OS 32.2691125 44.0522487
OS 32.26926998 44.05211154
OS 32.2702809 44.05177626
OS 32.27680108 44.04881208
OS 32.28497734 44.04689438
OS 32.30742586 44.03943694
OS 32.31755284 44.03605366
OS 32.32696354 44.0302142
OS 32.33710576 44.02640928
OS 32.35281058 44.02383372
OS 32.35580016 44.02194396
OS 32.35885578 44.02076794
OS 32.36069982 44.01980274
OS 32.36352938 44.01896962
OS 32.36403992 44.01877404
OS 32.36442092 44.018708
OS 32.36828426 44.01757262
OS 32.36877194 44.01736942
OS 32.36939932 44.01724496
OS 32.37055502 44.0169046
OS 32.37277244 44.01563968
OS 32.37657482 44.01437222
OS 32.40532254 44.01074764
OS 32.433514 44.00404712
OS 32.4677405 44.00277966
OS 32.469709 44.00309716
OS 32.47816212 44.00137504
OS 32.75704396 44.00010758
OS 32.75750624 44.00019648
OS 32.75797106 44.00010504
OS 32.86952278 44.00010504
OS 32.87080802 44.00036158
OS 32.87210342 44.00012028
OS 32.972248 44.00138774
OS 32.97629422 44.00224626
OS 32.98038362 44.00165444
OS 33.02855472 44.00418936
OS 33.03747266 44.00645504
OS 33.04667 44.00595466
OS 33.05554476 44.00722212
OS 33.07293614 44.01333844
OS 33.0735051 44.0134121
OS 33.07437886 44.01337654
OS 33.07891022 44.01409282
OS 33.09122414 44.0156473
OS 33.09692898 44.01754976
OS 33.1002513 44.0194446
OS 33.10402066 44.02006182
OS 33.1141578 44.0238642
OS 33.11844024 44.0265185
OS 33.14187936 44.03240368
OS 33.1637386 44.04275672
OS 33.17291308 44.04683342
OS 33.18039846 44.05211662
OS 33.18911066 44.05491316
OS 33.19336516 44.05727536
OS 33.19985486 44.06022684
OS 33.20428716 44.063412
OS 33.20904458 44.06641682
OS 33.21505676 44.06782652
OS 33.22202652 44.07099644
OS 33.22803108 44.07530936
OS 33.22918424 44.07552526
OS 33.23552408 44.07806018
OS 33.23661374 44.07876884
OS 33.23789136 44.07902284
OS 33.24819106 44.08590878
OS 33.25075646 44.08696796
OS 33.25736554 44.09137486
OS 33.25742142 44.0913901
OS 33.2599538 44.09265756
OS 33.2645258 44.09620848
OS 33.2648814 44.09638628
OS 33.26498046 44.09646248
OS 33.26509984 44.0964955
OS 33.2714346 44.10142056
OS 33.3022194 44.12144592
OS 33.302956 44.1225178
OS 33.30403804 44.1232417
OS 33.30906978 44.12827598
OS 33.31287978 44.13082106
OS 33.3154147 44.13335344
OS 33.31668724 44.13525844
OS 33.31858462 44.1365259
OS 33.32529276 44.1432315
OS 33.32775656 44.14514412
OS 33.32782006 44.14525334
OS 33.32791658 44.14532954
OS 33.32861254 44.14655382
OS 33.37499548 44.19293422
OS 33.37809682 44.1975748
OS 33.38738814 44.20478586
OS 33.38978336 44.20898702
OS 33.39081714 44.2100208
OS 33.39106098 44.21038402
OS 33.394269 44.21316024
OS 33.396682 44.21625904
OS 33.3970503 44.21653082
OS 33.3976091 44.21745284
OS 33.39870638 44.21886254
OS 33.3998697 44.22118156
OS 33.41529766 44.24662982
OS 33.4201643 44.25290108
OS 33.42143176 44.255436
OS 33.42160956 44.25608878
OS 33.42660574 44.26356146
OS 33.4350995 44.27333284
OS 33.44016934 44.2822076
OS 33.44110406 44.2850016
OS 33.44809414 44.29279686
OS 33.45104054 44.30117124
OS 33.45849798 44.312332
OS 33.45874436 44.3135766
OS 33.45943524 44.31463578
OS 33.46197016 44.32097308
OS 33.46484036 44.3363858
OS 33.46577254 44.33856004
OS 33.46594018 44.33934998
OS 33.46990766 44.3452885
OS 33.47015658 44.3465458
OS 33.47085508 44.34761768
OS 33.47339 44.35395752
OS 33.473644 44.35532404
OS 33.47438568 44.35649752
OS 33.47705268 44.36343426
OS 33.47908214 44.36850918
OS 33.48062392 44.37678958
OS 33.49391574 44.40492516
OS 33.49645066 44.41506738
OS 33.4966564 44.41927362
OS 33.49720758 44.42073158
OS 33.4970628 44.4254509
OS 33.49731172 44.42662692
OS 33.49788322 44.42824744
OS 33.5055464 44.4466853
OS 33.50808386 44.45936244
OS 33.50809148 44.46513332
OS 33.51000156 44.47056892
OS 33.51190148 44.48387852
OS 33.51145444 44.49205224
OS 33.51355248 44.4999745
OS 33.51406048 44.50812282
OS 33.51442624 44.50915914
OS 33.51539398 44.51592316
OS 33.52411126 44.5434212
OS 33.52537872 44.55483088
OS 33.525079 44.55833354
OS 33.52524156 44.55903204
OS 33.52477166 44.5618997
OS 33.5239614 44.57132564
OS 33.52529236 44.57722606
OS 33.522031 44.59612112
OS 33.52053748 44.62680432
OS 33.51927002 44.63187162
OS 33.51864772 44.63318988
OS 33.51856898 44.63410428
OS 33.51459896 44.64175984
OS 33.5143729 44.64223736
OS 33.51398682 44.64609562
OS 33.5129632 44.6634743
OS 33.51019968 44.67406864
OS 33.51054258 44.6850135
OS 33.50987202 44.68903686
OS 33.50843184 44.7000757
OS 33.50093122 44.72225498
OS 33.50048164 44.72539188
OS 33.49763176 44.7334894
OS 33.49690786 44.73657804
OS 33.49645066 44.7459608
OS 33.49391574 44.75610048
OS 33.4855439 44.7738246
OS 33.48403514 44.7799841
OS 33.4837786 44.78524698
OS 33.48124368 44.7953892
OS 33.47476668 44.80910266
OS 33.47180758 44.82397944
OS 33.45792902 44.84474902
OS 33.45575224 44.84935912
OS 33.45558714 44.8499611
OS 33.45431968 44.85249602
OS 33.45419522 44.85265604
OS 33.44726356 44.86733216
OS 33.4442816 44.87003726
OS 33.43922192 44.87712386
OS 33.43415462 44.88188636
OS 33.43285922 44.88475656
OS 33.431607 44.88650916
OS 33.43157398 44.8865752
OS 33.43139872 44.88680126
OS 33.4296893 44.88919394
OS 33.4291432 44.88970702
OS 33.42526462 44.89470574
OS 33.42366442 44.8973194
OS 33.42362124 44.89753784
OS 33.4225519 44.89913804
OS 33.4216121 44.9006722
OS 33.4139794 44.91500288
OS 33.40946582 44.92051976
OS 33.40914832 44.92103792
OS 33.40888416 44.92123096
OS 33.40827456 44.92197518
OS 33.40607492 44.92378366
OS 33.4052672 44.92499524
OS 33.40383718 44.92768002
OS 33.40261036 44.92918116
OS 33.40140386 44.93116998
OS 33.39795454 44.93952404
OS 33.3928847 44.94713134
OS 33.38992814 44.95009298
OS 33.385633 44.95717958
OS 33.38194238 44.95988722
OS 33.3801212 44.96261518
OS 33.37724846 44.967652
OS 33.3695675 44.97361338
OS 33.36895536 44.97468526
OS 33.36712402 44.97610512
OS 33.36485326 44.97950364
OS 33.36232088 44.98203856
OS 33.36041588 44.9833111
OS 33.35914842 44.98520848
OS 33.35661604 44.9877434
OS 33.35471358 44.98901594
OS 33.35344612 44.99091078
OS 33.34672528 44.99763416
OS 33.34482536 45.00008272
OS 33.3447898 45.00010304
OS 33.3447644 45.00013606
OS 33.34350456 45.00085488
OS 33.33823406 45.00612538
OS 33.33632906 45.00739792
OS 33.3350616 45.0092953
OS 33.33252922 45.01183022
OS 33.32788864 45.01493156
OS 33.32067758 45.02422288
OS 33.31574744 45.02703212
OS 33.31254958 45.0291708
OS 33.31237686 45.02942226
OS 33.31108654 45.03026046
OS 33.30560268 45.03609992
OS 33.3011653 45.03926984
OS 33.28966672 45.0444616
OS 33.28947114 45.04459114
OS 33.27505664 45.05576714
OS 33.27468326 45.05617608
OS 33.2718791 45.05823348
OS 33.26361394 45.0646419
OS 33.26107648 45.06590936
OS 33.25666958 45.06711332
OS 33.25527258 45.0677661
OS 33.24188424 45.0799073
OS 33.23554186 45.08370968
OS 33.22645374 45.08696342
OS 33.22619974 45.08720726
OS 33.21922744 45.09164464
OS 33.21869912 45.09185038
OS 33.21505676 45.09446658
OS 33.20110962 45.10080642
OS 33.19519142 45.1021958
OS 33.18521684 45.108495
OS 33.18434308 45.10911222
OS 33.18399764 45.10926716
OS 33.18292576 45.1099428
OS 33.17958058 45.11123058
OS 33.1729334 45.1141846
OS 33.17176754 45.11444876
OS 33.16623034 45.118147
OS 33.16363954 45.11866262
OS 33.16141196 45.12006978
OS 33.1531722 45.1232397
OS 33.14076938 45.12538092
OS 33.12938764 45.13075556
OS 33.12508742 45.13182998
OS 33.1220572 45.13304156
OS 33.10842502 45.13557902
OS 33.09589012 45.14150484
OS 33.09081774 45.14277484
OS 33.07714238 45.1434454
OS 33.07005578 45.14546978
OS 33.0697205 45.14549772
OS 33.06225544 45.1478015
OS 33.04475738 45.14960998
OS 33.01788164 45.15672452
OS 32.99760228 45.15799198
OS 32.9943079 45.15754748
OS 32.98478544 45.15962266
OS 32.91506244 45.16089012
OS 32.9143995 45.16077074
OS 32.90719606 45.1621906
OE
OB 14.42216826 44.87499788 H
OS 14.11783054 44.87499788
OS 13.8193399 44.81562538
OS 13.53816952 44.69915876
OS 13.28511948 44.53007858
OS 13.06992052 44.31487962
OS 12.90084034 44.06182958
OS 12.8147318 43.85394836
OS 12.677267 43.85394836
OS 12.59115846 44.06182958
OS 12.42207828 44.31487962
OS 12.20687932 44.53007858
OS 11.95382928 44.69915876
OS 11.6726589 44.81562538
OS 11.37416826 44.87499788
OS 11.06983054 44.87499788
OS 10.7713399 44.81562538
OS 10.49016952 44.69915876
OS 10.23711948 44.53007858
OS 10.02192052 44.31487962
OS 9.85284034 44.06182958
OS 9.73637372 43.7806592
OS 9.67700122 43.48216856
OS 9.67700122 43.17783084
OS 9.73637372 42.8793402
OS 9.85284034 42.59816982
OS 10.02192052 42.34511978
OS 10.23711948 42.12992082
OS 10.49016952 41.96084064
OS 10.7713399 41.84437402
OS 11.06983054 41.78500152
OS 11.37416826 41.78500152
OS 11.6726589 41.84437402
OS 11.95382928 41.96084064
OS 12.20687932 42.12992082
OS 12.42207828 42.34511978
OS 12.59115846 42.59816982
OS 12.677267 42.80605104
OS 12.8147318 42.80605104
OS 12.90084034 42.59816982
OS 13.06992052 42.34511978
OS 13.28511948 42.12992082
OS 13.53816952 41.96084064
OS 13.8193399 41.84437402
OS 14.11783054 41.78500152
OS 14.42216826 41.78500152
OS 14.7206589 41.84437402
OS 15.00182928 41.96084064
OS 15.25487932 42.12992082
OS 15.47007828 42.34511978
OS 15.63915846 42.59816982
OS 15.75562508 42.8793402
OS 15.81499758 43.17783084
OS 15.81499758 43.48216856
OS 15.75562508 43.7806592
OS 15.63915846 44.06182958
OS 15.47007828 44.31487962
OS 15.25487932 44.53007858
OS 15.00182928 44.69915876
OS 14.7206589 44.81562538
OS 14.42216826 44.87499788
OE
OB 43.12499884 44.7353563 H
OS 42.81173556 44.69411432
OS 42.51982098 44.57320016
OS 42.26914838 44.38085104
OS 42.07679926 44.13017844
OS 41.9558851 43.83826386
OS 41.91464312 43.52500058
OS 41.9558851 43.2117373
OS 42.07679926 42.91982272
OS 42.26914838 42.66915012
OS 42.51982098 42.476801
OS 42.81173556 42.35588684
OS 43.12499884 42.31464486
OS 43.43826212 42.35588684
OS 43.7301767 42.476801
OS 43.9808493 42.66915012
OS 44.17319842 42.91982272
OS 44.29411258 43.2117373
OS 44.33535456 43.52500058
OS 44.29411258 43.83826386
OS 44.17319842 44.13017844
OS 43.9808493 44.38085104
OS 43.7301767 44.57320016
OS 43.43826212 44.69411432
OS 43.12499884 44.7353563
OE
OB -2.37499906 44.7353563 H
OS -2.68826234 44.69411432
OS -2.98017692 44.57320016
OS -3.23084952 44.38085104
OS -3.42319864 44.13017844
OS -3.5441128 43.83826386
OS -3.58535478 43.52500058
OS -3.5441128 43.2117373
OS -3.42319864 42.91982272
OS -3.23084952 42.66915012
OS -2.98017692 42.476801
OS -2.68826234 42.35588684
OS -2.37499906 42.31464486
OS -2.06173578 42.35588684
OS -1.7698212 42.476801
OS -1.5191486 42.66915012
OS -1.32679948 42.91982272
OS -1.20588532 43.2117373
OS -1.16464334 43.52500058
OS -1.20588532 43.83826386
OS -1.32679948 44.13017844
OS -1.5191486 44.38085104
OS -1.7698212 44.57320016
OS -2.06173578 44.69411432
OS -2.37499906 44.7353563
OE
OB 8.3379056 44.57499848 H
OS 8.0100932 44.57499848
OS 7.69344664 44.49015486
OS 7.40955084 44.32624866
OS 7.17775044 44.09444826
OS 7.01384424 43.81055246
OS 6.92900062 43.4939059
OS 6.92900062 43.1660935
OS 7.01384424 42.84944694
OS 7.17775044 42.56555114
OS 7.40955084 42.33375074
OS 7.69344664 42.16984454
OS 8.0100932 42.08500092
OS 8.3379056 42.08500092
OS 8.65455216 42.16984454
OS 8.93844796 42.33375074
OS 9.17024836 42.56555114
OS 9.33415456 42.84944694
OS 9.41899818 43.1660935
OS 9.41899818 43.4939059
OS 9.33415456 43.81055246
OS 9.17024836 44.09444826
OS 8.93844796 44.32624866
OS 8.65455216 44.49015486
OS 8.3379056 44.57499848
OE
OB 5.2899056 44.57499848 H
OS 4.9620932 44.57499848
OS 4.64544664 44.49015486
OS 4.36155084 44.32624866
OS 4.12975044 44.09444826
OS 3.96584424 43.81055246
OS 3.88100062 43.4939059
OS 3.88100062 43.1660935
OS 3.96584424 42.84944694
OS 4.12975044 42.56555114
OS 4.36155084 42.33375074
OS 4.64544664 42.16984454
OS 4.9620932 42.08500092
OS 5.2899056 42.08500092
OS 5.60655216 42.16984454
OS 5.89044796 42.33375074
OS 6.12224836 42.56555114
OS 6.28615456 42.84944694
OS 6.37099818 43.1660935
OS 6.37099818 43.4939059
OS 6.28615456 43.81055246
OS 6.12224836 44.09444826
OS 5.89044796 44.32624866
OS 5.60655216 44.49015486
OS 5.2899056 44.57499848
OE
OB 2.2419056 44.57499848 H
OS 1.9140932 44.57499848
OS 1.59744664 44.49015486
OS 1.31355084 44.32624866
OS 1.08175044 44.09444826
OS 0.91784424 43.81055246
OS 0.83300062 43.4939059
OS 0.83300062 43.1660935
OS 0.91784424 42.84944694
OS 1.08175044 42.56555114
OS 1.31355084 42.33375074
OS 1.59744664 42.16984454
OS 1.9140932 42.08500092
OS 2.2419056 42.08500092
OS 2.55855216 42.16984454
OS 2.84244796 42.33375074
OS 3.07424836 42.56555114
OS 3.23815456 42.84944694
OS 3.32299818 43.1660935
OS 3.32299818 43.4939059
OS 3.23815456 43.81055246
OS 3.07424836 44.09444826
OS 2.84244796 44.32624866
OS 2.55855216 44.49015486
OS 2.2419056 44.57499848
OE
OB 0.17101566 41.93899918 H
OS 0.12699492 41.93899918
OS 0.12699492 40.76701016
OS 1.29899918 40.76701016
OS 1.29899918 40.81101566
OS 1.2104751 41.141396
OS 1.0394569 41.43760318
OS 0.79760318 41.6794569
OS 0.501396 41.8504751
OS 0.17101566 41.93899918
OE
OB -0.12700508 41.93899918 H
OS -0.17101566 41.93899918
OS -0.501396 41.8504751
OS -0.79760318 41.6794569
OS -1.0394569 41.43760318
OS -1.2104751 41.141396
OS -1.29899918 40.81101566
OS -1.29899918 40.76701016
OS -0.12700508 40.76701016
OS -0.12700508 41.93899918
OE
OB 1.29899918 40.51301016 H
OS 0.12699492 40.51301016
OS 0.12699492 39.34100082
OS 0.17101566 39.34100082
OS 0.501396 39.4295249
OS 0.79760318 39.6005431
OS 1.0394569 39.84239682
OS 1.2104751 40.138604
OS 1.29899918 40.46898434
OS 1.29899918 40.51301016
OE
OB -0.12700508 40.51301016 H
OS -1.29899918 40.51301016
OS -1.29899918 40.46898434
OS -1.2104751 40.138604
OS -1.0394569 39.84239682
OS -0.79760318 39.6005431
OS -0.501396 39.4295249
OS -0.17101566 39.34100082
OS -0.12700508 39.34100082
OS -0.12700508 40.51301016
OE
OB 20.46429994 44.98999892 H
OS 20.01570038 44.98999892
OS 19.57262278 44.9198238
OS 19.14597898 44.78119822
OS 18.74627442 44.57753848
OS 18.38334906 44.31385854
OS 18.06614116 43.99665064
OS 17.80246122 43.63372528
OS 17.59880148 43.23402072
OS 17.4601759 42.80737692
OS 17.39000078 42.36429932
OS 17.39000078 41.91569976
OS 17.4601759 41.47262216
OS 17.59880148 41.04597836
OS 17.80246122 40.6462738
OS 18.06614116 40.28334844
OS 18.38334906 39.96614054
OS 18.74627442 39.7024606
OS 19.14597898 39.49880086
OS 19.57262278 39.36017528
OS 20.01570038 39.29000016
OS 20.46429994 39.29000016
OS 20.90737754 39.36017528
OS 21.33402134 39.49880086
OS 21.7337259 39.7024606
OS 22.09665126 39.96614054
OS 22.41385916 40.28334844
OS 22.6775391 40.6462738
OS 22.88119884 41.04597836
OS 23.01982442 41.47262216
OS 23.08999954 41.91569976
OS 23.08999954 42.36429932
OS 23.01982442 42.80737692
OS 22.88119884 43.23402072
OS 22.6775391 43.63372528
OS 22.41385916 43.99665064
OS 22.09665126 44.31385854
OS 21.7337259 44.57753848
OS 21.33402134 44.78119822
OS 20.90737754 44.9198238
OS 20.46429994 44.98999892
OE
OB 40.79216886 42.18499818 H
OS 40.48783114 42.18499818
OS 40.1893405 42.12562568
OS 39.90817012 42.00915906
OS 39.65512008 41.84007888
OS 39.43992112 41.62487992
OS 39.27084094 41.37182988
OS 39.15437432 41.0906595
OS 39.09500182 40.79216886
OS 39.09500182 40.48783114
OS 39.15437432 40.1893405
OS 39.27084094 39.90817012
OS 39.43992112 39.65512008
OS 39.65512008 39.43992112
OS 39.90817012 39.27084094
OS 40.1893405 39.15437432
OS 40.48783114 39.09500182
OS 40.79216886 39.09500182
OS 41.0906595 39.15437432
OS 41.37182988 39.27084094
OS 41.62487992 39.43992112
OS 41.84007888 39.65512008
OS 42.00915906 39.90817012
OS 42.12562568 40.1893405
OS 42.18499818 40.48783114
OS 42.18499818 40.79216886
OS 42.12562568 41.0906595
OS 42.00915906 41.37182988
OS 41.84007888 41.62487992
OS 41.62487992 41.84007888
OS 41.37182988 42.00915906
OS 41.0906595 42.12562568
OS 40.79216886 42.18499818
OE
OB 40.8039062 1.24499878 H
OS 40.4760938 1.24499878
OS 40.15944724 1.16015516
OS 39.87555144 0.99624896
OS 39.64375104 0.76444856
OS 39.47984484 0.48055276
OS 39.39500122 0.1639062
OS 39.39500122 -0.1639062
OS 39.47984484 -0.48055276
OS 39.64375104 -0.76444856
OS 39.87555144 -0.99624896
OS 40.15944724 -1.16015516
OS 40.4760938 -1.24499878
OS 40.8039062 -1.24499878
OS 41.12055276 -1.16015516
OS 41.40444856 -0.99624896
OS 41.63624896 -0.76444856
OS 41.80015516 -0.48055276
OS 41.88499878 -0.1639062
OS 41.88499878 0.1639062
OS 41.80015516 0.48055276
OS 41.63624896 0.76444856
OS 41.40444856 0.99624896
OS 41.12055276 1.16015516
OS 40.8039062 1.24499878
OE
OB 0.1639062 1.24499878 H
OS -0.1639062 1.24499878
OS -0.48055276 1.16015516
OS -0.76444856 0.99624896
OS -0.99624896 0.76444856
OS -1.16015516 0.48055276
OS -1.24499878 0.1639062
OS -1.24499878 -0.1639062
OS -1.16015516 -0.48055276
OS -0.99624896 -0.76444856
OS -0.76444856 -0.99624896
OS -0.48055276 -1.16015516
OS -0.1639062 -1.24499878
OS 0.1639062 -1.24499878
OS 0.48055276 -1.16015516
OS 0.76444856 -0.99624896
OS 0.99624896 -0.76444856
OS 1.16015516 -0.48055276
OS 1.24499878 -0.1639062
OS 1.24499878 0.1639062
OS 1.16015516 0.48055276
OS 0.99624896 0.76444856
OS 0.76444856 0.99624896
OS 0.48055276 1.16015516
OS 0.1639062 1.24499878
OE
OB 35.70190726 1.0499979 H
OS 35.29809298 1.0499979
OS 34.9020384 0.97121726
OS 34.52896066 0.81668366
OS 34.19320314 0.59233816
OS 33.90766142 0.30679644
OS 33.68331592 -0.02896108
OS 33.52878232 -0.40203882
OS 33.45000168 -0.7980934
OS 33.45000168 -1.20190768
OS 33.52878232 -1.59796226
OS 33.68331592 -1.97104
OS 33.90766142 -2.30679752
OS 34.19320314 -2.59233924
OS 34.52896066 -2.81668474
OS 34.9020384 -2.97121834
OS 35.29809298 -3.04999898
OS 35.70190726 -3.04999898
OS 36.09796184 -2.97121834
OS 36.47103958 -2.81668474
OS 36.8067971 -2.59233924
OS 37.09233882 -2.30679752
OS 37.31668432 -1.97104
OS 37.47121792 -1.59796226
OS 37.54999856 -1.20190768
OS 37.54999856 -0.7980934
OS 37.47121792 -0.40203882
OS 37.31668432 -0.02896108
OS 37.09233882 0.30679644
OS 36.8067971 0.59233816
OS 36.47103958 0.81668366
OS 36.09796184 0.97121726
OS 35.70190726 1.0499979
OE
OB -2.20000068 -1.48964396 H
OS -2.51326396 -1.53088594
OS -2.80517854 -1.6518001
OS -3.05585114 -1.84414922
OS -3.24820026 -2.09482182
OS -3.36911442 -2.3867364
OS -3.4103564 -2.69999968
OS -3.36911442 -3.01326296
OS -3.24820026 -3.30517754
OS -3.05585114 -3.55585014
OS -2.80517854 -3.74819926
OS -2.51326396 -3.86911342
OS -2.20000068 -3.9103554
OS -1.8867374 -3.86911342
OS -1.59482282 -3.74819926
OS -1.34415022 -3.55585014
OS -1.1518011 -3.30517754
OS -1.03088694 -3.01326296
OS -0.98964496 -2.69999968
OS -1.03088694 -2.3867364
OS -1.1518011 -2.09482182
OS -1.34415022 -1.84414922
OS -1.59482282 -1.6518001
OS -1.8867374 -1.53088594
OS -2.20000068 -1.48964396
OE
OB 20.66429954 1.58999936 H
OS 20.21569998 1.58999936
OS 19.77262238 1.51982424
OS 19.34597858 1.38119866
OS 18.94627402 1.17753892
OS 18.58334866 0.91385898
OS 18.26614076 0.59665108
OS 18.00246082 0.23372572
OS 17.79880108 -0.16597884
OS 17.6601755 -0.59262264
OS 17.59000038 -1.03570024
OS 17.59000038 -1.4842998
OS 17.6601755 -1.9273774
OS 17.79880108 -2.3540212
OS 18.00246082 -2.75372576
OS 18.26614076 -3.11665112
OS 18.58334866 -3.43385902
OS 18.94627402 -3.69753896
OS 19.34597858 -3.9011987
OS 19.77262238 -4.03982428
OS 20.21569998 -4.1099994
OS 20.66429954 -4.1099994
OS 21.10737714 -4.03982428
OS 21.53402094 -3.9011987
OS 21.9337255 -3.69753896
OS 22.29665086 -3.43385902
OS 22.61385876 -3.11665112
OS 22.8775387 -2.75372576
OS 23.08119844 -2.3540212
OS 23.21982402 -1.9273774
OS 23.28999914 -1.4842998
OS 23.28999914 -1.03570024
OS 23.21982402 -0.59262264
OS 23.08119844 -0.16597884
OS 22.8775387 0.23372572
OS 22.61385876 0.59665108
OS 22.29665086 0.91385898
OS 21.9337255 1.17753892
OS 21.53402094 1.38119866
OS 21.10737714 1.51982424
OS 20.66429954 1.58999936
OE
SE
S P 0
OB -2.56054098 -38.95999828 I
OS -2.63912858 -38.95999828
OS -2.63912858 -38.32020276
OS -2.56054098 -38.32020276
OS -2.56054098 -38.95999828
OE
OB -2.22215202 -38.48662356 I
OS -2.20828362 -38.48754812
OS -2.1925661 -38.48939724
OS -2.17684858 -38.49217092
OS -2.16113106 -38.49586916
OS -2.1463381 -38.50049196
OS -2.14448898 -38.50141652
OS -2.13986618 -38.50326564
OS -2.13339426 -38.50603932
OS -2.12507322 -38.50973756
OS -2.11582762 -38.51528492
OS -2.10658202 -38.52083228
OS -2.09826098 -38.52822876
OS -2.0908645 -38.53562524
OS -2.08993994 -38.5365498
OS -2.08809082 -38.53932348
OS -2.08531714 -38.54394628
OS -2.0816189 -38.54949364
OS -2.0769961 -38.55781468
OS -2.07329786 -38.56613572
OS -2.06959962 -38.57630588
OS -2.06682594 -38.58832516
OS -2.06682594 -38.58924972
OS -2.06590138 -38.5920234
OS -2.06497682 -38.59757076
OS -2.06405226 -38.60496724
OS -2.06405226 -38.6151374
OS -2.0631277 -38.62715668
OS -2.06220314 -38.6428742
OS -2.06220314 -38.66044084
OS -2.06220314 -38.76584068
OS -2.06220314 -38.76676524
OS -2.06220314 -38.77046348
OS -2.06220314 -38.77601084
OS -2.06220314 -38.78340732
OS -2.06220314 -38.79172836
OS -2.06220314 -38.80189852
OS -2.06127858 -38.82408796
OS -2.06127858 -38.84720196
OS -2.06035402 -38.87031596
OS -2.05942946 -38.88048612
OS -2.05942946 -38.88973172
OS -2.0585049 -38.89805276
OS -2.05758034 -38.90452468
OS -2.05758034 -38.90544924
OS -2.05665578 -38.90914748
OS -2.05573122 -38.91469484
OS -2.05295754 -38.92209132
OS -2.05110842 -38.93041236
OS -2.04741018 -38.93965796
OS -2.04278738 -38.94982812
OS -2.03816458 -38.95999828
OS -2.12045042 -38.95999828
OS -2.12137498 -38.95907372
OS -2.12229954 -38.95537548
OS -2.12414866 -38.95075268
OS -2.12692234 -38.9433562
OS -2.12969602 -38.93503516
OS -2.13154514 -38.924865
OS -2.13339426 -38.91377028
OS -2.13524338 -38.901751
OS -2.13616794 -38.901751
OS -2.1370925 -38.90360012
OS -2.14263986 -38.90822292
OS -2.1509609 -38.91469484
OS -2.16205562 -38.92301588
OS -2.17592402 -38.93133692
OS -2.18979242 -38.94058252
OS -2.20458538 -38.94890356
OS -2.2203029 -38.95537548
OS -2.22215202 -38.95630004
OS -2.22769938 -38.9572246
OS -2.23602042 -38.95999828
OS -2.24619058 -38.96277196
OS -2.25913442 -38.96554564
OS -2.27392738 -38.96739476
OS -2.29056946 -38.96924388
OS -2.30721154 -38.97016844
OS -2.31460802 -38.97016844
OS -2.32015538 -38.96924388
OS -2.3266273 -38.96924388
OS -2.33402378 -38.96831932
OS -2.35066586 -38.96554564
OS -2.36915706 -38.96092284
OS -2.38949738 -38.95445092
OS -2.40798858 -38.94520532
OS -2.42463066 -38.93318604
OS -2.42647978 -38.93133692
OS -2.43110258 -38.92671412
OS -2.4375745 -38.91839308
OS -2.44497098 -38.90729836
OS -2.45236746 -38.89342996
OS -2.45883938 -38.87771244
OS -2.46346218 -38.85829668
OS -2.46438674 -38.84905108
OS -2.4653113 -38.83795636
OS -2.4653113 -38.83610724
OS -2.4653113 -38.832409
OS -2.46438674 -38.82593708
OS -2.46346218 -38.81761604
OS -2.46161306 -38.80744588
OS -2.45883938 -38.79727572
OS -2.45514114 -38.786181
OS -2.45051834 -38.77601084
OS -2.44959378 -38.77508628
OS -2.44774466 -38.77138804
OS -2.44404642 -38.76584068
OS -2.43942362 -38.75936876
OS -2.43387626 -38.75197228
OS -2.42647978 -38.7445758
OS -2.4190833 -38.73717932
OS -2.4098377 -38.7307074
OS -2.40891314 -38.72978284
OS -2.4052149 -38.72793372
OS -2.4005921 -38.72423548
OS -2.39319562 -38.72053724
OS -2.38487458 -38.716839
OS -2.37470442 -38.7122162
OS -2.36453426 -38.70851796
OS -2.35251498 -38.70481972
OS -2.35159042 -38.70481972
OS -2.34789218 -38.70389516
OS -2.34234482 -38.70204604
OS -2.33494834 -38.70112148
OS -2.32570274 -38.69927236
OS -2.31368346 -38.69742324
OS -2.29981506 -38.69464956
OS -2.28317298 -38.69280044
OS -2.28224842 -38.69280044
OS -2.27855018 -38.69187588
OS -2.27392738 -38.69187588
OS -2.26745546 -38.69095132
OS -2.26005898 -38.69002676
OS -2.25081338 -38.68817764
OS -2.24064322 -38.68725308
OS -2.2295485 -38.68540396
OS -2.20735906 -38.68078116
OS -2.1833205 -38.67615836
OS -2.16205562 -38.670611
OS -2.15188546 -38.66783732
OS -2.14263986 -38.66506364
OS -2.14263986 -38.66413908
OS -2.14263986 -38.66228996
OS -2.1417153 -38.6567426
OS -2.1417153 -38.65027068
OS -2.1417153 -38.64657244
OS -2.1417153 -38.64472332
OS -2.1417153 -38.64379876
OS -2.1417153 -38.6428742
OS -2.1417153 -38.63732684
OS -2.14263986 -38.62808124
OS -2.14448898 -38.61791108
OS -2.14726266 -38.60681636
OS -2.15188546 -38.59572164
OS -2.15743282 -38.58555148
OS -2.1648293 -38.57723044
OS -2.16575386 -38.57630588
OS -2.17037666 -38.57260764
OS -2.17777314 -38.5689094
OS -2.18701874 -38.56336204
OS -2.19996258 -38.55873924
OS -2.21475554 -38.55411644
OS -2.23324674 -38.55134276
OS -2.25451162 -38.5504182
OS -2.26375722 -38.5504182
OS -2.27300282 -38.55134276
OS -2.28594666 -38.55319188
OS -2.2988905 -38.555041
OS -2.3127589 -38.55873924
OS -2.32570274 -38.56336204
OS -2.33679746 -38.56983396
OS -2.33772202 -38.57075852
OS -2.34142026 -38.5735322
OS -2.34604306 -38.578155
OS -2.35159042 -38.58555148
OS -2.35713778 -38.59479708
OS -2.3636097 -38.60681636
OS -2.36915706 -38.62160932
OS -2.37470442 -38.6382514
OS -2.4514429 -38.62808124
OS -2.4514429 -38.62715668
OS -2.45051834 -38.62623212
OS -2.45051834 -38.62345844
OS -2.44959378 -38.6197602
OS -2.4468201 -38.61143916
OS -2.44312186 -38.59941988
OS -2.43849906 -38.5874006
OS -2.4329517 -38.57445676
OS -2.42555522 -38.56151292
OS -2.41723418 -38.54949364
OS -2.41630962 -38.54856908
OS -2.41261138 -38.54487084
OS -2.40706402 -38.53932348
OS -2.39966754 -38.531927
OS -2.38949738 -38.52453052
OS -2.3774781 -38.51713404
OS -2.3636097 -38.508813
OS -2.34789218 -38.50234108
OS -2.34696762 -38.50234108
OS -2.34604306 -38.50141652
OS -2.34326938 -38.50049196
OS -2.33957114 -38.4995674
OS -2.33032554 -38.49679372
OS -2.3173817 -38.49402004
OS -2.30258874 -38.49124636
OS -2.28409754 -38.48847268
OS -2.26468178 -38.48662356
OS -2.24249234 -38.485699
OS -2.23232218 -38.485699
OS -2.22215202 -38.48662356
OE
OB -3.41206074 -38.48662356 I
OS -3.40558882 -38.48754812
OS -3.39172042 -38.48939724
OS -3.37507834 -38.49309548
OS -3.3575117 -38.49864284
OS -3.33994506 -38.50696388
OS -3.32237842 -38.51713404
OS -3.32145386 -38.51713404
OS -3.3205293 -38.51898316
OS -3.31498194 -38.5226814
OS -3.3066609 -38.53007788
OS -3.29649074 -38.53932348
OS -3.28539602 -38.55134276
OS -3.2743013 -38.56613572
OS -3.26320658 -38.58370236
OS -3.25396098 -38.60311812
OS -3.25396098 -38.60404268
OS -3.25303642 -38.6058918
OS -3.25211186 -38.60866548
OS -3.25026274 -38.61236372
OS -3.24841362 -38.61791108
OS -3.2465645 -38.624383
OS -3.2419417 -38.63917596
OS -3.2373189 -38.65766716
OS -3.23362066 -38.67800748
OS -3.23084698 -38.70112148
OS -3.22992242 -38.72516004
OS -3.22992242 -38.7260846
OS -3.22992242 -38.72793372
OS -3.22992242 -38.73163196
OS -3.22992242 -38.73717932
OS -3.23084698 -38.74365124
OS -3.23084698 -38.75104772
OS -3.2326961 -38.7676898
OS -3.23639434 -38.78803012
OS -3.24101714 -38.809295
OS -3.24748906 -38.83148444
OS -3.2558101 -38.85367388
OS -3.2558101 -38.85459844
OS -3.25673466 -38.85644756
OS -3.25858378 -38.85922124
OS -3.2604329 -38.86291948
OS -3.26690482 -38.87308964
OS -3.27522586 -38.88603348
OS -3.28539602 -38.89990188
OS -3.29833986 -38.91377028
OS -3.31313282 -38.92763868
OS -3.33069946 -38.94058252
OS -3.33162402 -38.94058252
OS -3.33254858 -38.94150708
OS -3.33532226 -38.9433562
OS -3.3390205 -38.94520532
OS -3.3482661 -38.94982812
OS -3.36120994 -38.95537548
OS -3.37692746 -38.96092284
OS -3.39356954 -38.96554564
OS -3.4129853 -38.96924388
OS -3.43240106 -38.97016844
OS -3.43887298 -38.97016844
OS -3.44626946 -38.96924388
OS -3.45551506 -38.96831932
OS -3.46660978 -38.9664702
OS -3.47862906 -38.96369652
OS -3.49064834 -38.95999828
OS -3.50266762 -38.95445092
OS -3.50359218 -38.95352636
OS -3.50821498 -38.95167724
OS -3.51376234 -38.947979
OS -3.52115882 -38.94243164
OS -3.5285553 -38.93688428
OS -3.5378009 -38.9294878
OS -3.54612194 -38.92116676
OS -3.55351842 -38.91192116
OS -3.55351842 -39.1375138
OS -3.63210602 -39.1375138
OS -3.63210602 -38.49586916
OS -3.5609149 -38.49586916
OS -3.5609149 -38.55689012
OS -3.55999034 -38.555041
OS -3.5562921 -38.55134276
OS -3.5516693 -38.54487084
OS -3.54427282 -38.53747436
OS -3.53595178 -38.52822876
OS -3.52670618 -38.51990772
OS -3.51561146 -38.51158668
OS -3.50451674 -38.5041902
OS -3.50266762 -38.50326564
OS -3.49896938 -38.50141652
OS -3.4915729 -38.49864284
OS -3.4823273 -38.4949446
OS -3.47123258 -38.49124636
OS -3.45828874 -38.48847268
OS -3.44349578 -38.48662356
OS -3.4268537 -38.485699
OS -3.41668354 -38.485699
OS -3.41206074 -38.48662356
OE
OB -2.6872057 -39.1375138 I
OS -3.20773298 -39.1375138
OS -3.20773298 -39.08111564
OS -2.6872057 -39.08111564
OS -2.6872057 -39.1375138
OE
OB -0.81127346 -38.48662356 I
OS -0.8011033 -38.48847268
OS -0.78908402 -38.49217092
OS -0.77614018 -38.49679372
OS -0.76134722 -38.50326564
OS -0.7456297 -38.51158668
OS -0.77429106 -38.58370236
OS -0.77521562 -38.5827778
OS -0.77891386 -38.58092868
OS -0.78446122 -38.578155
OS -0.7918577 -38.57538132
OS -0.80017874 -38.57260764
OS -0.8103489 -38.56983396
OS -0.82051906 -38.56798484
OS -0.83068922 -38.56706028
OS -0.83531202 -38.56706028
OS -0.83993482 -38.56798484
OS -0.84640674 -38.5689094
OS -0.85287866 -38.57075852
OS -0.8611997 -38.5735322
OS -0.86952074 -38.57723044
OS -0.87691722 -38.5827778
OS -0.87784178 -38.58370236
OS -0.88061546 -38.58555148
OS -0.88338914 -38.58924972
OS -0.88801194 -38.59387252
OS -0.89263474 -38.60034444
OS -0.89725754 -38.60774092
OS -0.90188034 -38.61606196
OS -0.90557858 -38.62623212
OS -0.90650314 -38.62808124
OS -0.9074277 -38.6336286
OS -0.90927682 -38.64194964
OS -0.9120505 -38.65304436
OS -0.91482418 -38.66691276
OS -0.9166733 -38.68263028
OS -0.91759786 -38.69927236
OS -0.91852242 -38.71776356
OS -0.91852242 -38.95999828
OS -0.99711002 -38.95999828
OS -0.99711002 -38.49586916
OS -0.9259189 -38.49586916
OS -0.9259189 -38.56613572
OS -0.92499434 -38.56521116
OS -0.9212961 -38.55873924
OS -0.9166733 -38.5504182
OS -0.90927682 -38.54024804
OS -0.90188034 -38.53007788
OS -0.8935593 -38.51898316
OS -0.88523826 -38.50973756
OS -0.87691722 -38.50234108
OS -0.87599266 -38.50141652
OS -0.87321898 -38.4995674
OS -0.86767162 -38.49679372
OS -0.86212426 -38.49402004
OS -0.85472778 -38.49124636
OS -0.84548218 -38.48847268
OS -0.83623658 -38.48662356
OS -0.82606642 -38.485699
OS -0.8195945 -38.485699
OS -0.81127346 -38.48662356
OE
OB -0.62821058 -38.42745172 I
OS -0.64947546 -38.54671996
OS -0.69847714 -38.54671996
OS -0.7178929 -38.42745172
OS -0.7178929 -38.32020276
OS -0.62821058 -38.32020276
OS -0.62821058 -38.42745172
OE
OB -1.73768258 -38.96739476 I
OS -1.73768258 -38.96831932
OS -1.73860714 -38.971093
OS -1.74045626 -38.97479124
OS -1.74230538 -38.97941404
OS -1.74507906 -38.98588596
OS -1.74785274 -38.99328244
OS -1.75432466 -39.00899996
OS -1.76079658 -39.0265666
OS -1.76819306 -39.04413324
OS -1.77558954 -39.05985076
OS -1.77928778 -39.06632268
OS -1.78206146 -39.0727946
OS -1.78298602 -39.07464372
OS -1.7857597 -39.07926652
OS -1.7903825 -39.08573844
OS -1.79592986 -39.09405948
OS -1.80332634 -39.10330508
OS -1.81164738 -39.11255068
OS -1.81996842 -39.12179628
OS -1.83013858 -39.12919276
OS -1.83106314 -39.13011732
OS -1.83476138 -39.13196644
OS -1.84030874 -39.13474012
OS -1.84862978 -39.13843836
OS -1.85787538 -39.1421366
OS -1.8689701 -39.14491028
OS -1.88098938 -39.1467594
OS -1.89485778 -39.14768396
OS -1.89855602 -39.14768396
OS -1.90317882 -39.1467594
OS -1.90965074 -39.1467594
OS -1.91704722 -39.14491028
OS -1.92536826 -39.14306116
OS -1.93461386 -39.14121204
OS -1.94478402 -39.1375138
OS -1.95310506 -39.06447356
OS -1.9521805 -39.06447356
OS -1.94848226 -39.06539812
OS -1.94385946 -39.06632268
OS -1.9383121 -39.0681718
OS -1.92351914 -39.07094548
OS -1.90872618 -39.07187004
OS -1.90410338 -39.07187004
OS -1.89948058 -39.07094548
OS -1.89393322 -39.07094548
OS -1.88006482 -39.0681718
OS -1.8735929 -39.06539812
OS -1.86712098 -39.06262444
OS -1.86619642 -39.06262444
OS -1.8643473 -39.06077532
OS -1.86157362 -39.0589262
OS -1.85787538 -39.05615252
OS -1.84955434 -39.04875604
OS -1.84215786 -39.03858588
OS -1.84215786 -39.03766132
OS -1.84030874 -39.0358122
OS -1.83845962 -39.03211396
OS -1.8366105 -39.0265666
OS -1.83291226 -39.01917012
OS -1.82921402 -39.0080754
OS -1.82366666 -38.99513156
OS -1.8181193 -38.97941404
OS -1.8181193 -38.97848948
OS -1.81627018 -38.97479124
OS -1.81442106 -38.96831932
OS -1.81072282 -38.95999828
OS -1.98638922 -38.49586916
OS -1.90317882 -38.49586916
OS -1.80610002 -38.76491612
OS -1.80610002 -38.76584068
OS -1.80517546 -38.76676524
OS -1.8042509 -38.76953892
OS -1.80332634 -38.77416172
OS -1.80147722 -38.77878452
OS -1.7996281 -38.78433188
OS -1.7950053 -38.79727572
OS -1.78945794 -38.81299324
OS -1.78391058 -38.83148444
OS -1.77836322 -38.8509002
OS -1.77281586 -38.87216508
OS -1.77281586 -38.87124052
OS -1.7718913 -38.8693914
OS -1.77096674 -38.86661772
OS -1.77004218 -38.86291948
OS -1.76911762 -38.85829668
OS -1.7672685 -38.85274932
OS -1.76357026 -38.83888092
OS -1.75894746 -38.8231634
OS -1.75247554 -38.8046722
OS -1.74692818 -38.786181
OS -1.7395317 -38.76676524
OS -1.63967922 -38.49586916
OS -1.56109162 -38.49586916
OS -1.73768258 -38.96739476
OE
OB -1.28834642 -38.48662356 I
OS -1.28094994 -38.48754812
OS -1.27170434 -38.48939724
OS -1.26153418 -38.49124636
OS -1.2495149 -38.49402004
OS -1.23842018 -38.49679372
OS -1.22547634 -38.50141652
OS -1.21345706 -38.50603932
OS -1.20051322 -38.51251124
OS -1.18756938 -38.51990772
OS -1.17462554 -38.52822876
OS -1.16260626 -38.53839892
OS -1.15151154 -38.54949364
OS -1.15058698 -38.5504182
OS -1.14873786 -38.55226732
OS -1.14596418 -38.55596556
OS -1.14226594 -38.56151292
OS -1.13764314 -38.56798484
OS -1.13302034 -38.57538132
OS -1.12747298 -38.58462692
OS -1.12192562 -38.59572164
OS -1.11637826 -38.60774092
OS -1.1108309 -38.62068476
OS -1.1062081 -38.63547772
OS -1.1015853 -38.65119524
OS -1.09788706 -38.66876188
OS -1.09511338 -38.68725308
OS -1.09326426 -38.70666884
OS -1.0923397 -38.72793372
OS -1.0923397 -38.72885828
OS -1.0923397 -38.73255652
OS -1.0923397 -38.73902844
OS -1.09326426 -38.74827404
OS -1.43997426 -38.74827404
OS -1.43997426 -38.7491986
OS -1.43997426 -38.75197228
OS -1.4390497 -38.75567052
OS -1.4390497 -38.76121788
OS -1.43812514 -38.7676898
OS -1.43627602 -38.77508628
OS -1.43350234 -38.79172836
OS -1.42795498 -38.81021956
OS -1.4205585 -38.83055988
OS -1.41038834 -38.84905108
OS -1.3974445 -38.86569316
OS -1.39651994 -38.86569316
OS -1.39559538 -38.86754228
OS -1.39004802 -38.87216508
OS -1.38172698 -38.878637
OS -1.37063226 -38.88510892
OS -1.3558393 -38.8925054
OS -1.33919722 -38.89897732
OS -1.32070602 -38.90360012
OS -1.31053586 -38.90452468
OS -1.29944114 -38.90544924
OS -1.29204466 -38.90544924
OS -1.28372362 -38.90452468
OS -1.27355346 -38.90267556
OS -1.26245874 -38.89990188
OS -1.2495149 -38.89620364
OS -1.23749562 -38.89065628
OS -1.22547634 -38.8832598
OS -1.22455178 -38.88233524
OS -1.21992898 -38.878637
OS -1.21438162 -38.87308964
OS -1.2079097 -38.86569316
OS -1.20051322 -38.855523
OS -1.19219218 -38.84257916
OS -1.18387114 -38.8277862
OS -1.17647466 -38.81021956
OS -1.09511338 -38.82038972
OS -1.09511338 -38.82131428
OS -1.09603794 -38.8231634
OS -1.0969625 -38.82686164
OS -1.09881162 -38.832409
OS -1.1015853 -38.83795636
OS -1.10435898 -38.84535284
OS -1.11175546 -38.86107036
OS -1.12100106 -38.878637
OS -1.1339449 -38.8971282
OS -1.14873786 -38.91469484
OS -1.16722906 -38.93133692
OS -1.16815362 -38.93133692
OS -1.17000274 -38.93318604
OS -1.17277642 -38.93503516
OS -1.17647466 -38.93780884
OS -1.18202202 -38.94058252
OS -1.18756938 -38.9433562
OS -1.19496586 -38.94705444
OS -1.2032869 -38.95075268
OS -1.2125325 -38.95445092
OS -1.2217781 -38.95814916
OS -1.2448921 -38.96369652
OS -1.27077978 -38.96831932
OS -1.29944114 -38.97016844
OS -1.3096113 -38.97016844
OS -1.31608322 -38.96924388
OS -1.32440426 -38.96831932
OS -1.33457442 -38.9664702
OS -1.34566914 -38.96462108
OS -1.35768842 -38.96277196
OS -1.3835761 -38.95537548
OS -1.3974445 -38.94982812
OS -1.41038834 -38.94428076
OS -1.42425674 -38.93688428
OS -1.43720058 -38.92856324
OS -1.44921986 -38.91931764
OS -1.46123914 -38.90822292
OS -1.4621637 -38.90729836
OS -1.46401282 -38.90544924
OS -1.4667865 -38.901751
OS -1.47048474 -38.89620364
OS -1.47510754 -38.88973172
OS -1.47973034 -38.88233524
OS -1.4852777 -38.87308964
OS -1.49082506 -38.86291948
OS -1.49637242 -38.8509002
OS -1.50191978 -38.83795636
OS -1.50654258 -38.8231634
OS -1.51116538 -38.80744588
OS -1.51486362 -38.7908038
OS -1.5176373 -38.7723126
OS -1.51948642 -38.75289684
OS -1.52041098 -38.73255652
OS -1.52041098 -38.73163196
OS -1.52041098 -38.72700916
OS -1.52041098 -38.7214618
OS -1.51948642 -38.71314076
OS -1.51856186 -38.7029706
OS -1.5176373 -38.69187588
OS -1.51578818 -38.67893204
OS -1.5130145 -38.6659882
OS -1.50561802 -38.63640228
OS -1.50099522 -38.62160932
OS -1.49544786 -38.6058918
OS -1.48805138 -38.59109884
OS -1.47973034 -38.57723044
OS -1.47048474 -38.56336204
OS -1.46031458 -38.5504182
OS -1.45939002 -38.54949364
OS -1.4575409 -38.54764452
OS -1.45384266 -38.54487084
OS -1.44921986 -38.54024804
OS -1.4436725 -38.53562524
OS -1.43627602 -38.53007788
OS -1.42795498 -38.52360596
OS -1.41778482 -38.5180586
OS -1.40761466 -38.51158668
OS -1.39559538 -38.50603932
OS -1.38265154 -38.50049196
OS -1.36878314 -38.49586916
OS -1.35399018 -38.49124636
OS -1.33827266 -38.48847268
OS -1.32163058 -38.48662356
OS -1.30406394 -38.485699
OS -1.29481834 -38.485699
OS -1.28834642 -38.48662356
OE
OB -3.9261161 -38.48662356 I
OS -3.91779506 -38.48754812
OS -3.90854946 -38.48939724
OS -3.8983793 -38.49124636
OS -3.88636002 -38.49309548
OS -3.8613969 -38.50141652
OS -3.84845306 -38.50603932
OS -3.83550922 -38.51251124
OS -3.82256538 -38.51898316
OS -3.80962154 -38.52822876
OS -3.79760226 -38.53747436
OS -3.78558298 -38.54856908
OS -3.78465842 -38.54949364
OS -3.7828093 -38.55134276
OS -3.78003562 -38.555041
OS -3.77633738 -38.5596638
OS -3.77171458 -38.56613572
OS -3.76616722 -38.57445676
OS -3.76061986 -38.58370236
OS -3.7550725 -38.59387252
OS -3.74952514 -38.60496724
OS -3.74397778 -38.61883564
OS -3.73843042 -38.63270404
OS -3.73380762 -38.64842156
OS -3.73010938 -38.66506364
OS -3.7273357 -38.68263028
OS -3.72548658 -38.70112148
OS -3.72456202 -38.7214618
OS -3.72456202 -38.72238636
OS -3.72456202 -38.72516004
OS -3.72456202 -38.72978284
OS -3.72456202 -38.73625476
OS -3.72548658 -38.74365124
OS -3.72641114 -38.75289684
OS -3.72641114 -38.76214244
OS -3.72826026 -38.7723126
OS -3.73103394 -38.7954266
OS -3.7365813 -38.8185406
OS -3.74305322 -38.8416546
OS -3.75229882 -38.86291948
OS -3.75229882 -38.86384404
OS -3.75322338 -38.8647686
OS -3.7550725 -38.86754228
OS -3.75692162 -38.87124052
OS -3.76339354 -38.88048612
OS -3.77171458 -38.89158084
OS -3.7828093 -38.90452468
OS -3.7966777 -38.91746852
OS -3.81239522 -38.93041236
OS -3.83088642 -38.94243164
OS -3.83181098 -38.94243164
OS -3.83273554 -38.9433562
OS -3.83550922 -38.94520532
OS -3.84013202 -38.94705444
OS -3.84475482 -38.94890356
OS -3.85030218 -38.95075268
OS -3.86417058 -38.95630004
OS -3.8798881 -38.96092284
OS -3.89930386 -38.96554564
OS -3.91964418 -38.96924388
OS -3.94183362 -38.97016844
OS -3.95107922 -38.97016844
OS -3.9584757 -38.96924388
OS -3.96679674 -38.96831932
OS -3.97604234 -38.9664702
OS -3.98713706 -38.96462108
OS -3.99823178 -38.96277196
OS -4.0231949 -38.95537548
OS -4.0370633 -38.94982812
OS -4.05000714 -38.94428076
OS -4.06295098 -38.93688428
OS -4.07589482 -38.92856324
OS -4.0879141 -38.91931764
OS -4.09993338 -38.90822292
OS -4.10085794 -38.90729836
OS -4.10270706 -38.90544924
OS -4.10548074 -38.901751
OS -4.10917898 -38.89620364
OS -4.11380178 -38.88973172
OS -4.11842458 -38.88233524
OS -4.12397194 -38.87308964
OS -4.1295193 -38.86199492
OS -4.13506666 -38.84997564
OS -4.14061402 -38.83610724
OS -4.14523682 -38.82131428
OS -4.14985962 -38.80559676
OS -4.15355786 -38.78803012
OS -4.15633154 -38.76953892
OS -4.15818066 -38.7491986
OS -4.15910522 -38.72793372
OS -4.15910522 -38.7260846
OS -4.15910522 -38.72238636
OS -4.15818066 -38.71591444
OS -4.15818066 -38.70666884
OS -4.1572561 -38.69649868
OS -4.15540698 -38.68355484
OS -4.15355786 -38.670611
OS -4.14985962 -38.65581804
OS -4.14616138 -38.64102508
OS -4.14153858 -38.62530756
OS -4.13599122 -38.60866548
OS -4.12859474 -38.59294796
OS -4.12119826 -38.578155
OS -4.1110281 -38.56336204
OS -4.10085794 -38.54949364
OS -4.0879141 -38.53747436
OS -4.08698954 -38.5365498
OS -4.08514042 -38.53562524
OS -4.08144218 -38.53285156
OS -4.07681938 -38.52915332
OS -4.07127202 -38.52545508
OS -4.06387554 -38.52083228
OS -4.05647906 -38.51620948
OS -4.04723346 -38.51158668
OS -4.0370633 -38.50696388
OS -4.02596858 -38.50234108
OS -4.00100546 -38.49402004
OS -3.9723441 -38.48754812
OS -3.95755114 -38.48662356
OS -3.94183362 -38.485699
OS -3.93258802 -38.485699
OS -3.9261161 -38.48662356
OE
OB -5.4655085 -38.31835364 I
OS -5.45348922 -38.32020276
OS -5.43962082 -38.32297644
OS -5.42482786 -38.32667468
OS -5.40911034 -38.33129748
OS -5.39431738 -38.33869396
OS -5.39339282 -38.33869396
OS -5.39246826 -38.33961852
OS -5.38784546 -38.3423922
OS -5.38044898 -38.347015
OS -5.37120338 -38.35348692
OS -5.36103322 -38.36273252
OS -5.3499385 -38.37290268
OS -5.33976834 -38.38492196
OS -5.32959818 -38.39879036
OS -5.32867362 -38.40063948
OS -5.32497538 -38.40526228
OS -5.32127714 -38.41358332
OS -5.31480522 -38.4256026
OS -5.30925786 -38.439471
OS -5.30186138 -38.45518852
OS -5.29538946 -38.47367972
OS -5.2898421 -38.49402004
OS -5.2898421 -38.4949446
OS -5.28891754 -38.49679372
OS -5.28799298 -38.4995674
OS -5.28706842 -38.5041902
OS -5.28614386 -38.50973756
OS -5.2852193 -38.51620948
OS -5.28337018 -38.52453052
OS -5.28244562 -38.53377612
OS -5.2805965 -38.54394628
OS -5.27967194 -38.555041
OS -5.27874738 -38.56798484
OS -5.27689826 -38.58092868
OS -5.2759737 -38.59572164
OS -5.2759737 -38.6105146
OS -5.27504914 -38.62715668
OS -5.27504914 -38.64472332
OS -5.27504914 -38.64564788
OS -5.27504914 -38.64934612
OS -5.27504914 -38.65581804
OS -5.27504914 -38.66321452
OS -5.2759737 -38.67338468
OS -5.2759737 -38.6844794
OS -5.27689826 -38.69649868
OS -5.27782282 -38.70944252
OS -5.2805965 -38.73902844
OS -5.2852193 -38.76953892
OS -5.29076666 -38.79912484
OS -5.2944649 -38.81299324
OS -5.2990877 -38.82686164
OS -5.2990877 -38.8277862
OS -5.30001226 -38.82963532
OS -5.30186138 -38.83333356
OS -5.3037105 -38.83795636
OS -5.30555962 -38.84442828
OS -5.30925786 -38.8509002
OS -5.31665434 -38.86661772
OS -5.32589994 -38.8832598
OS -5.33791922 -38.901751
OS -5.35178762 -38.91839308
OS -5.3684297 -38.9341106
OS -5.36935426 -38.9341106
OS -5.37027882 -38.93595972
OS -5.3730525 -38.93780884
OS -5.37675074 -38.93965796
OS -5.38137354 -38.94243164
OS -5.38599634 -38.94612988
OS -5.39986474 -38.9526018
OS -5.41650682 -38.95907372
OS -5.43592258 -38.96554564
OS -5.45903658 -38.96924388
OS -5.4839997 -38.971093
OS -5.4932453 -38.971093
OS -5.49971722 -38.97016844
OS -5.5071137 -38.96924388
OS -5.5163593 -38.96739476
OS -5.52652946 -38.96554564
OS -5.53762418 -38.96277196
OS -5.5487189 -38.95907372
OS -5.56073818 -38.95537548
OS -5.57275746 -38.94982812
OS -5.58477674 -38.9433562
OS -5.59679602 -38.93595972
OS -5.6088153 -38.92671412
OS -5.61991002 -38.91654396
OS -5.63008018 -38.90544924
OS -5.63100474 -38.90452468
OS -5.63285386 -38.901751
OS -5.63562754 -38.8971282
OS -5.64025034 -38.88973172
OS -5.64487314 -38.88141068
OS -5.64949594 -38.87031596
OS -5.65596786 -38.85737212
OS -5.66151522 -38.84257916
OS -5.66706258 -38.82593708
OS -5.67260994 -38.80652132
OS -5.6781573 -38.78525644
OS -5.6827801 -38.76121788
OS -5.6874029 -38.7353302
OS -5.69017658 -38.7075934
OS -5.6920257 -38.67708292
OS -5.69295026 -38.64472332
OS -5.69295026 -38.64379876
OS -5.69295026 -38.64010052
OS -5.69295026 -38.6336286
OS -5.69295026 -38.62623212
OS -5.6920257 -38.61606196
OS -5.6920257 -38.60496724
OS -5.69110114 -38.59294796
OS -5.69017658 -38.57907956
OS -5.6874029 -38.5504182
OS -5.6827801 -38.51990772
OS -5.67723274 -38.48939724
OS -5.6735345 -38.47552884
OS -5.66983626 -38.46166044
OS -5.66983626 -38.46073588
OS -5.6689117 -38.45888676
OS -5.66706258 -38.45518852
OS -5.66521346 -38.45056572
OS -5.66336434 -38.4440938
OS -5.6596661 -38.43762188
OS -5.65226962 -38.42190436
OS -5.64302402 -38.40526228
OS -5.63100474 -38.38769564
OS -5.61713634 -38.370129
OS -5.60049426 -38.35533604
OS -5.5995697 -38.35533604
OS -5.59864514 -38.35348692
OS -5.59587146 -38.3516378
OS -5.59217322 -38.34978868
OS -5.58755042 -38.34609044
OS -5.58200306 -38.34331676
OS -5.56813466 -38.33592028
OS -5.55149258 -38.32944836
OS -5.53207682 -38.32297644
OS -5.50896282 -38.3192782
OS -5.4839997 -38.31742908
OS -5.47567866 -38.31742908
OS -5.4655085 -38.31835364
OE
OB -4.89967778 -38.95999828 I
OS -4.97826538 -38.95999828
OS -4.97826538 -38.45981132
OS -4.97918994 -38.46073588
OS -4.98381274 -38.46443412
OS -4.9893601 -38.46998148
OS -4.9986057 -38.4764534
OS -5.00877586 -38.48477444
OS -5.0217197 -38.49402004
OS -5.03651266 -38.5041902
OS -5.05315474 -38.51436036
OS -5.0540793 -38.51436036
OS -5.05500386 -38.51528492
OS -5.06055122 -38.51898316
OS -5.06979682 -38.52360596
OS -5.08089154 -38.52915332
OS -5.09383538 -38.53562524
OS -5.10770378 -38.54209716
OS -5.12157218 -38.54856908
OS -5.13544058 -38.55411644
OS -5.13544058 -38.47830252
OS -5.13451602 -38.47830252
OS -5.1326669 -38.4764534
OS -5.12896866 -38.47552884
OS -5.12434586 -38.47275516
OS -5.1187985 -38.46998148
OS -5.11232658 -38.46628324
OS -5.09660906 -38.45703764
OS -5.07811786 -38.44686748
OS -5.05962666 -38.43392364
OS -5.0402109 -38.41913068
OS -5.02079514 -38.40341316
OS -5.01987058 -38.4024886
OS -5.01894602 -38.40156404
OS -5.01617234 -38.39879036
OS -5.0124741 -38.39601668
OS -5.00415306 -38.38677108
OS -4.99305834 -38.37567636
OS -4.98196362 -38.36273252
OS -4.96994434 -38.34793956
OS -4.95977418 -38.3331466
OS -4.95052858 -38.31742908
OS -4.89967778 -38.31742908
OS -4.89967778 -38.95999828
OE
OB -5.79280274 -38.95999828 I
OS -5.87139034 -38.95999828
OS -5.87139034 -38.32020276
OS -5.79280274 -38.32020276
OS -5.79280274 -38.95999828
OE
OB -5.97031826 -38.42745172 I
OS -5.99158314 -38.54671996
OS -6.04058482 -38.54671996
OS -6.06000058 -38.42745172
OS -6.06000058 -38.32020276
OS -5.97031826 -38.32020276
OS -5.97031826 -38.42745172
OE
OB -4.2866945 -38.49586916 I
OS -4.20718234 -38.49586916
OS -4.20718234 -38.55689012
OS -4.2866945 -38.55689012
OS -4.2866945 -38.82963532
OS -4.2866945 -38.83148444
OS -4.2866945 -38.83518268
OS -4.2866945 -38.84073004
OS -4.28576994 -38.84720196
OS -4.28484538 -38.86199492
OS -4.28392082 -38.86846684
OS -4.28299626 -38.87308964
OS -4.2820717 -38.87493876
OS -4.27929802 -38.878637
OS -4.27559978 -38.8832598
OS -4.26912786 -38.8878826
OS -4.26727874 -38.88880716
OS -4.26265594 -38.89065628
OS -4.2543349 -38.8925054
OS -4.24231562 -38.89342996
OS -4.23307002 -38.89342996
OS -4.22844722 -38.8925054
OS -4.2219753 -38.8925054
OS -4.21457882 -38.89158084
OS -4.20718234 -38.89065628
OS -4.19701218 -38.95999828
OS -4.1988613 -38.95999828
OS -4.20255954 -38.96092284
OS -4.20903146 -38.9618474
OS -4.2173525 -38.96277196
OS -4.2265981 -38.96462108
OS -4.23676826 -38.96554564
OS -4.25710858 -38.9664702
OS -4.26450506 -38.9664702
OS -4.27190154 -38.96554564
OS -4.28114714 -38.96462108
OS -4.29224186 -38.96369652
OS -4.30333658 -38.96092284
OS -4.31350674 -38.95814916
OS -4.3236769 -38.95352636
OS -4.32460146 -38.9526018
OS -4.32737514 -38.95075268
OS -4.33107338 -38.947979
OS -4.33662074 -38.9433562
OS -4.34124354 -38.9387334
OS -4.3467909 -38.93226148
OS -4.35233826 -38.92578956
OS -4.3560365 -38.91746852
OS -4.3560365 -38.91654396
OS -4.35788562 -38.91284572
OS -4.35881018 -38.9063738
OS -4.3606593 -38.8971282
OS -4.36250842 -38.88510892
OS -4.36343298 -38.87771244
OS -4.36343298 -38.8693914
OS -4.36435754 -38.85922124
OS -4.3652821 -38.84905108
OS -4.3652821 -38.83795636
OS -4.3652821 -38.82501252
OS -4.3652821 -38.55689012
OS -4.42352938 -38.55689012
OS -4.42352938 -38.49586916
OS -4.3652821 -38.49586916
OS -4.3652821 -38.38122372
OS -4.2866945 -38.33407116
OS -4.2866945 -38.49586916
OE
OB -4.46421002 -38.7676898 I
OS -4.7073693 -38.7676898
OS -4.7073693 -38.6891022
OS -4.46421002 -38.6891022
OS -4.46421002 -38.7676898
OE
OB -3.43425018 -38.54764452 H
OS -3.43887298 -38.54764452
OS -3.44257122 -38.54856908
OS -3.45181682 -38.5504182
OS -3.4638361 -38.55319188
OS -3.4777045 -38.55873924
OS -3.49249746 -38.56706028
OS -3.5008185 -38.57260764
OS -3.50821498 -38.57907956
OS -3.51561146 -38.58647604
OS -3.52300794 -38.59479708
OS -3.52300794 -38.59572164
OS -3.52485706 -38.5966462
OS -3.52670618 -38.59941988
OS -3.5285553 -38.60311812
OS -3.53132898 -38.60866548
OS -3.53502722 -38.61421284
OS -3.53872546 -38.62160932
OS -3.54149914 -38.6290058
OS -3.54519738 -38.6382514
OS -3.54889562 -38.64842156
OS -3.5516693 -38.65951628
OS -3.55536754 -38.67153556
OS -3.55721666 -38.68540396
OS -3.55906578 -38.69927236
OS -3.5609149 -38.71406532
OS -3.5609149 -38.7307074
OS -3.5609149 -38.73163196
OS -3.5609149 -38.73440564
OS -3.5609149 -38.73902844
OS -3.55999034 -38.74550036
OS -3.55999034 -38.75289684
OS -3.55906578 -38.76121788
OS -3.5562921 -38.78063364
OS -3.5516693 -38.80282308
OS -3.54612194 -38.82408796
OS -3.53687634 -38.84535284
OS -3.53132898 -38.85459844
OS -3.52485706 -38.86291948
OS -3.52300794 -38.8647686
OS -3.51838514 -38.8693914
OS -3.51098866 -38.87678788
OS -3.5008185 -38.88418436
OS -3.48787466 -38.89158084
OS -3.4730817 -38.89897732
OS -3.45643962 -38.90360012
OS -3.44719402 -38.90452468
OS -3.43794842 -38.90544924
OS -3.43240106 -38.90544924
OS -3.42870282 -38.90452468
OS -3.41945722 -38.90267556
OS -3.40651338 -38.89990188
OS -3.39264498 -38.89435452
OS -3.37785202 -38.88695804
OS -3.36305906 -38.87586332
OS -3.35566258 -38.8693914
OS -3.3482661 -38.86199492
OS -3.3482661 -38.86107036
OS -3.34641698 -38.8601458
OS -3.34456786 -38.85737212
OS -3.34271874 -38.85367388
OS -3.3390205 -38.84905108
OS -3.33624682 -38.84257916
OS -3.33254858 -38.83610724
OS -3.32885034 -38.8277862
OS -3.32607666 -38.81946516
OS -3.32237842 -38.80837044
OS -3.31868018 -38.79727572
OS -3.3159065 -38.78525644
OS -3.31405738 -38.77138804
OS -3.31220826 -38.75659508
OS -3.31035914 -38.74087756
OS -3.31035914 -38.72423548
OS -3.31035914 -38.72331092
OS -3.31035914 -38.72053724
OS -3.31035914 -38.71591444
OS -3.3112837 -38.70944252
OS -3.3112837 -38.70204604
OS -3.31220826 -38.693725
OS -3.31498194 -38.67430924
OS -3.31960474 -38.65304436
OS -3.32607666 -38.63177948
OS -3.33532226 -38.6105146
OS -3.34086962 -38.60034444
OS -3.34734154 -38.5920234
OS -3.34734154 -38.59109884
OS -3.34919066 -38.59017428
OS -3.35381346 -38.58462692
OS -3.36120994 -38.578155
OS -3.3713801 -38.56983396
OS -3.38432394 -38.56151292
OS -3.3991169 -38.55411644
OS -3.41575898 -38.54949364
OS -3.42500458 -38.54856908
OS -3.43425018 -38.54764452
OE
OB -3.94183362 -38.5504182 H
OS -3.94738098 -38.5504182
OS -3.95200378 -38.55134276
OS -3.96217394 -38.55226732
OS -3.97604234 -38.55596556
OS -3.99175986 -38.56151292
OS -4.00840194 -38.5689094
OS -4.02411946 -38.58000412
OS -4.0324405 -38.5874006
OS -4.03983698 -38.59479708
OS -4.03983698 -38.59572164
OS -4.0416861 -38.5966462
OS -4.04353522 -38.59941988
OS -4.0463089 -38.60311812
OS -4.04908258 -38.60774092
OS -4.05185626 -38.61328828
OS -4.0555545 -38.62068476
OS -4.05925274 -38.62808124
OS -4.06295098 -38.63732684
OS -4.06664922 -38.64657244
OS -4.0694229 -38.65766716
OS -4.07219658 -38.66968644
OS -4.07497026 -38.68263028
OS -4.07681938 -38.69649868
OS -4.07774394 -38.7122162
OS -4.0786685 -38.72793372
OS -4.0786685 -38.72885828
OS -4.0786685 -38.73163196
OS -4.0786685 -38.73625476
OS -4.07774394 -38.74272668
OS -4.07774394 -38.75012316
OS -4.07681938 -38.7584442
OS -4.0740457 -38.77785996
OS -4.0694229 -38.8000494
OS -4.06202642 -38.82223884
OS -4.05278082 -38.84350372
OS -4.0463089 -38.85274932
OS -4.03983698 -38.86199492
OS -4.03891242 -38.86199492
OS -4.03798786 -38.86384404
OS -4.0324405 -38.86846684
OS -4.02411946 -38.87586332
OS -4.01302474 -38.8832598
OS -3.99915634 -38.89158084
OS -3.98251426 -38.89897732
OS -3.9630985 -38.90360012
OS -3.95292834 -38.90452468
OS -3.94183362 -38.90544924
OS -3.93628626 -38.90544924
OS -3.93166346 -38.90452468
OS -3.9214933 -38.90267556
OS -3.9076249 -38.89990188
OS -3.89283194 -38.89435452
OS -3.87618986 -38.88695804
OS -3.86047234 -38.87586332
OS -3.8521513 -38.86846684
OS -3.84475482 -38.86107036
OS -3.84383026 -38.8601458
OS -3.8429057 -38.85922124
OS -3.84105658 -38.85644756
OS -3.8382829 -38.85274932
OS -3.83550922 -38.84812652
OS -3.83181098 -38.84257916
OS -3.82811274 -38.83518268
OS -3.8244145 -38.8277862
OS -3.82071626 -38.8185406
OS -3.81794258 -38.80837044
OS -3.81424434 -38.79727572
OS -3.81147066 -38.78525644
OS -3.80869698 -38.77138804
OS -3.80684786 -38.75751964
OS -3.80499874 -38.74180212
OS -3.80499874 -38.72516004
OS -3.80499874 -38.72423548
OS -3.80499874 -38.7214618
OS -3.80499874 -38.716839
OS -3.8059233 -38.71129164
OS -3.8059233 -38.70389516
OS -3.80684786 -38.69557412
OS -3.80962154 -38.67615836
OS -3.81424434 -38.65581804
OS -3.82164082 -38.6336286
OS -3.83181098 -38.61328828
OS -3.83735834 -38.60311812
OS -3.84475482 -38.59479708
OS -3.84475482 -38.59387252
OS -3.84660394 -38.59294796
OS -3.8521513 -38.5874006
OS -3.86047234 -38.58092868
OS -3.87156706 -38.57260764
OS -3.88543546 -38.5642866
OS -3.90207754 -38.55689012
OS -3.92056874 -38.55226732
OS -3.9307389 -38.55134276
OS -3.94183362 -38.5504182
OE
OB -5.48492426 -38.38214828 H
OS -5.49047162 -38.38214828
OS -5.49416986 -38.38307284
OS -5.50434002 -38.38492196
OS -5.5163593 -38.38769564
OS -5.5302277 -38.393243
OS -5.54502066 -38.40156404
OS -5.55241714 -38.4071114
OS -5.55981362 -38.41265876
OS -5.56628554 -38.42005524
OS -5.57275746 -38.42837628
OS -5.57275746 -38.42930084
OS -5.57460658 -38.43114996
OS -5.5764557 -38.4348482
OS -5.57922938 -38.439471
OS -5.58200306 -38.44686748
OS -5.5857013 -38.45518852
OS -5.58847498 -38.46535868
OS -5.59217322 -38.47737796
OS -5.59587146 -38.49124636
OS -5.5995697 -38.50696388
OS -5.60326794 -38.52453052
OS -5.60604162 -38.54394628
OS -5.6088153 -38.56613572
OS -5.61066442 -38.59017428
OS -5.61158898 -38.61606196
OS -5.61251354 -38.64472332
OS -5.61251354 -38.64657244
OS -5.61251354 -38.65119524
OS -5.61251354 -38.65951628
OS -5.61158898 -38.670611
OS -5.61158898 -38.68263028
OS -5.61066442 -38.69742324
OS -5.60973986 -38.71314076
OS -5.60789074 -38.72978284
OS -5.60326794 -38.76584068
OS -5.60049426 -38.78340732
OS -5.59679602 -38.8000494
OS -5.59309778 -38.81576692
OS -5.58755042 -38.83055988
OS -5.58200306 -38.84350372
OS -5.57553114 -38.85459844
OS -5.57553114 -38.855523
OS -5.57368202 -38.85644756
OS -5.56905922 -38.86291948
OS -5.56073818 -38.87124052
OS -5.55056802 -38.88048612
OS -5.53669962 -38.88973172
OS -5.5209821 -38.89805276
OS -5.50341546 -38.90452468
OS -5.49416986 -38.90544924
OS -5.4839997 -38.9063738
OS -5.47845234 -38.9063738
OS -5.4747541 -38.90544924
OS -5.4655085 -38.90360012
OS -5.45256466 -38.89990188
OS -5.43869626 -38.89342996
OS -5.42297874 -38.88418436
OS -5.41558226 -38.878637
OS -5.40818578 -38.87124052
OS -5.4007893 -38.86384404
OS -5.39339282 -38.85459844
OS -5.39339282 -38.85367388
OS -5.3915437 -38.85182476
OS -5.38969458 -38.84905108
OS -5.38784546 -38.84442828
OS -5.38414722 -38.83795636
OS -5.38137354 -38.82963532
OS -5.3776753 -38.82038972
OS -5.37397706 -38.809295
OS -5.37120338 -38.7954266
OS -5.36750514 -38.78063364
OS -5.3638069 -38.763067
OS -5.36103322 -38.7445758
OS -5.3591841 -38.72238636
OS -5.35733498 -38.69927236
OS -5.35548586 -38.67338468
OS -5.35548586 -38.64472332
OS -5.35548586 -38.64379876
OS -5.35548586 -38.6428742
OS -5.35548586 -38.6382514
OS -5.35548586 -38.62993036
OS -5.35641042 -38.61883564
OS -5.35641042 -38.60681636
OS -5.35733498 -38.5920234
OS -5.35825954 -38.57630588
OS -5.36010866 -38.55873924
OS -5.36473146 -38.52360596
OS -5.36750514 -38.50603932
OS -5.37120338 -38.48939724
OS -5.37490162 -38.47367972
OS -5.38044898 -38.45888676
OS -5.38599634 -38.44594292
OS -5.39246826 -38.4348482
OS -5.39246826 -38.43392364
OS -5.39431738 -38.43299908
OS -5.3961665 -38.4302254
OS -5.39894018 -38.42652716
OS -5.40726122 -38.41820612
OS -5.41743138 -38.40803596
OS -5.43129978 -38.39879036
OS -5.4470173 -38.39046932
OS -5.45533834 -38.38677108
OS -5.46458394 -38.3839974
OS -5.4747541 -38.38307284
OS -5.48492426 -38.38214828
OE
OB -2.1417153 -38.72700916 H
OS -2.14263986 -38.72700916
OS -2.14356442 -38.72793372
OS -2.1463381 -38.72885828
OS -2.15003634 -38.72978284
OS -2.15465914 -38.73163196
OS -2.1602065 -38.73348108
OS -2.16667842 -38.7353302
OS -2.1740749 -38.73717932
OS -2.18239594 -38.739953
OS -2.1925661 -38.74180212
OS -2.20273626 -38.7445758
OS -2.21475554 -38.74734948
OS -2.22769938 -38.75012316
OS -2.24064322 -38.75289684
OS -2.25543618 -38.75474596
OS -2.2711537 -38.75751964
OS -2.27300282 -38.75751964
OS -2.27855018 -38.7584442
OS -2.28779578 -38.76029332
OS -2.29796594 -38.76214244
OS -2.30906066 -38.76399156
OS -2.32015538 -38.76676524
OS -2.33032554 -38.76953892
OS -2.33957114 -38.77323716
OS -2.3404957 -38.77323716
OS -2.34326938 -38.77508628
OS -2.34696762 -38.7769354
OS -2.35066586 -38.77970908
OS -2.36176058 -38.78710556
OS -2.37100618 -38.79820028
OS -2.37100618 -38.79912484
OS -2.3728553 -38.80097396
OS -2.37377986 -38.8046722
OS -2.37562898 -38.809295
OS -2.3774781 -38.81484236
OS -2.37932722 -38.82038972
OS -2.38025178 -38.8277862
OS -2.38117634 -38.83518268
OS -2.38117634 -38.83610724
OS -2.38117634 -38.84073004
OS -2.38025178 -38.8462774
OS -2.37840266 -38.85367388
OS -2.37562898 -38.86199492
OS -2.37100618 -38.87031596
OS -2.36545882 -38.87956156
OS -2.35806234 -38.8878826
OS -2.35713778 -38.88880716
OS -2.35343954 -38.89065628
OS -2.34789218 -38.89435452
OS -2.3404957 -38.89805276
OS -2.33032554 -38.901751
OS -2.31830626 -38.90544924
OS -2.30443786 -38.90729836
OS -2.28779578 -38.90822292
OS -2.2803993 -38.90822292
OS -2.2711537 -38.90729836
OS -2.26098354 -38.90544924
OS -2.2480397 -38.90360012
OS -2.23509586 -38.89990188
OS -2.22122746 -38.89527908
OS -2.20735906 -38.88880716
OS -2.20550994 -38.8878826
OS -2.2018117 -38.88510892
OS -2.19533978 -38.88048612
OS -2.1879433 -38.8740142
OS -2.17962226 -38.86661772
OS -2.17037666 -38.85737212
OS -2.16298018 -38.8462774
OS -2.1555837 -38.83425812
OS -2.15465914 -38.83333356
OS -2.15373458 -38.82963532
OS -2.15188546 -38.8231634
OS -2.14911178 -38.81484236
OS -2.1463381 -38.80374764
OS -2.14448898 -38.7908038
OS -2.14356442 -38.77508628
OS -2.14263986 -38.75659508
OS -2.1417153 -38.72700916
OE
OB -1.30313938 -38.5504182 H
OS -1.30868674 -38.5504182
OS -1.31238498 -38.55134276
OS -1.32255514 -38.55226732
OS -1.33457442 -38.555041
OS -1.34936738 -38.5596638
OS -1.3650849 -38.56613572
OS -1.37987786 -38.57538132
OS -1.39467082 -38.5874006
OS -1.39651994 -38.58924972
OS -1.40021818 -38.59387252
OS -1.4066901 -38.60219356
OS -1.41316202 -38.61328828
OS -1.4205585 -38.62623212
OS -1.42703042 -38.6428742
OS -1.43257778 -38.66228996
OS -1.43535146 -38.68355484
OS -1.1755501 -38.68355484
OS -1.1755501 -38.68263028
OS -1.1755501 -38.68078116
OS -1.17647466 -38.67800748
OS -1.17647466 -38.67430924
OS -1.17832378 -38.66321452
OS -1.18109746 -38.65119524
OS -1.18572026 -38.63640228
OS -1.19034306 -38.62253388
OS -1.19773954 -38.60866548
OS -1.20606058 -38.5966462
OS -1.20606058 -38.59572164
OS -1.2079097 -38.59479708
OS -1.2125325 -38.58924972
OS -1.22085354 -38.58185324
OS -1.23194826 -38.5735322
OS -1.24581666 -38.56521116
OS -1.26245874 -38.55781468
OS -1.2818745 -38.55226732
OS -1.29204466 -38.55134276
OS -1.30313938 -38.5504182
OE
SE
S P 0
OB -4.66714078 -36.5016923 I
OS -4.65465922 -36.5016923
OS -4.62553558 -36.50307914
OS -4.5950251 -36.50723966
OS -4.56174094 -36.51140018
OS -4.53123046 -36.51833438
OS -4.51597522 -36.5224949
OS -4.50349366 -36.52665542
OS -4.50210682 -36.52665542
OS -4.50071998 -36.52804226
OS -4.49239894 -36.53220278
OS -4.47991738 -36.53775014
OS -4.46466214 -36.54745802
OS -4.44802006 -36.55993958
OS -4.42999114 -36.57658166
OS -4.41334906 -36.59599742
OS -4.39670698 -36.61818686
OS -4.39670698 -36.6195737
OS -4.39532014 -36.62096054
OS -4.38977278 -36.62928158
OS -4.38422542 -36.64314998
OS -4.37590438 -36.6611789
OS -4.36897018 -36.6819815
OS -4.36203598 -36.70694462
OS -4.35787546 -36.73329458
OS -4.35648862 -36.76241822
OS -4.35648862 -36.76380506
OS -4.35648862 -36.76657874
OS -4.35648862 -36.7721261
OS -4.35787546 -36.7790603
OS -4.35787546 -36.78876818
OS -4.3592623 -36.79847606
OS -4.36480966 -36.82205234
OS -4.3731307 -36.84978914
OS -4.38422542 -36.87891278
OS -4.4008675 -36.90803642
OS -4.41196222 -36.92190482
OS -4.42305694 -36.93577322
OS -4.42444378 -36.93716006
OS -4.42583062 -36.9385469
OS -4.42999114 -36.94270742
OS -4.4355385 -36.94686794
OS -4.4424727 -36.9524153
OS -4.45079374 -36.95796266
OS -4.46188846 -36.96489686
OS -4.47298318 -36.9732179
OS -4.48685158 -36.9801521
OS -4.50210682 -36.9870863
OS -4.5187489 -36.99540734
OS -4.53677782 -37.00234154
OS -4.55758042 -37.0078889
OS -4.57838302 -37.0148231
OS -4.6019593 -37.01898362
OS -4.62692242 -37.02314414
OS -4.62414874 -37.02453098
OS -4.61860138 -37.02730466
OS -4.61028034 -37.03285202
OS -4.59918562 -37.03839938
OS -4.5742225 -37.05365462
OS -4.56174094 -37.0633625
OS -4.55064622 -37.07168354
OS -4.54787254 -37.07445722
OS -4.54093834 -37.08139142
OS -4.52984362 -37.09248614
OS -4.51597522 -37.10635454
OS -4.50071998 -37.1257703
OS -4.48269106 -37.1465729
OS -4.46466214 -37.17153602
OS -4.44524638 -37.19927282
OS -4.28021242 -37.45999874
OS -4.43831218 -37.45999874
OS -4.56451462 -37.26029378
OS -4.56451462 -37.25890694
OS -4.5672883 -37.25613326
OS -4.57006198 -37.25197274
OS -4.5742225 -37.24642538
OS -4.58393038 -37.23117014
OS -4.59641194 -37.21175438
OS -4.61166718 -37.19095178
OS -4.62692242 -37.16876234
OS -4.64217766 -37.14795974
OS -4.65604606 -37.12854398
OS -4.6574329 -37.12715714
OS -4.66159342 -37.12160978
OS -4.66852762 -37.11328874
OS -4.6782355 -37.10358086
OS -4.6990381 -37.08277826
OS -4.71013282 -37.07307038
OS -4.72122754 -37.06474934
OS -4.72261438 -37.0633625
OS -4.72538806 -37.06197566
OS -4.73093542 -37.05920198
OS -4.73925646 -37.05504146
OS -4.7475775 -37.05088094
OS -4.75728538 -37.04672042
OS -4.77947482 -37.03978622
OS -4.78086166 -37.03978622
OS -4.78363534 -37.03839938
OS -4.7891827 -37.03839938
OS -4.7961169 -37.03701254
OS -4.80582478 -37.0356257
OS -4.8169195 -37.0356257
OS -4.83217474 -37.03423886
OS -4.99582186 -37.03423886
OS -4.99582186 -37.45999874
OS -5.12341114 -37.45999874
OS -5.12341114 -36.50030546
OS -4.6782355 -36.50030546
OS -4.66714078 -36.5016923
OE
OB -1.0100437 -37.45999874 I
OS -1.13208562 -37.45999874
OS -1.13208562 -36.65701838
OS -1.4122273 -37.45999874
OS -1.52594818 -37.45999874
OS -1.80331618 -36.64314998
OS -1.80331618 -37.45999874
OS -1.9253581 -37.45999874
OS -1.9253581 -36.50030546
OS -1.73536102 -36.50030546
OS -1.50791926 -37.1812439
OS -1.50791926 -37.18263074
OS -1.50653242 -37.18540442
OS -1.50514558 -37.18956494
OS -1.5023719 -37.19649914
OS -1.49682454 -37.21314122
OS -1.48989034 -37.23394382
OS -1.48295614 -37.2575201
OS -1.4746351 -37.28109638
OS -1.4677009 -37.30328582
OS -1.46215354 -37.32270158
OS -1.4607667 -37.3199279
OS -1.45937986 -37.3129937
OS -1.45521934 -37.30051214
OS -1.44967198 -37.28387006
OS -1.44273778 -37.26168062
OS -1.4330299 -37.23533066
OS -1.42332202 -37.20482018
OS -1.41084046 -37.16876234
OS -1.18062502 -36.50030546
OS -1.0100437 -36.50030546
OS -1.0100437 -37.45999874
OE
OB -2.02382374 -37.45999874 I
OS -2.1680551 -37.45999874
OS -2.28038914 -37.16876234
OS -2.68257274 -37.16876234
OS -2.78658574 -37.45999874
OS -2.92110922 -37.45999874
OS -2.55498346 -36.50030546
OS -2.41629946 -36.50030546
OS -2.02382374 -37.45999874
OE
OB -3.02928274 -37.45999874 I
OS -3.16103254 -37.45999874
OS -3.66306862 -36.70694462
OS -3.66306862 -37.45999874
OS -3.78511054 -37.45999874
OS -3.78511054 -36.50030546
OS -3.65474758 -36.50030546
OS -3.15132466 -37.25474642
OS -3.15132466 -36.50030546
OS -3.02928274 -36.50030546
OS -3.02928274 -37.45999874
OE
OB -5.3231161 -36.61402634 I
OS -5.89033366 -36.61402634
OS -5.89033366 -36.90664958
OS -5.35917394 -36.90664958
OS -5.35917394 -37.02037046
OS -5.89033366 -37.02037046
OS -5.89033366 -37.34627786
OS -5.30092666 -37.34627786
OS -5.30092666 -37.45999874
OS -6.01792294 -37.45999874
OS -6.01792294 -36.50030546
OS -5.3231161 -36.50030546
OS -5.3231161 -36.61402634
OE
OB -0.10721086 -36.61402634 I
OS -0.67442842 -36.61402634
OS -0.67442842 -36.90664958
OS -0.1432687 -36.90664958
OS -0.1432687 -37.02037046
OS -0.67442842 -37.02037046
OS -0.67442842 -37.34627786
OS -0.08502142 -37.34627786
OS -0.08502142 -37.45999874
OS -0.8020177 -37.45999874
OS -0.8020177 -36.50030546
OS -0.10721086 -36.50030546
OS -0.10721086 -36.61402634
OE
OB -8.43241138 -37.34627786 I
OS -7.95949894 -37.34627786
OS -7.95949894 -37.45999874
OS -8.56000066 -37.45999874
OS -8.56000066 -36.50030546
OS -8.43241138 -36.50030546
OS -8.43241138 -37.34627786
OE
OB -6.51718534 -37.05365462 I
OS -6.51718534 -37.45999874
OS -6.64477462 -37.45999874
OS -6.64477462 -37.05365462
OS -7.0150609 -36.50030546
OS -6.86112166 -36.50030546
OS -6.67251142 -36.79154186
OS -6.67251142 -36.7929287
OS -6.66973774 -36.79570238
OS -6.66696406 -36.7998629
OS -6.66419038 -36.80541026
OS -6.65864302 -36.81234446
OS -6.65309566 -36.8206655
OS -6.6406141 -36.8414681
OS -6.62535886 -36.86643122
OS -6.60871678 -36.89416802
OS -6.59068786 -36.92329166
OS -6.57404578 -36.95380214
OS -6.57404578 -36.9524153
OS -6.57265894 -36.94964162
OS -6.56988526 -36.9454811
OS -6.56572474 -36.93993374
OS -6.56156422 -36.93299954
OS -6.55601686 -36.9246785
OS -6.5435353 -36.9038759
OS -6.52828006 -36.87891278
OS -6.51025114 -36.84978914
OS -6.48944854 -36.81789182
OS -6.4672591 -36.78322082
OS -6.28280938 -36.50030546
OS -6.1344175 -36.50030546
OS -6.51718534 -37.05365462
OE
OB -7.01644774 -37.45999874 I
OS -7.1606791 -37.45999874
OS -7.27301314 -37.16876234
OS -7.67519674 -37.16876234
OS -7.77920974 -37.45999874
OS -7.91373322 -37.45999874
OS -7.54760746 -36.50030546
OS -7.40892346 -36.50030546
OS -7.01644774 -37.45999874
OE
OB -7.48103914 -36.60015794 H
OS -7.48103914 -36.60154478
OS -7.48242598 -36.60431846
OS -7.48242598 -36.60986582
OS -7.48519966 -36.61541318
OS -7.4865865 -36.62512106
OS -7.48936018 -36.63482894
OS -7.49490754 -36.65840522
OS -7.50184174 -36.68614202
OS -7.51154962 -36.7166525
OS -7.5212575 -36.74993666
OS -7.53373906 -36.78460766
OS -7.63775206 -37.06474934
OS -7.3132315 -37.06474934
OS -7.41308398 -36.80124974
OS -7.41308398 -36.7998629
OS -7.41447082 -36.79570238
OS -7.4172445 -36.78876818
OS -7.42001818 -36.78044714
OS -7.4241787 -36.77073926
OS -7.42833922 -36.7582577
OS -7.43249974 -36.7443893
OS -7.4380471 -36.7305209
OS -7.44914182 -36.69862358
OS -7.46023654 -36.66533942
OS -7.47133126 -36.63205526
OS -7.48103914 -36.60015794
OE
OB -4.69349074 -36.60709214 H
OS -4.99582186 -36.60709214
OS -4.99582186 -36.9246785
OS -4.71013282 -36.9246785
OS -4.69349074 -36.92329166
OS -4.67407498 -36.92190482
OS -4.65188554 -36.92051798
OS -4.6296961 -36.9177443
OS -4.60750666 -36.91358378
OS -4.5880909 -36.90803642
OS -4.58531722 -36.90664958
OS -4.57976986 -36.9038759
OS -4.57144882 -36.89971538
OS -4.5603541 -36.89416802
OS -4.54787254 -36.88584698
OS -4.53539098 -36.8761391
OS -4.52290942 -36.86365754
OS -4.51320154 -36.84978914
OS -4.5118147 -36.8484023
OS -4.50904102 -36.84285494
OS -4.5048805 -36.8345339
OS -4.49933314 -36.82343918
OS -4.49517262 -36.81095762
OS -4.4910121 -36.79708922
OS -4.48823842 -36.78044714
OS -4.48685158 -36.76380506
OS -4.48685158 -36.76241822
OS -4.48685158 -36.76103138
OS -4.48823842 -36.75271034
OS -4.48962526 -36.74022878
OS -4.49239894 -36.7235867
OS -4.49933314 -36.70694462
OS -4.50765418 -36.68752886
OS -4.52013574 -36.66949994
OS -4.53677782 -36.65147102
OS -4.5395515 -36.65008418
OS -4.5464857 -36.64453682
OS -4.55758042 -36.63760262
OS -4.57560934 -36.62928158
OS -4.59641194 -36.62096054
OS -4.62414874 -36.61402634
OS -4.65604606 -36.60847898
OS -4.69349074 -36.60709214
OE
OB -2.48841514 -36.60015794 H
OS -2.48841514 -36.60154478
OS -2.48980198 -36.60431846
OS -2.48980198 -36.60986582
OS -2.49257566 -36.61541318
OS -2.4939625 -36.62512106
OS -2.49673618 -36.63482894
OS -2.50228354 -36.65840522
OS -2.50921774 -36.68614202
OS -2.51892562 -36.7166525
OS -2.5286335 -36.74993666
OS -2.54111506 -36.78460766
OS -2.64512806 -37.06474934
OS -2.3206075 -37.06474934
OS -2.42045998 -36.80124974
OS -2.42045998 -36.7998629
OS -2.42184682 -36.79570238
OS -2.4246205 -36.78876818
OS -2.42739418 -36.78044714
OS -2.4315547 -36.77073926
OS -2.43571522 -36.7582577
OS -2.43987574 -36.7443893
OS -2.4454231 -36.7305209
OS -2.45651782 -36.69862358
OS -2.46761254 -36.66533942
OS -2.47870726 -36.63205526
OS -2.48841514 -36.60015794
OE
SE
S P 0
OB 35.73690338 -37.45999874 I
OS 35.61486146 -37.45999874
OS 35.61486146 -36.65701838
OS 35.33471978 -37.45999874
OS 35.2209989 -37.45999874
OS 34.9436309 -36.64314998
OS 34.9436309 -37.45999874
OS 34.82158898 -37.45999874
OS 34.82158898 -36.50030546
OS 35.01158606 -36.50030546
OS 35.23902782 -37.1812439
OS 35.23902782 -37.18263074
OS 35.24041466 -37.18540442
OS 35.2418015 -37.18956494
OS 35.24457518 -37.19649914
OS 35.25012254 -37.21314122
OS 35.25705674 -37.23394382
OS 35.26399094 -37.2575201
OS 35.27231198 -37.28109638
OS 35.27924618 -37.30328582
OS 35.28479354 -37.32270158
OS 35.28618038 -37.3199279
OS 35.28756722 -37.3129937
OS 35.29172774 -37.30051214
OS 35.2972751 -37.28387006
OS 35.3042093 -37.26168062
OS 35.31391718 -37.23533066
OS 35.32362506 -37.20482018
OS 35.33610662 -37.16876234
OS 35.56632206 -36.50030546
OS 35.73690338 -36.50030546
OS 35.73690338 -37.45999874
OE
OB 34.61356298 -37.05504146 I
OS 34.61356298 -37.0564283
OS 34.61356298 -37.06197566
OS 34.61356298 -37.06890986
OS 34.61356298 -37.07861774
OS 34.61217614 -37.0910993
OS 34.61217614 -37.1049677
OS 34.6107893 -37.12160978
OS 34.60940246 -37.13825186
OS 34.60524194 -37.17569654
OS 34.59969458 -37.21452806
OS 34.59137354 -37.25197274
OS 34.58582618 -37.27000166
OS 34.58027882 -37.28664374
OS 34.58027882 -37.28803058
OS 34.57889198 -37.29080426
OS 34.5761183 -37.29496478
OS 34.57334462 -37.30051214
OS 34.56502358 -37.31576738
OS 34.55254202 -37.33518314
OS 34.53589994 -37.35737258
OS 34.51648418 -37.37956202
OS 34.49152106 -37.4031383
OS 34.46101058 -37.4239409
OS 34.45962374 -37.4239409
OS 34.45685006 -37.42671458
OS 34.45268954 -37.42810142
OS 34.44575534 -37.43226194
OS 34.4374343 -37.43642246
OS 34.42633958 -37.44058298
OS 34.41524486 -37.4447435
OS 34.40137646 -37.45029086
OS 34.38612122 -37.45583822
OS 34.36947914 -37.45999874
OS 34.35145022 -37.46415926
OS 34.33064762 -37.46831978
OS 34.30984502 -37.47109346
OS 34.28765558 -37.47386714
OS 34.23772934 -37.47664082
OS 34.22524778 -37.47664082
OS 34.2155399 -37.47525398
OS 34.20444518 -37.47525398
OS 34.19057678 -37.47386714
OS 34.17532154 -37.4724803
OS 34.1600663 -37.47109346
OS 34.1253953 -37.4655461
OS 34.08795062 -37.45722506
OS 34.05189278 -37.44613034
OS 34.01722178 -37.4308751
OS 34.01583494 -37.4308751
OS 34.01306126 -37.42810142
OS 34.00890074 -37.42532774
OS 34.00335338 -37.42255406
OS 33.98809814 -37.41145934
OS 33.97006922 -37.3962041
OS 33.94926662 -37.37678834
OS 33.92985086 -37.3545989
OS 33.9104351 -37.3268621
OS 33.89517986 -37.29635162
OS 33.89517986 -37.29496478
OS 33.89379302 -37.2921911
OS 33.89240618 -37.28664374
OS 33.8896325 -37.27970954
OS 33.88685882 -37.2713885
OS 33.88408514 -37.26029378
OS 33.87992462 -37.24781222
OS 33.87715094 -37.23255698
OS 33.87437726 -37.2159149
OS 33.87021674 -37.19788598
OS 33.86744306 -37.17847022
OS 33.86466938 -37.15766762
OS 33.8618957 -37.13409134
OS 33.86050886 -37.10912822
OS 33.85912202 -37.08277826
OS 33.85912202 -37.05504146
OS 33.85912202 -36.50030546
OS 33.9867113 -36.50030546
OS 33.9867113 -37.05504146
OS 33.9867113 -37.0564283
OS 33.9867113 -37.06058882
OS 33.9867113 -37.06752302
OS 33.9867113 -37.07584406
OS 33.98809814 -37.08555194
OS 33.98809814 -37.0980335
OS 33.98948498 -37.12438346
OS 33.99225866 -37.15489394
OS 33.99641918 -37.18540442
OS 34.00196654 -37.21452806
OS 34.00474022 -37.22700962
OS 34.00890074 -37.23949118
OS 34.01028758 -37.24226486
OS 34.01306126 -37.24919906
OS 34.01999546 -37.25890694
OS 34.0283165 -37.27277534
OS 34.03802438 -37.28664374
OS 34.05189278 -37.30189898
OS 34.06853486 -37.31715422
OS 34.08795062 -37.32963578
OS 34.0907243 -37.33102262
OS 34.0976585 -37.33518314
OS 34.11014006 -37.33934366
OS 34.12678214 -37.34489102
OS 34.1461979 -37.35182522
OS 34.17116102 -37.35598574
OS 34.19751098 -37.36014626
OS 34.22663462 -37.3615331
OS 34.24050302 -37.3615331
OS 34.24882406 -37.36014626
OS 34.26130562 -37.36014626
OS 34.27378718 -37.35875942
OS 34.30429766 -37.35321206
OS 34.33758182 -37.34627786
OS 34.36947914 -37.33518314
OS 34.39998962 -37.3199279
OS 34.41385802 -37.31022002
OS 34.42633958 -37.2991253
OS 34.42772642 -37.29773846
OS 34.42911326 -37.29635162
OS 34.43188694 -37.2921911
OS 34.43604746 -37.28664374
OS 34.44020798 -37.2783227
OS 34.44575534 -37.27000166
OS 34.4513027 -37.2575201
OS 34.45685006 -37.24503854
OS 34.46239742 -37.2297833
OS 34.46655794 -37.21175438
OS 34.4721053 -37.19095178
OS 34.47626582 -37.16876234
OS 34.48042634 -37.14379922
OS 34.48320002 -37.11744926
OS 34.4859737 -37.08693878
OS 34.4859737 -37.05504146
OS 34.4859737 -36.50030546
OS 34.61356298 -36.50030546
OS 34.61356298 -37.05504146
OE
OB 33.64416182 -37.45999874 I
OS 33.51241202 -37.45999874
OS 33.01037594 -36.70694462
OS 33.01037594 -37.45999874
OS 32.88833402 -37.45999874
OS 32.88833402 -36.50030546
OS 33.01869698 -36.50030546
OS 33.5221199 -37.25474642
OS 33.5221199 -36.50030546
OS 33.64416182 -36.50030546
OS 33.64416182 -37.45999874
OE
OB 38.19022334 -36.5016923 I
OS 38.2027049 -36.5016923
OS 38.23182854 -36.50307914
OS 38.26233902 -36.50723966
OS 38.29562318 -36.51140018
OS 38.32613366 -36.51833438
OS 38.3413889 -36.5224949
OS 38.35387046 -36.52665542
OS 38.3552573 -36.52665542
OS 38.35664414 -36.52804226
OS 38.36496518 -36.53220278
OS 38.37744674 -36.53775014
OS 38.39270198 -36.54745802
OS 38.40934406 -36.55993958
OS 38.42737298 -36.57658166
OS 38.44401506 -36.59599742
OS 38.46065714 -36.61818686
OS 38.46065714 -36.6195737
OS 38.46204398 -36.62096054
OS 38.46759134 -36.62928158
OS 38.4731387 -36.64314998
OS 38.48145974 -36.6611789
OS 38.48839394 -36.6819815
OS 38.49532814 -36.70694462
OS 38.49948866 -36.73329458
OS 38.5008755 -36.76241822
OS 38.5008755 -36.76380506
OS 38.5008755 -36.76657874
OS 38.5008755 -36.7721261
OS 38.49948866 -36.7790603
OS 38.49948866 -36.78876818
OS 38.49810182 -36.79847606
OS 38.49255446 -36.82205234
OS 38.48423342 -36.84978914
OS 38.4731387 -36.87891278
OS 38.45649662 -36.90803642
OS 38.4454019 -36.92190482
OS 38.43430718 -36.93577322
OS 38.43292034 -36.93716006
OS 38.4315335 -36.9385469
OS 38.42737298 -36.94270742
OS 38.42182562 -36.94686794
OS 38.41489142 -36.9524153
OS 38.40657038 -36.95796266
OS 38.39547566 -36.96489686
OS 38.38438094 -36.9732179
OS 38.37051254 -36.9801521
OS 38.3552573 -36.9870863
OS 38.33861522 -36.99540734
OS 38.3205863 -37.00234154
OS 38.2997837 -37.0078889
OS 38.2789811 -37.0148231
OS 38.25540482 -37.01898362
OS 38.2304417 -37.02314414
OS 38.23321538 -37.02453098
OS 38.23876274 -37.02730466
OS 38.24708378 -37.03285202
OS 38.2581785 -37.03839938
OS 38.28314162 -37.05365462
OS 38.29562318 -37.0633625
OS 38.3067179 -37.07168354
OS 38.30949158 -37.07445722
OS 38.31642578 -37.08139142
OS 38.3275205 -37.09248614
OS 38.3413889 -37.10635454
OS 38.35664414 -37.1257703
OS 38.37467306 -37.1465729
OS 38.39270198 -37.17153602
OS 38.41211774 -37.19927282
OS 38.5771517 -37.45999874
OS 38.41905194 -37.45999874
OS 38.2928495 -37.26029378
OS 38.2928495 -37.25890694
OS 38.29007582 -37.25613326
OS 38.28730214 -37.25197274
OS 38.28314162 -37.24642538
OS 38.27343374 -37.23117014
OS 38.26095218 -37.21175438
OS 38.24569694 -37.19095178
OS 38.2304417 -37.16876234
OS 38.21518646 -37.14795974
OS 38.20131806 -37.12854398
OS 38.19993122 -37.12715714
OS 38.1957707 -37.12160978
OS 38.1888365 -37.11328874
OS 38.17912862 -37.10358086
OS 38.15832602 -37.08277826
OS 38.1472313 -37.07307038
OS 38.13613658 -37.06474934
OS 38.13474974 -37.0633625
OS 38.13197606 -37.06197566
OS 38.1264287 -37.05920198
OS 38.11810766 -37.05504146
OS 38.10978662 -37.05088094
OS 38.10007874 -37.04672042
OS 38.0778893 -37.03978622
OS 38.07650246 -37.03978622
OS 38.07372878 -37.03839938
OS 38.06818142 -37.03839938
OS 38.06124722 -37.03701254
OS 38.05153934 -37.0356257
OS 38.04044462 -37.0356257
OS 38.02518938 -37.03423886
OS 37.86154226 -37.03423886
OS 37.86154226 -37.45999874
OS 37.73395298 -37.45999874
OS 37.73395298 -36.50030546
OS 38.17912862 -36.50030546
OS 38.19022334 -36.5016923
OE
OB 37.53424802 -36.61402634 I
OS 36.96703046 -36.61402634
OS 36.96703046 -36.90664958
OS 37.49819018 -36.90664958
OS 37.49819018 -37.02037046
OS 36.96703046 -37.02037046
OS 36.96703046 -37.34627786
OS 37.55643746 -37.34627786
OS 37.55643746 -37.45999874
OS 36.83944118 -37.45999874
OS 36.83944118 -36.50030546
OS 37.53424802 -36.50030546
OS 37.53424802 -36.61402634
OE
OB 36.32492354 -36.5016923 I
OS 36.33601826 -36.5016923
OS 36.36098138 -36.50446598
OS 36.38871818 -36.50723966
OS 36.41784182 -36.51278702
OS 36.44696546 -36.51972122
OS 36.47331542 -36.5294291
OS 36.47470226 -36.5294291
OS 36.4760891 -36.53081594
OS 36.48441014 -36.53497646
OS 36.4968917 -36.54191066
OS 36.5107601 -36.55161854
OS 36.52740218 -36.5641001
OS 36.5454311 -36.57935534
OS 36.56207318 -36.5987711
OS 36.57732842 -36.6195737
OS 36.57871526 -36.62234738
OS 36.58287578 -36.63066842
OS 36.58980998 -36.64176314
OS 36.59674418 -36.65840522
OS 36.60367838 -36.67782098
OS 36.61061258 -36.69862358
OS 36.6147731 -36.72219986
OS 36.61615994 -36.74577614
OS 36.61615994 -36.74854982
OS 36.61615994 -36.75548402
OS 36.6147731 -36.76796558
OS 36.61199942 -36.78322082
OS 36.6078389 -36.80124974
OS 36.6009047 -36.8206655
OS 36.59258366 -36.84008126
OS 36.58148894 -36.86088386
OS 36.5801021 -36.86365754
OS 36.57594158 -36.8692049
OS 36.56762054 -36.88029962
OS 36.55652582 -36.89139434
OS 36.54265742 -36.90526274
OS 36.52601534 -36.92051798
OS 36.50521274 -36.93438638
OS 36.48163646 -36.94825478
OS 36.4830233 -36.94825478
OS 36.48579698 -36.94964162
OS 36.4899575 -36.95102846
OS 36.49550486 -36.95380214
OS 36.51214694 -36.9593495
OS 36.5315627 -36.96905738
OS 36.5523653 -36.98153894
OS 36.57594158 -36.99679418
OS 36.59674418 -37.0148231
OS 36.61615994 -37.03701254
OS 36.61754678 -37.03978622
OS 36.62309414 -37.04810726
OS 36.63141518 -37.06058882
OS 36.63973622 -37.0772309
OS 36.64805726 -37.09942034
OS 36.6563783 -37.12299662
OS 36.66192566 -37.15073342
OS 36.6633125 -37.1812439
OS 36.6633125 -37.18263074
OS 36.6633125 -37.18401758
OS 36.6633125 -37.19233862
OS 36.66192566 -37.20620702
OS 36.65915198 -37.2228491
OS 36.6563783 -37.24226486
OS 36.65083094 -37.26306746
OS 36.64389674 -37.2852569
OS 36.63418886 -37.30744634
OS 36.63280202 -37.31022002
OS 36.6286415 -37.31715422
OS 36.62309414 -37.3268621
OS 36.6147731 -37.3407305
OS 36.60367838 -37.3545989
OS 36.59258366 -37.36985414
OS 36.57871526 -37.38510938
OS 36.56346002 -37.39759094
OS 36.56207318 -37.39897778
OS 36.55652582 -37.4031383
OS 36.54681794 -37.40868566
OS 36.53433638 -37.41423302
OS 36.51908114 -37.42255406
OS 36.50105222 -37.4308751
OS 36.48163646 -37.4378093
OS 36.45806018 -37.4447435
OS 36.4552865 -37.4447435
OS 36.44696546 -37.44751718
OS 36.43309706 -37.44890402
OS 36.41506814 -37.4516777
OS 36.3928787 -37.45445138
OS 36.36652874 -37.45722506
OS 36.3374051 -37.4586119
OS 36.30412094 -37.45999874
OS 35.93799518 -37.45999874
OS 35.93799518 -36.50030546
OS 36.31521566 -36.50030546
OS 36.32492354 -36.5016923
OE
OB 32.3849111 -36.61402634 I
OS 32.06871158 -36.61402634
OS 32.06871158 -37.45999874
OS 31.9411223 -37.45999874
OS 31.9411223 -36.61402634
OS 31.62492278 -36.61402634
OS 31.62492278 -36.50030546
OS 32.3849111 -36.50030546
OS 32.3849111 -36.61402634
OE
OB 30.62639798 -37.45999874 I
OS 30.48216662 -37.45999874
OS 30.36983258 -37.16876234
OS 29.96764898 -37.16876234
OS 29.86363598 -37.45999874
OS 29.7291125 -37.45999874
OS 30.09523826 -36.50030546
OS 30.23392226 -36.50030546
OS 30.62639798 -37.45999874
OE
OB 29.3546657 -36.5016923 I
OS 29.37824198 -36.50307914
OS 29.4032051 -36.50446598
OS 29.42678138 -36.50723966
OS 29.44758398 -36.51001334
OS 29.45035766 -36.51001334
OS 29.46006554 -36.51278702
OS 29.4725471 -36.5155607
OS 29.48918918 -36.51972122
OS 29.5072181 -36.52665542
OS 29.52663386 -36.53497646
OS 29.54743646 -36.54468434
OS 29.56546538 -36.55577906
OS 29.56823906 -36.5571659
OS 29.57378642 -36.56132642
OS 29.58210746 -36.56964746
OS 29.59320218 -36.57935534
OS 29.60568374 -36.5918369
OS 29.6181653 -36.60847898
OS 29.6320337 -36.6265079
OS 29.64312842 -36.6473105
OS 29.64451526 -36.65008418
OS 29.64728894 -36.65701838
OS 29.6528363 -36.66949994
OS 29.65838366 -36.68614202
OS 29.66254418 -36.70555778
OS 29.66809154 -36.72774722
OS 29.67086522 -36.75271034
OS 29.67225206 -36.7790603
OS 29.67225206 -36.78044714
OS 29.67225206 -36.78460766
OS 29.67225206 -36.79015502
OS 29.67086522 -36.7998629
OS 29.66947838 -36.80957078
OS 29.66809154 -36.82205234
OS 29.66531786 -36.83592074
OS 29.66254418 -36.85117598
OS 29.6528363 -36.8830733
OS 29.64728894 -36.89971538
OS 29.6389679 -36.9177443
OS 29.62926002 -36.93577322
OS 29.61955214 -36.9524153
OS 29.60707058 -36.96905738
OS 29.59320218 -36.98569946
OS 29.59181534 -36.9870863
OS 29.58904166 -36.98985998
OS 29.58488114 -36.9940205
OS 29.57794694 -36.99818102
OS 29.5696259 -37.00511522
OS 29.55853118 -37.01204942
OS 29.54466278 -37.02037046
OS 29.52940754 -37.02730466
OS 29.51137862 -37.0356257
OS 29.49057602 -37.04394674
OS 29.46838658 -37.05088094
OS 29.44203662 -37.0564283
OS 29.41429982 -37.06197566
OS 29.38378934 -37.06613618
OS 29.34911834 -37.06890986
OS 29.3130605 -37.0702967
OS 29.06758982 -37.0702967
OS 29.06758982 -37.45999874
OS 28.94000054 -37.45999874
OS 28.94000054 -36.50030546
OS 29.3338631 -36.50030546
OS 29.3546657 -36.5016923
OE
OB 31.18668134 -36.5016923 I
OS 31.1991629 -36.5016923
OS 31.22828654 -36.50307914
OS 31.25879702 -36.50723966
OS 31.29208118 -36.51140018
OS 31.32259166 -36.51833438
OS 31.3378469 -36.5224949
OS 31.35032846 -36.52665542
OS 31.3517153 -36.52665542
OS 31.35310214 -36.52804226
OS 31.36142318 -36.53220278
OS 31.37390474 -36.53775014
OS 31.38915998 -36.54745802
OS 31.40580206 -36.55993958
OS 31.42383098 -36.57658166
OS 31.44047306 -36.59599742
OS 31.45711514 -36.61818686
OS 31.45711514 -36.6195737
OS 31.45850198 -36.62096054
OS 31.46404934 -36.62928158
OS 31.4695967 -36.64314998
OS 31.47791774 -36.6611789
OS 31.48485194 -36.6819815
OS 31.49178614 -36.70694462
OS 31.49594666 -36.73329458
OS 31.4973335 -36.76241822
OS 31.4973335 -36.76380506
OS 31.4973335 -36.76657874
OS 31.4973335 -36.7721261
OS 31.49594666 -36.7790603
OS 31.49594666 -36.78876818
OS 31.49455982 -36.79847606
OS 31.48901246 -36.82205234
OS 31.48069142 -36.84978914
OS 31.4695967 -36.87891278
OS 31.45295462 -36.90803642
OS 31.4418599 -36.92190482
OS 31.43076518 -36.93577322
OS 31.42937834 -36.93716006
OS 31.4279915 -36.9385469
OS 31.42383098 -36.94270742
OS 31.41828362 -36.94686794
OS 31.41134942 -36.9524153
OS 31.40302838 -36.95796266
OS 31.39193366 -36.96489686
OS 31.38083894 -36.9732179
OS 31.36697054 -36.9801521
OS 31.3517153 -36.9870863
OS 31.33507322 -36.99540734
OS 31.3170443 -37.00234154
OS 31.2962417 -37.0078889
OS 31.2754391 -37.0148231
OS 31.25186282 -37.01898362
OS 31.2268997 -37.02314414
OS 31.22967338 -37.02453098
OS 31.23522074 -37.02730466
OS 31.24354178 -37.03285202
OS 31.2546365 -37.03839938
OS 31.27959962 -37.05365462
OS 31.29208118 -37.0633625
OS 31.3031759 -37.07168354
OS 31.30594958 -37.07445722
OS 31.31288378 -37.08139142
OS 31.3239785 -37.09248614
OS 31.3378469 -37.10635454
OS 31.35310214 -37.1257703
OS 31.37113106 -37.1465729
OS 31.38915998 -37.17153602
OS 31.40857574 -37.19927282
OS 31.5736097 -37.45999874
OS 31.41550994 -37.45999874
OS 31.2893075 -37.26029378
OS 31.2893075 -37.25890694
OS 31.28653382 -37.25613326
OS 31.28376014 -37.25197274
OS 31.27959962 -37.24642538
OS 31.26989174 -37.23117014
OS 31.25741018 -37.21175438
OS 31.24215494 -37.19095178
OS 31.2268997 -37.16876234
OS 31.21164446 -37.14795974
OS 31.19777606 -37.12854398
OS 31.19638922 -37.12715714
OS 31.1922287 -37.12160978
OS 31.1852945 -37.11328874
OS 31.17558662 -37.10358086
OS 31.15478402 -37.08277826
OS 31.1436893 -37.07307038
OS 31.13259458 -37.06474934
OS 31.13120774 -37.0633625
OS 31.12843406 -37.06197566
OS 31.1228867 -37.05920198
OS 31.11456566 -37.05504146
OS 31.10624462 -37.05088094
OS 31.09653674 -37.04672042
OS 31.0743473 -37.03978622
OS 31.07296046 -37.03978622
OS 31.07018678 -37.03839938
OS 31.06463942 -37.03839938
OS 31.05770522 -37.03701254
OS 31.04799734 -37.0356257
OS 31.03690262 -37.0356257
OS 31.02164738 -37.03423886
OS 30.85800026 -37.03423886
OS 30.85800026 -37.45999874
OS 30.73041098 -37.45999874
OS 30.73041098 -36.50030546
OS 31.17558662 -36.50030546
OS 31.18668134 -36.5016923
OE
OB 38.16387338 -36.60709214 H
OS 37.86154226 -36.60709214
OS 37.86154226 -36.9246785
OS 38.1472313 -36.9246785
OS 38.16387338 -36.92329166
OS 38.18328914 -36.92190482
OS 38.20547858 -36.92051798
OS 38.22766802 -36.9177443
OS 38.24985746 -36.91358378
OS 38.26927322 -36.90803642
OS 38.2720469 -36.90664958
OS 38.27759426 -36.9038759
OS 38.2859153 -36.89971538
OS 38.29701002 -36.89416802
OS 38.30949158 -36.88584698
OS 38.32197314 -36.8761391
OS 38.3344547 -36.86365754
OS 38.34416258 -36.84978914
OS 38.34554942 -36.8484023
OS 38.3483231 -36.84285494
OS 38.35248362 -36.8345339
OS 38.35803098 -36.82343918
OS 38.3621915 -36.81095762
OS 38.36635202 -36.79708922
OS 38.3691257 -36.78044714
OS 38.37051254 -36.76380506
OS 38.37051254 -36.76241822
OS 38.37051254 -36.76103138
OS 38.3691257 -36.75271034
OS 38.36773886 -36.74022878
OS 38.36496518 -36.7235867
OS 38.35803098 -36.70694462
OS 38.34970994 -36.68752886
OS 38.33722838 -36.66949994
OS 38.3205863 -36.65147102
OS 38.31781262 -36.65008418
OS 38.31087842 -36.64453682
OS 38.2997837 -36.63760262
OS 38.28175478 -36.62928158
OS 38.26095218 -36.62096054
OS 38.23321538 -36.61402634
OS 38.20131806 -36.60847898
OS 38.16387338 -36.60709214
OE
OB 29.34218414 -36.61402634 H
OS 29.06758982 -36.61402634
OS 29.06758982 -36.95657582
OS 29.32554206 -36.95657582
OS 29.33524994 -36.95518898
OS 29.34495782 -36.95518898
OS 29.35605254 -36.95380214
OS 29.3824025 -36.95102846
OS 29.41152614 -36.9454811
OS 29.44064978 -36.93716006
OS 29.46699974 -36.92606534
OS 29.4794813 -36.91913114
OS 29.48918918 -36.9108101
OS 29.49196286 -36.90803642
OS 29.49751022 -36.90248906
OS 29.50583126 -36.89139434
OS 29.51553914 -36.87752594
OS 29.52524702 -36.85949702
OS 29.53356806 -36.83730758
OS 29.53911542 -36.81234446
OS 29.5418891 -36.78322082
OS 29.5418891 -36.78183398
OS 29.5418891 -36.78044714
OS 29.5418891 -36.77351294
OS 29.54050226 -36.76103138
OS 29.53772858 -36.74716298
OS 29.5349549 -36.73190774
OS 29.52940754 -36.71387882
OS 29.5210865 -36.69723674
OS 29.51137862 -36.68059466
OS 29.50999178 -36.67920782
OS 29.50583126 -36.67366046
OS 29.49889706 -36.66672626
OS 29.49057602 -36.65701838
OS 29.47809446 -36.6473105
OS 29.46422606 -36.63898946
OS 29.44897082 -36.63066842
OS 29.4309419 -36.62373422
OS 29.42955506 -36.62373422
OS 29.4240077 -36.62234738
OS 29.41568666 -36.62096054
OS 29.40459194 -36.61818686
OS 29.38794986 -36.61680002
OS 29.36714726 -36.61541318
OS 29.34218414 -36.61402634
OE
OB 30.16180658 -36.60015794 H
OS 30.16180658 -36.60154478
OS 30.16041974 -36.60431846
OS 30.16041974 -36.60986582
OS 30.15764606 -36.61541318
OS 30.15625922 -36.62512106
OS 30.15348554 -36.63482894
OS 30.14793818 -36.65840522
OS 30.14100398 -36.68614202
OS 30.1312961 -36.7166525
OS 30.12158822 -36.74993666
OS 30.10910666 -36.78460766
OS 30.00509366 -37.06474934
OS 30.32961422 -37.06474934
OS 30.22976174 -36.80124974
OS 30.22976174 -36.7998629
OS 30.2283749 -36.79570238
OS 30.22560122 -36.78876818
OS 30.22282754 -36.78044714
OS 30.21866702 -36.77073926
OS 30.2145065 -36.7582577
OS 30.21034598 -36.7443893
OS 30.20479862 -36.7305209
OS 30.1937039 -36.69862358
OS 30.18260918 -36.66533942
OS 30.17151446 -36.63205526
OS 30.16180658 -36.60015794
OE
OB 31.16033138 -36.60709214 H
OS 30.85800026 -36.60709214
OS 30.85800026 -36.9246785
OS 31.1436893 -36.9246785
OS 31.16033138 -36.92329166
OS 31.17974714 -36.92190482
OS 31.20193658 -36.92051798
OS 31.22412602 -36.9177443
OS 31.24631546 -36.91358378
OS 31.26573122 -36.90803642
OS 31.2685049 -36.90664958
OS 31.27405226 -36.9038759
OS 31.2823733 -36.89971538
OS 31.29346802 -36.89416802
OS 31.30594958 -36.88584698
OS 31.31843114 -36.8761391
OS 31.3309127 -36.86365754
OS 31.34062058 -36.84978914
OS 31.34200742 -36.8484023
OS 31.3447811 -36.84285494
OS 31.34894162 -36.8345339
OS 31.35448898 -36.82343918
OS 31.3586495 -36.81095762
OS 31.36281002 -36.79708922
OS 31.3655837 -36.78044714
OS 31.36697054 -36.76380506
OS 31.36697054 -36.76241822
OS 31.36697054 -36.76103138
OS 31.3655837 -36.75271034
OS 31.36419686 -36.74022878
OS 31.36142318 -36.7235867
OS 31.35448898 -36.70694462
OS 31.34616794 -36.68752886
OS 31.33368638 -36.66949994
OS 31.3170443 -36.65147102
OS 31.31427062 -36.65008418
OS 31.30733642 -36.64453682
OS 31.2962417 -36.63760262
OS 31.27821278 -36.62928158
OS 31.25741018 -36.62096054
OS 31.22967338 -36.61402634
OS 31.19777606 -36.60847898
OS 31.16033138 -36.60709214
OE
OB 36.29302622 -36.61402634 H
OS 36.06558446 -36.61402634
OS 36.06558446 -36.90248906
OS 36.30134726 -36.90248906
OS 36.31937618 -36.90110222
OS 36.33879194 -36.89971538
OS 36.3582077 -36.89832854
OS 36.37762346 -36.89555486
OS 36.3928787 -36.89278118
OS 36.39565238 -36.89139434
OS 36.40119974 -36.8900075
OS 36.40952078 -36.88584698
OS 36.4206155 -36.88029962
OS 36.43171022 -36.87475226
OS 36.44419178 -36.86643122
OS 36.45667334 -36.8553365
OS 36.46638122 -36.84424178
OS 36.46776806 -36.84285494
OS 36.47054174 -36.83869442
OS 36.47470226 -36.83037338
OS 36.47886278 -36.8206655
OS 36.4830233 -36.80957078
OS 36.48718382 -36.79570238
OS 36.4899575 -36.7790603
OS 36.49134434 -36.76103138
OS 36.49134434 -36.7582577
OS 36.49134434 -36.75271034
OS 36.4899575 -36.7443893
OS 36.48857066 -36.73329458
OS 36.48579698 -36.71942618
OS 36.48163646 -36.70555778
OS 36.4760891 -36.69168938
OS 36.46776806 -36.67782098
OS 36.46638122 -36.67643414
OS 36.46360754 -36.67227362
OS 36.45806018 -36.66533942
OS 36.45112598 -36.65840522
OS 36.4414181 -36.65008418
OS 36.43032338 -36.64176314
OS 36.41645498 -36.6334421
OS 36.40119974 -36.62789474
OS 36.3998129 -36.62789474
OS 36.3928787 -36.62512106
OS 36.38317082 -36.62373422
OS 36.36791558 -36.62096054
OS 36.34711298 -36.61818686
OS 36.3235367 -36.61680002
OS 36.29302622 -36.61402634
OE
OB 36.31798934 -37.01620994 H
OS 36.06558446 -37.01620994
OS 36.06558446 -37.34627786
OS 36.33879194 -37.34627786
OS 36.36791558 -37.34489102
OS 36.38039714 -37.34350418
OS 36.39149186 -37.34211734
OS 36.3928787 -37.34211734
OS 36.39842606 -37.3407305
OS 36.4067471 -37.33934366
OS 36.41645498 -37.33656998
OS 36.44003126 -37.32824894
OS 36.46360754 -37.31715422
OS 36.46499438 -37.31576738
OS 36.4691549 -37.3129937
OS 36.47470226 -37.30883318
OS 36.48163646 -37.30328582
OS 36.48857066 -37.29496478
OS 36.49827854 -37.28664374
OS 36.50521274 -37.27554902
OS 36.51353378 -37.26306746
OS 36.51492062 -37.26168062
OS 36.51630746 -37.2575201
OS 36.51908114 -37.24919906
OS 36.52324166 -37.23949118
OS 36.52740218 -37.22839646
OS 36.53017586 -37.21452806
OS 36.5315627 -37.19788598
OS 36.53294954 -37.1812439
OS 36.53294954 -37.17847022
OS 36.53294954 -37.17292286
OS 36.5315627 -37.16182814
OS 36.52878902 -37.14934658
OS 36.52601534 -37.13547818
OS 36.52046798 -37.12022294
OS 36.51353378 -37.1049677
OS 36.5038259 -37.08971246
OS 36.50243906 -37.08832562
OS 36.49827854 -37.08277826
OS 36.49273118 -37.07584406
OS 36.48441014 -37.06752302
OS 36.47331542 -37.05781514
OS 36.45944702 -37.04810726
OS 36.44419178 -37.03978622
OS 36.42616286 -37.03285202
OS 36.42338918 -37.03146518
OS 36.41784182 -37.03007834
OS 36.40536026 -37.02730466
OS 36.39010502 -37.02453098
OS 36.37068926 -37.0217573
OS 36.34711298 -37.01898362
OS 36.31798934 -37.01620994
OE
SE
S P 0
OB 40.9056459 -38.32112732 I
OS 40.92136342 -38.32205188
OS 40.9380055 -38.32297644
OS 40.95372302 -38.32482556
OS 40.96759142 -38.32667468
OS 40.96944054 -38.32667468
OS 40.97591246 -38.3285238
OS 40.9842335 -38.33037292
OS 40.99532822 -38.3331466
OS 41.0073475 -38.3377694
OS 41.02029134 -38.34331676
OS 41.03415974 -38.34978868
OS 41.04617902 -38.35718516
OS 41.04802814 -38.35810972
OS 41.05172638 -38.3608834
OS 41.05727374 -38.36643076
OS 41.06467022 -38.37290268
OS 41.07299126 -38.38122372
OS 41.0813123 -38.39231844
OS 41.0905579 -38.40433772
OS 41.09795438 -38.41820612
OS 41.09887894 -38.42005524
OS 41.10072806 -38.42467804
OS 41.1044263 -38.43299908
OS 41.10812454 -38.4440938
OS 41.11089822 -38.45703764
OS 41.11459646 -38.4718306
OS 41.11644558 -38.48847268
OS 41.11737014 -38.50603932
OS 41.11737014 -38.50696388
OS 41.11737014 -38.50973756
OS 41.11737014 -38.5134358
OS 41.11644558 -38.51990772
OS 41.11552102 -38.52637964
OS 41.11459646 -38.53470068
OS 41.11274734 -38.54394628
OS 41.11089822 -38.55411644
OS 41.1044263 -38.57538132
OS 41.10072806 -38.58647604
OS 41.0951807 -38.59849532
OS 41.08870878 -38.6105146
OS 41.08223686 -38.62160932
OS 41.07391582 -38.63270404
OS 41.06467022 -38.64379876
OS 41.06374566 -38.64472332
OS 41.06189654 -38.64657244
OS 41.05912286 -38.64934612
OS 41.05450006 -38.6521198
OS 41.0489527 -38.6567426
OS 41.04155622 -38.6613654
OS 41.03231062 -38.66691276
OS 41.02214046 -38.67153556
OS 41.01012118 -38.67708292
OS 40.99625278 -38.68263028
OS 40.98145982 -38.68725308
OS 40.96389318 -38.69095132
OS 40.94540198 -38.69464956
OS 40.92506166 -38.69742324
OS 40.90194766 -38.69927236
OS 40.8779091 -38.70019692
OS 40.71426198 -38.70019692
OS 40.71426198 -38.95999828
OS 40.62920246 -38.95999828
OS 40.62920246 -38.32020276
OS 40.8917775 -38.32020276
OS 40.9056459 -38.32112732
OE
OB 40.49791494 -38.98403684 I
OS 40.49791494 -38.9849614
OS 40.49791494 -38.98773508
OS 40.49791494 -38.99235788
OS 40.49791494 -38.99790524
OS 40.49699038 -39.00530172
OS 40.49699038 -39.0126982
OS 40.49514126 -39.0311894
OS 40.49236758 -39.05060516
OS 40.48866934 -39.07094548
OS 40.48312198 -39.08851212
OS 40.47942374 -39.09683316
OS 40.4757255 -39.10330508
OS 40.4757255 -39.10422964
OS 40.47480094 -39.1051542
OS 40.47017814 -39.109777
OS 40.46278166 -39.11717348
OS 40.45353606 -39.12549452
OS 40.44059222 -39.13381556
OS 40.42395014 -39.14028748
OS 40.40453438 -39.14583484
OS 40.39343966 -39.1467594
OS 40.38142038 -39.14768396
OS 40.37587302 -39.14768396
OS 40.37032566 -39.1467594
OS 40.36200462 -39.1467594
OS 40.35275902 -39.14583484
OS 40.34258886 -39.14398572
OS 40.32039942 -39.13843836
OS 40.33519238 -39.07187004
OS 40.33611694 -39.07187004
OS 40.33889062 -39.0727946
OS 40.34351342 -39.07371916
OS 40.34813622 -39.07464372
OS 40.3601555 -39.0774174
OS 40.36570286 -39.07834196
OS 40.37494846 -39.07834196
OS 40.37957126 -39.0774174
OS 40.38511862 -39.07649284
OS 40.39066598 -39.07464372
OS 40.39621334 -39.07094548
OS 40.40268526 -39.06724724
OS 40.40730806 -39.06169988
OS 40.40823262 -39.06077532
OS 40.40915718 -39.05800164
OS 40.4110063 -39.05337884
OS 40.41377998 -39.04598236
OS 40.4156291 -39.0358122
OS 40.41655366 -39.02841572
OS 40.41747822 -39.0219438
OS 40.41840278 -39.01362276
OS 40.41840278 -39.0034526
OS 40.41932734 -38.99328244
OS 40.41932734 -38.98218772
OS 40.41932734 -38.49586916
OS 40.49791494 -38.49586916
OS 40.49791494 -38.98403684
OE
OB 41.51770462 -38.3100326 I
OS 41.52602566 -38.31095716
OS 41.53619582 -38.31188172
OS 41.54636598 -38.31280628
OS 41.55838526 -38.31557996
OS 41.58334838 -38.32112732
OS 41.61108518 -38.32944836
OS 41.62495358 -38.33499572
OS 41.63789742 -38.34146764
OS 41.65084126 -38.34978868
OS 41.6637851 -38.35810972
OS 41.66470966 -38.35903428
OS 41.66655878 -38.35995884
OS 41.67025702 -38.36273252
OS 41.67487982 -38.36735532
OS 41.67950262 -38.37197812
OS 41.68597454 -38.37845004
OS 41.69244646 -38.38584652
OS 41.69984294 -38.393243
OS 41.70723942 -38.4024886
OS 41.7146359 -38.41358332
OS 41.72295694 -38.42467804
OS 41.73035342 -38.43669732
OS 41.73682534 -38.45056572
OS 41.74422182 -38.46443412
OS 41.74976918 -38.47922708
OS 41.75531654 -38.49586916
OS 41.67210614 -38.51528492
OS 41.67210614 -38.51436036
OS 41.67118158 -38.51251124
OS 41.66933246 -38.508813
OS 41.66748334 -38.5041902
OS 41.66563422 -38.49864284
OS 41.66286054 -38.49124636
OS 41.65546406 -38.4764534
OS 41.64621846 -38.45981132
OS 41.63512374 -38.44316924
OS 41.62125534 -38.42745172
OS 41.60646238 -38.41358332
OS 41.60461326 -38.4117342
OS 41.5990659 -38.40803596
OS 41.5898203 -38.40341316
OS 41.57780102 -38.39694124
OS 41.5620835 -38.39139388
OS 41.54451686 -38.38584652
OS 41.52325198 -38.38214828
OS 41.50013798 -38.38122372
OS 41.4927415 -38.38122372
OS 41.4881187 -38.38214828
OS 41.48164678 -38.38214828
OS 41.4742503 -38.38307284
OS 41.45668366 -38.38584652
OS 41.4372679 -38.38954476
OS 41.41692758 -38.39601668
OS 41.3956627 -38.40526228
OS 41.37624694 -38.41728156
OS 41.37532238 -38.41728156
OS 41.37439782 -38.41913068
OS 41.3679259 -38.42375348
OS 41.35960486 -38.43114996
OS 41.3494347 -38.44224468
OS 41.33741542 -38.45611308
OS 41.3263207 -38.4718306
OS 41.31615054 -38.49124636
OS 41.30690494 -38.51251124
OS 41.30690494 -38.5134358
OS 41.30598038 -38.51528492
OS 41.30505582 -38.5180586
OS 41.30413126 -38.5226814
OS 41.30228214 -38.52822876
OS 41.30043302 -38.53470068
OS 41.29765934 -38.5504182
OS 41.2939611 -38.5689094
OS 41.29026286 -38.58924972
OS 41.28841374 -38.61143916
OS 41.28748918 -38.63547772
OS 41.28748918 -38.63640228
OS 41.28748918 -38.63917596
OS 41.28748918 -38.64379876
OS 41.28748918 -38.64934612
OS 41.28841374 -38.65581804
OS 41.28841374 -38.66413908
OS 41.2893383 -38.67338468
OS 41.29026286 -38.68355484
OS 41.29303654 -38.70574428
OS 41.29765934 -38.72978284
OS 41.3032067 -38.7538214
OS 41.31060318 -38.77785996
OS 41.31060318 -38.77878452
OS 41.31152774 -38.78063364
OS 41.31337686 -38.78340732
OS 41.31522598 -38.78803012
OS 41.32077334 -38.79912484
OS 41.32909438 -38.81206868
OS 41.33926454 -38.82686164
OS 41.35220838 -38.84257916
OS 41.36700134 -38.85644756
OS 41.38456798 -38.8693914
OS 41.38549254 -38.8693914
OS 41.38734166 -38.87031596
OS 41.39011534 -38.87216508
OS 41.39381358 -38.8740142
OS 41.39843638 -38.87586332
OS 41.40398374 -38.878637
OS 41.41692758 -38.88418436
OS 41.43356966 -38.88973172
OS 41.45206086 -38.89435452
OS 41.47240118 -38.89805276
OS 41.49366606 -38.89897732
OS 41.50013798 -38.89897732
OS 41.50568534 -38.89805276
OS 41.51215726 -38.89805276
OS 41.51862918 -38.8971282
OS 41.53527126 -38.89342996
OS 41.55468702 -38.88880716
OS 41.57410278 -38.88141068
OS 41.5944431 -38.87124052
OS 41.60461326 -38.86569316
OS 41.61385886 -38.85829668
OS 41.61478342 -38.85737212
OS 41.61570798 -38.85644756
OS 41.61848166 -38.85367388
OS 41.6221799 -38.8509002
OS 41.62587814 -38.8462774
OS 41.63050094 -38.84073004
OS 41.6360483 -38.83518268
OS 41.6406711 -38.8277862
OS 41.64621846 -38.81946516
OS 41.65269038 -38.81021956
OS 41.65823774 -38.80097396
OS 41.6637851 -38.78987924
OS 41.6684079 -38.77785996
OS 41.6730307 -38.76491612
OS 41.6776535 -38.75104772
OS 41.68135174 -38.73625476
OS 41.76641126 -38.75751964
OS 41.76641126 -38.7584442
OS 41.7654867 -38.76214244
OS 41.76363758 -38.7676898
OS 41.7608639 -38.77508628
OS 41.75809022 -38.78340732
OS 41.75439198 -38.79357748
OS 41.74976918 -38.8046722
OS 41.74422182 -38.81669148
OS 41.73127798 -38.84257916
OS 41.7146359 -38.86846684
OS 41.70446574 -38.88141068
OS 41.69429558 -38.89435452
OS 41.68320086 -38.90544924
OS 41.67025702 -38.91654396
OS 41.66933246 -38.91746852
OS 41.66748334 -38.91931764
OS 41.66286054 -38.92116676
OS 41.65823774 -38.924865
OS 41.65084126 -38.9294878
OS 41.64344478 -38.9341106
OS 41.63327462 -38.9387334
OS 41.62310446 -38.9433562
OS 41.61108518 -38.94890356
OS 41.59814134 -38.95352636
OS 41.58427294 -38.95814916
OS 41.56947998 -38.96277196
OS 41.55376246 -38.9664702
OS 41.53712038 -38.96831932
OS 41.51955374 -38.97016844
OS 41.50106254 -38.971093
OS 41.49089238 -38.971093
OS 41.4834959 -38.97016844
OS 41.47517486 -38.97016844
OS 41.4650047 -38.96924388
OS 41.45390998 -38.96739476
OS 41.44096614 -38.96554564
OS 41.4141539 -38.96092284
OS 41.3864171 -38.95352636
OS 41.3586803 -38.9433562
OS 41.34573646 -38.93688428
OS 41.33279262 -38.9294878
OS 41.33186806 -38.92856324
OS 41.33001894 -38.92763868
OS 41.3263207 -38.924865
OS 41.32262246 -38.92116676
OS 41.3170751 -38.91746852
OS 41.31060318 -38.91192116
OS 41.3032067 -38.90544924
OS 41.29581022 -38.89805276
OS 41.28841374 -38.88973172
OS 41.2800927 -38.88141068
OS 41.26345062 -38.8601458
OS 41.2477331 -38.83518268
OS 41.2338647 -38.80744588
OS 41.2338647 -38.80652132
OS 41.23201558 -38.80374764
OS 41.23109102 -38.79912484
OS 41.22831734 -38.79357748
OS 41.22646822 -38.786181
OS 41.22369454 -38.7769354
OS 41.2199963 -38.76676524
OS 41.21722262 -38.75567052
OS 41.21444894 -38.74365124
OS 41.2107507 -38.72978284
OS 41.2061279 -38.70112148
OS 41.20242966 -38.66876188
OS 41.20058054 -38.63547772
OS 41.20058054 -38.63455316
OS 41.20058054 -38.63085492
OS 41.20058054 -38.62530756
OS 41.2015051 -38.61883564
OS 41.2015051 -38.60959004
OS 41.20242966 -38.60034444
OS 41.20335422 -38.58832516
OS 41.20520334 -38.57630588
OS 41.20982614 -38.54949364
OS 41.21629806 -38.51990772
OS 41.22554366 -38.4903218
OS 41.2384875 -38.46166044
OS 41.23941206 -38.46073588
OS 41.24033662 -38.4579622
OS 41.24218574 -38.45426396
OS 41.24588398 -38.44964116
OS 41.24958222 -38.44316924
OS 41.25420502 -38.43577276
OS 41.2662243 -38.41913068
OS 41.28194182 -38.40063948
OS 41.30043302 -38.38214828
OS 41.3216979 -38.36365708
OS 41.34666102 -38.34793956
OS 41.34758558 -38.347015
OS 41.35035926 -38.34609044
OS 41.3540575 -38.34424132
OS 41.3586803 -38.34146764
OS 41.36607678 -38.33869396
OS 41.37347326 -38.33592028
OS 41.38271886 -38.33222204
OS 41.39288902 -38.3285238
OS 41.40398374 -38.32482556
OS 41.41600302 -38.32112732
OS 41.4418907 -38.31557996
OS 41.47147662 -38.31095716
OS 41.5019871 -38.30910804
OS 41.5112327 -38.30910804
OS 41.51770462 -38.3100326
OE
OB 42.90454462 -39.1375138 I
OS 42.38401734 -39.1375138
OS 42.38401734 -39.08111564
OS 42.90454462 -39.08111564
OS 42.90454462 -39.1375138
OE
OB 42.12514054 -38.32112732 I
OS 42.13253702 -38.32112732
OS 42.1491791 -38.32297644
OS 42.1676703 -38.32482556
OS 42.18708606 -38.3285238
OS 42.20650182 -38.3331466
OS 42.22406846 -38.33961852
OS 42.22499302 -38.33961852
OS 42.22591758 -38.34054308
OS 42.23146494 -38.34331676
OS 42.23978598 -38.34793956
OS 42.24903158 -38.35441148
OS 42.2601263 -38.36273252
OS 42.27214558 -38.37290268
OS 42.2832403 -38.38584652
OS 42.29341046 -38.39971492
OS 42.29433502 -38.40156404
OS 42.2971087 -38.4071114
OS 42.3017315 -38.41450788
OS 42.3063543 -38.4256026
OS 42.3109771 -38.43854644
OS 42.3155999 -38.45241484
OS 42.31837358 -38.46813236
OS 42.31929814 -38.48384988
OS 42.31929814 -38.485699
OS 42.31929814 -38.4903218
OS 42.31837358 -38.49864284
OS 42.31652446 -38.508813
OS 42.31375078 -38.52083228
OS 42.30912798 -38.53377612
OS 42.30358062 -38.54671996
OS 42.29618414 -38.56058836
OS 42.29525958 -38.56243748
OS 42.2924859 -38.56613572
OS 42.28693854 -38.5735322
OS 42.27954206 -38.58092868
OS 42.27029646 -38.59017428
OS 42.25920174 -38.60034444
OS 42.24533334 -38.60959004
OS 42.22961582 -38.61883564
OS 42.23054038 -38.61883564
OS 42.2323895 -38.6197602
OS 42.23516318 -38.62068476
OS 42.23886142 -38.62253388
OS 42.24995614 -38.62623212
OS 42.26289998 -38.63270404
OS 42.27676838 -38.64102508
OS 42.2924859 -38.65119524
OS 42.3063543 -38.66321452
OS 42.31929814 -38.67800748
OS 42.3202227 -38.6798566
OS 42.32392094 -38.68540396
OS 42.3294683 -38.693725
OS 42.33501566 -38.70481972
OS 42.34056302 -38.71961268
OS 42.34611038 -38.7353302
OS 42.34980862 -38.7538214
OS 42.35073318 -38.77416172
OS 42.35073318 -38.77508628
OS 42.35073318 -38.77601084
OS 42.35073318 -38.7815582
OS 42.34980862 -38.7908038
OS 42.3479595 -38.80189852
OS 42.34611038 -38.81484236
OS 42.34241214 -38.82871076
OS 42.33778934 -38.84350372
OS 42.33131742 -38.85829668
OS 42.33039286 -38.8601458
OS 42.32761918 -38.8647686
OS 42.32392094 -38.87124052
OS 42.31837358 -38.88048612
OS 42.3109771 -38.88973172
OS 42.30358062 -38.89990188
OS 42.29433502 -38.91007204
OS 42.28416486 -38.91839308
OS 42.2832403 -38.91931764
OS 42.27954206 -38.92209132
OS 42.27307014 -38.92578956
OS 42.2647491 -38.9294878
OS 42.25457894 -38.93503516
OS 42.24255966 -38.94058252
OS 42.22961582 -38.94520532
OS 42.2138983 -38.94982812
OS 42.21204918 -38.94982812
OS 42.20650182 -38.95167724
OS 42.19725622 -38.9526018
OS 42.18523694 -38.95445092
OS 42.17044398 -38.95630004
OS 42.15287734 -38.95814916
OS 42.13346158 -38.95907372
OS 42.11127214 -38.95999828
OS 41.8671883 -38.95999828
OS 41.8671883 -38.32020276
OS 42.11866862 -38.32020276
OS 42.12514054 -38.32112732
OE
OB 40.30745558 -38.48662356 I
OS 40.31762574 -38.48847268
OS 40.32964502 -38.49217092
OS 40.34258886 -38.49679372
OS 40.35738182 -38.50326564
OS 40.37309934 -38.51158668
OS 40.34443798 -38.58370236
OS 40.34351342 -38.5827778
OS 40.33981518 -38.58092868
OS 40.33426782 -38.578155
OS 40.32687134 -38.57538132
OS 40.3185503 -38.57260764
OS 40.30838014 -38.56983396
OS 40.29820998 -38.56798484
OS 40.28803982 -38.56706028
OS 40.28341702 -38.56706028
OS 40.27879422 -38.56798484
OS 40.2723223 -38.5689094
OS 40.26585038 -38.57075852
OS 40.25752934 -38.5735322
OS 40.2492083 -38.57723044
OS 40.24181182 -38.5827778
OS 40.24088726 -38.58370236
OS 40.23811358 -38.58555148
OS 40.2353399 -38.58924972
OS 40.2307171 -38.59387252
OS 40.2260943 -38.60034444
OS 40.2214715 -38.60774092
OS 40.2168487 -38.61606196
OS 40.21315046 -38.62623212
OS 40.2122259 -38.62808124
OS 40.21130134 -38.6336286
OS 40.20945222 -38.64194964
OS 40.20667854 -38.65304436
OS 40.20390486 -38.66691276
OS 40.20205574 -38.68263028
OS 40.20113118 -38.69927236
OS 40.20020662 -38.71776356
OS 40.20020662 -38.95999828
OS 40.12161902 -38.95999828
OS 40.12161902 -38.49586916
OS 40.19281014 -38.49586916
OS 40.19281014 -38.56613572
OS 40.1937347 -38.56521116
OS 40.19743294 -38.55873924
OS 40.20205574 -38.5504182
OS 40.20945222 -38.54024804
OS 40.2168487 -38.53007788
OS 40.22516974 -38.51898316
OS 40.23349078 -38.50973756
OS 40.24181182 -38.50234108
OS 40.24273638 -38.50141652
OS 40.24551006 -38.4995674
OS 40.25105742 -38.49679372
OS 40.25660478 -38.49402004
OS 40.26400126 -38.49124636
OS 40.27324686 -38.48847268
OS 40.28249246 -38.48662356
OS 40.29266262 -38.485699
OS 40.29913454 -38.485699
OS 40.30745558 -38.48662356
OE
OB 39.48829542 -38.95999828 I
OS 39.3986131 -38.95999828
OS 39.3986131 -38.87031596
OS 39.48829542 -38.87031596
OS 39.48829542 -38.95999828
OE
OB 38.6404739 -38.95999828 I
OS 38.55171614 -38.95999828
OS 38.30393406 -38.32020276
OS 38.39639006 -38.32020276
OS 38.56281086 -38.78525644
OS 38.56281086 -38.786181
OS 38.56373542 -38.78803012
OS 38.56465998 -38.7908038
OS 38.5665091 -38.79450204
OS 38.56743366 -38.8000494
OS 38.56928278 -38.80559676
OS 38.57390558 -38.81946516
OS 38.57945294 -38.83518268
OS 38.5850003 -38.85274932
OS 38.59609502 -38.88973172
OS 38.59609502 -38.88880716
OS 38.59701958 -38.88695804
OS 38.59794414 -38.88418436
OS 38.5988687 -38.88048612
OS 38.60164238 -38.87031596
OS 38.60626518 -38.85644756
OS 38.61088798 -38.84073004
OS 38.61643534 -38.8231634
OS 38.62290726 -38.8046722
OS 38.63030374 -38.78525644
OS 38.80412102 -38.32020276
OS 38.8901051 -38.32020276
OS 38.6404739 -38.95999828
OE
OB 39.27564662 -38.42745172 I
OS 39.25438174 -38.54671996
OS 39.20538006 -38.54671996
OS 39.1859643 -38.42745172
OS 39.1859643 -38.32020276
OS 39.27564662 -38.32020276
OS 39.27564662 -38.42745172
OE
OB 40.49791494 -38.4117342 I
OS 40.41932734 -38.4117342
OS 40.41932734 -38.32020276
OS 40.49791494 -38.32020276
OS 40.49791494 -38.4117342
OE
OB 39.84517558 -38.48662356 I
OS 39.8516475 -38.48754812
OS 39.8655159 -38.48939724
OS 39.88215798 -38.49309548
OS 39.89972462 -38.49864284
OS 39.91729126 -38.50696388
OS 39.9348579 -38.51713404
OS 39.93578246 -38.51713404
OS 39.93670702 -38.51898316
OS 39.94225438 -38.5226814
OS 39.95057542 -38.53007788
OS 39.96074558 -38.53932348
OS 39.9718403 -38.55134276
OS 39.98293502 -38.56613572
OS 39.99402974 -38.58370236
OS 40.00327534 -38.60311812
OS 40.00327534 -38.60404268
OS 40.0041999 -38.6058918
OS 40.00512446 -38.60866548
OS 40.00697358 -38.61236372
OS 40.0088227 -38.61791108
OS 40.01067182 -38.624383
OS 40.01529462 -38.63917596
OS 40.01991742 -38.65766716
OS 40.02361566 -38.67800748
OS 40.02638934 -38.70112148
OS 40.0273139 -38.72516004
OS 40.0273139 -38.7260846
OS 40.0273139 -38.72793372
OS 40.0273139 -38.73163196
OS 40.0273139 -38.73717932
OS 40.02638934 -38.74365124
OS 40.02638934 -38.75104772
OS 40.02454022 -38.7676898
OS 40.02084198 -38.78803012
OS 40.01621918 -38.809295
OS 40.00974726 -38.83148444
OS 40.00142622 -38.85367388
OS 40.00142622 -38.85459844
OS 40.00050166 -38.85644756
OS 39.99865254 -38.85922124
OS 39.99680342 -38.86291948
OS 39.9903315 -38.87308964
OS 39.98201046 -38.88603348
OS 39.9718403 -38.89990188
OS 39.95889646 -38.91377028
OS 39.9441035 -38.92763868
OS 39.92653686 -38.94058252
OS 39.9256123 -38.94058252
OS 39.92468774 -38.94150708
OS 39.92191406 -38.9433562
OS 39.91821582 -38.94520532
OS 39.90897022 -38.94982812
OS 39.89602638 -38.95537548
OS 39.88030886 -38.96092284
OS 39.86366678 -38.96554564
OS 39.84425102 -38.96924388
OS 39.82483526 -38.97016844
OS 39.81836334 -38.97016844
OS 39.81096686 -38.96924388
OS 39.80172126 -38.96831932
OS 39.79062654 -38.9664702
OS 39.77860726 -38.96369652
OS 39.76658798 -38.95999828
OS 39.7545687 -38.95445092
OS 39.75364414 -38.95352636
OS 39.74902134 -38.95167724
OS 39.74347398 -38.947979
OS 39.7360775 -38.94243164
OS 39.72868102 -38.93688428
OS 39.71943542 -38.9294878
OS 39.71111438 -38.92116676
OS 39.7037179 -38.91192116
OS 39.7037179 -39.1375138
OS 39.6251303 -39.1375138
OS 39.6251303 -38.49586916
OS 39.69632142 -38.49586916
OS 39.69632142 -38.55689012
OS 39.69724598 -38.555041
OS 39.70094422 -38.55134276
OS 39.70556702 -38.54487084
OS 39.7129635 -38.53747436
OS 39.72128454 -38.52822876
OS 39.73053014 -38.51990772
OS 39.74162486 -38.51158668
OS 39.75271958 -38.5041902
OS 39.7545687 -38.50326564
OS 39.75826694 -38.50141652
OS 39.76566342 -38.49864284
OS 39.77490902 -38.4949446
OS 39.78600374 -38.49124636
OS 39.79894758 -38.48847268
OS 39.81374054 -38.48662356
OS 39.83038262 -38.485699
OS 39.84055278 -38.485699
OS 39.84517558 -38.48662356
OE
OB 44.92193454 -38.40988508 I
OS 44.84334694 -38.40988508
OS 44.84334694 -38.32020276
OS 44.92193454 -38.32020276
OS 44.92193454 -38.40988508
OE
OB 45.24553054 -38.48662356 I
OS 45.25385158 -38.48754812
OS 45.26309718 -38.48939724
OS 45.27326734 -38.49124636
OS 45.28528662 -38.49309548
OS 45.31024974 -38.50141652
OS 45.32319358 -38.50603932
OS 45.33613742 -38.51251124
OS 45.34908126 -38.51898316
OS 45.3620251 -38.52822876
OS 45.37404438 -38.53747436
OS 45.38606366 -38.54856908
OS 45.38698822 -38.54949364
OS 45.38883734 -38.55134276
OS 45.39161102 -38.555041
OS 45.39530926 -38.5596638
OS 45.39993206 -38.56613572
OS 45.40547942 -38.57445676
OS 45.41102678 -38.58370236
OS 45.41657414 -38.59387252
OS 45.4221215 -38.60496724
OS 45.42766886 -38.61883564
OS 45.43321622 -38.63270404
OS 45.43783902 -38.64842156
OS 45.44153726 -38.66506364
OS 45.44431094 -38.68263028
OS 45.44616006 -38.70112148
OS 45.44708462 -38.7214618
OS 45.44708462 -38.72238636
OS 45.44708462 -38.72516004
OS 45.44708462 -38.72978284
OS 45.44708462 -38.73625476
OS 45.44616006 -38.74365124
OS 45.4452355 -38.75289684
OS 45.4452355 -38.76214244
OS 45.44338638 -38.7723126
OS 45.4406127 -38.7954266
OS 45.43506534 -38.8185406
OS 45.42859342 -38.8416546
OS 45.41934782 -38.86291948
OS 45.41934782 -38.86384404
OS 45.41842326 -38.8647686
OS 45.41657414 -38.86754228
OS 45.41472502 -38.87124052
OS 45.4082531 -38.88048612
OS 45.39993206 -38.89158084
OS 45.38883734 -38.90452468
OS 45.37496894 -38.91746852
OS 45.35925142 -38.93041236
OS 45.34076022 -38.94243164
OS 45.33983566 -38.94243164
OS 45.3389111 -38.9433562
OS 45.33613742 -38.94520532
OS 45.33151462 -38.94705444
OS 45.32689182 -38.94890356
OS 45.32134446 -38.95075268
OS 45.30747606 -38.95630004
OS 45.29175854 -38.96092284
OS 45.27234278 -38.96554564
OS 45.25200246 -38.96924388
OS 45.22981302 -38.97016844
OS 45.22056742 -38.97016844
OS 45.21317094 -38.96924388
OS 45.2048499 -38.96831932
OS 45.1956043 -38.9664702
OS 45.18450958 -38.96462108
OS 45.17341486 -38.96277196
OS 45.14845174 -38.95537548
OS 45.13458334 -38.94982812
OS 45.1216395 -38.94428076
OS 45.10869566 -38.93688428
OS 45.09575182 -38.92856324
OS 45.08373254 -38.91931764
OS 45.07171326 -38.90822292
OS 45.0707887 -38.90729836
OS 45.06893958 -38.90544924
OS 45.0661659 -38.901751
OS 45.06246766 -38.89620364
OS 45.05784486 -38.88973172
OS 45.05322206 -38.88233524
OS 45.0476747 -38.87308964
OS 45.04212734 -38.86199492
OS 45.03657998 -38.84997564
OS 45.03103262 -38.83610724
OS 45.02640982 -38.82131428
OS 45.02178702 -38.80559676
OS 45.01808878 -38.78803012
OS 45.0153151 -38.76953892
OS 45.01346598 -38.7491986
OS 45.01254142 -38.72793372
OS 45.01254142 -38.7260846
OS 45.01254142 -38.72238636
OS 45.01346598 -38.71591444
OS 45.01346598 -38.70666884
OS 45.01439054 -38.69649868
OS 45.01623966 -38.68355484
OS 45.01808878 -38.670611
OS 45.02178702 -38.65581804
OS 45.02548526 -38.64102508
OS 45.03010806 -38.62530756
OS 45.03565542 -38.60866548
OS 45.0430519 -38.59294796
OS 45.05044838 -38.578155
OS 45.06061854 -38.56336204
OS 45.0707887 -38.54949364
OS 45.08373254 -38.53747436
OS 45.0846571 -38.5365498
OS 45.08650622 -38.53562524
OS 45.09020446 -38.53285156
OS 45.09482726 -38.52915332
OS 45.10037462 -38.52545508
OS 45.1077711 -38.52083228
OS 45.11516758 -38.51620948
OS 45.12441318 -38.51158668
OS 45.13458334 -38.50696388
OS 45.14567806 -38.50234108
OS 45.17064118 -38.49402004
OS 45.19930254 -38.48754812
OS 45.2140955 -38.48662356
OS 45.22981302 -38.485699
OS 45.23905862 -38.485699
OS 45.24553054 -38.48662356
OE
OB 44.92193454 -38.95999828 I
OS 44.84334694 -38.95999828
OS 44.84334694 -38.49586916
OS 44.92193454 -38.49586916
OS 44.92193454 -38.95999828
OE
OB 46.10722046 -38.42745172 I
OS 46.08595558 -38.54671996
OS 46.0369539 -38.54671996
OS 46.01753814 -38.42745172
OS 46.01753814 -38.32020276
OS 46.10722046 -38.32020276
OS 46.10722046 -38.42745172
OE
OB 45.77160518 -38.48662356 I
OS 45.78177534 -38.48754812
OS 45.79379462 -38.48939724
OS 45.80673846 -38.49217092
OS 45.82060686 -38.49586916
OS 45.8335507 -38.50141652
OS 45.83539982 -38.50234108
OS 45.83909806 -38.5041902
OS 45.84556998 -38.50696388
OS 45.85296646 -38.51158668
OS 45.86221206 -38.51713404
OS 45.8705331 -38.52453052
OS 45.87885414 -38.531927
OS 45.88625062 -38.5411726
OS 45.88717518 -38.54209716
OS 45.8890243 -38.5457954
OS 45.89179798 -38.5504182
OS 45.89642078 -38.55689012
OS 45.90011902 -38.56613572
OS 45.90381726 -38.57538132
OS 45.90844006 -38.58647604
OS 45.91121374 -38.59849532
OS 45.91121374 -38.59941988
OS 45.9121383 -38.60311812
OS 45.91306286 -38.60866548
OS 45.91398742 -38.61606196
OS 45.91398742 -38.62715668
OS 45.91491198 -38.64010052
OS 45.91583654 -38.65581804
OS 45.91583654 -38.6752338
OS 45.91583654 -38.95999828
OS 45.83724894 -38.95999828
OS 45.83724894 -38.67893204
OS 45.83724894 -38.67800748
OS 45.83724894 -38.67708292
OS 45.83724894 -38.670611
OS 45.83724894 -38.66228996
OS 45.83632438 -38.6521198
OS 45.83539982 -38.64010052
OS 45.8335507 -38.62808124
OS 45.83077702 -38.61698652
OS 45.82800334 -38.60681636
OS 45.82800334 -38.6058918
OS 45.82615422 -38.60311812
OS 45.82338054 -38.59849532
OS 45.82060686 -38.59294796
OS 45.81598406 -38.5874006
OS 45.8104367 -38.58092868
OS 45.80304022 -38.57445676
OS 45.79471918 -38.5689094
OS 45.79379462 -38.56798484
OS 45.79102094 -38.56613572
OS 45.78547358 -38.5642866
OS 45.77900166 -38.56151292
OS 45.77160518 -38.55873924
OS 45.76235958 -38.55596556
OS 45.75126486 -38.555041
OS 45.74017014 -38.55411644
OS 45.73554734 -38.55411644
OS 45.7318491 -38.555041
OS 45.7226035 -38.55596556
OS 45.71058422 -38.55781468
OS 45.69764038 -38.56243748
OS 45.68284742 -38.56798484
OS 45.66805446 -38.57538132
OS 45.65418606 -38.58647604
OS 45.65233694 -38.58832516
OS 45.6486387 -38.59294796
OS 45.64586502 -38.5966462
OS 45.64309134 -38.601269
OS 45.6393931 -38.60681636
OS 45.63661942 -38.61328828
OS 45.63292118 -38.62068476
OS 45.62922294 -38.62993036
OS 45.62644926 -38.64010052
OS 45.62367558 -38.65119524
OS 45.62182646 -38.66321452
OS 45.61997734 -38.67615836
OS 45.61812822 -38.69187588
OS 45.61812822 -38.7075934
OS 45.61812822 -38.95999828
OS 45.53954062 -38.95999828
OS 45.53954062 -38.49586916
OS 45.60980718 -38.49586916
OS 45.60980718 -38.56243748
OS 45.61073174 -38.56151292
OS 45.61258086 -38.55873924
OS 45.61535454 -38.555041
OS 45.61905278 -38.5504182
OS 45.62460014 -38.54487084
OS 45.63107206 -38.53839892
OS 45.63846854 -38.53100244
OS 45.64771414 -38.52360596
OS 45.65695974 -38.51713404
OS 45.66805446 -38.50973756
OS 45.68007374 -38.50326564
OS 45.69301758 -38.49771828
OS 45.70781054 -38.49309548
OS 45.7226035 -38.48939724
OS 45.73924558 -38.48662356
OS 45.75681222 -38.485699
OS 45.7642087 -38.485699
OS 45.77160518 -38.48662356
OE
OB 44.2756671 -38.95999828 I
OS 44.1970795 -38.95999828
OS 44.1970795 -38.49586916
OS 44.2756671 -38.49586916
OS 44.2756671 -38.95999828
OE
OB 43.4574315 -38.48662356 I
OS 43.46482798 -38.48754812
OS 43.47407358 -38.48939724
OS 43.48424374 -38.49124636
OS 43.49626302 -38.49402004
OS 43.50735774 -38.49679372
OS 43.52030158 -38.50141652
OS 43.53232086 -38.50603932
OS 43.5452647 -38.51251124
OS 43.55820854 -38.51990772
OS 43.57115238 -38.52822876
OS 43.58317166 -38.53839892
OS 43.59426638 -38.54949364
OS 43.59519094 -38.5504182
OS 43.59704006 -38.55226732
OS 43.59981374 -38.55596556
OS 43.60351198 -38.56151292
OS 43.60813478 -38.56798484
OS 43.61275758 -38.57538132
OS 43.61830494 -38.58462692
OS 43.6238523 -38.59572164
OS 43.62939966 -38.60774092
OS 43.63494702 -38.62068476
OS 43.63956982 -38.63547772
OS 43.64419262 -38.65119524
OS 43.64789086 -38.66876188
OS 43.65066454 -38.68725308
OS 43.65251366 -38.70666884
OS 43.65343822 -38.72793372
OS 43.65343822 -38.72885828
OS 43.65343822 -38.73255652
OS 43.65343822 -38.73902844
OS 43.65251366 -38.74827404
OS 43.30580366 -38.74827404
OS 43.30580366 -38.7491986
OS 43.30580366 -38.75197228
OS 43.30672822 -38.75567052
OS 43.30672822 -38.76121788
OS 43.30765278 -38.7676898
OS 43.3095019 -38.77508628
OS 43.31227558 -38.79172836
OS 43.31782294 -38.81021956
OS 43.32521942 -38.83055988
OS 43.33538958 -38.84905108
OS 43.34833342 -38.86569316
OS 43.34925798 -38.86569316
OS 43.35018254 -38.86754228
OS 43.3557299 -38.87216508
OS 43.36405094 -38.878637
OS 43.37514566 -38.88510892
OS 43.38993862 -38.8925054
OS 43.4065807 -38.89897732
OS 43.4250719 -38.90360012
OS 43.43524206 -38.90452468
OS 43.44633678 -38.90544924
OS 43.45373326 -38.90544924
OS 43.4620543 -38.90452468
OS 43.47222446 -38.90267556
OS 43.48331918 -38.89990188
OS 43.49626302 -38.89620364
OS 43.5082823 -38.89065628
OS 43.52030158 -38.8832598
OS 43.52122614 -38.88233524
OS 43.52584894 -38.878637
OS 43.5313963 -38.87308964
OS 43.53786822 -38.86569316
OS 43.5452647 -38.855523
OS 43.55358574 -38.84257916
OS 43.56190678 -38.8277862
OS 43.56930326 -38.81021956
OS 43.65066454 -38.82038972
OS 43.65066454 -38.82131428
OS 43.64973998 -38.8231634
OS 43.64881542 -38.82686164
OS 43.6469663 -38.832409
OS 43.64419262 -38.83795636
OS 43.64141894 -38.84535284
OS 43.63402246 -38.86107036
OS 43.62477686 -38.878637
OS 43.61183302 -38.8971282
OS 43.59704006 -38.91469484
OS 43.57854886 -38.93133692
OS 43.5776243 -38.93133692
OS 43.57577518 -38.93318604
OS 43.5730015 -38.93503516
OS 43.56930326 -38.93780884
OS 43.5637559 -38.94058252
OS 43.55820854 -38.9433562
OS 43.55081206 -38.94705444
OS 43.54249102 -38.95075268
OS 43.53324542 -38.95445092
OS 43.52399982 -38.95814916
OS 43.50088582 -38.96369652
OS 43.47499814 -38.96831932
OS 43.44633678 -38.97016844
OS 43.43616662 -38.97016844
OS 43.4296947 -38.96924388
OS 43.42137366 -38.96831932
OS 43.4112035 -38.9664702
OS 43.40010878 -38.96462108
OS 43.3880895 -38.96277196
OS 43.36220182 -38.95537548
OS 43.34833342 -38.94982812
OS 43.33538958 -38.94428076
OS 43.32152118 -38.93688428
OS 43.30857734 -38.92856324
OS 43.29655806 -38.91931764
OS 43.28453878 -38.90822292
OS 43.28361422 -38.90729836
OS 43.2817651 -38.90544924
OS 43.27899142 -38.901751
OS 43.27529318 -38.89620364
OS 43.27067038 -38.88973172
OS 43.26604758 -38.88233524
OS 43.26050022 -38.87308964
OS 43.25495286 -38.86291948
OS 43.2494055 -38.8509002
OS 43.24385814 -38.83795636
OS 43.23923534 -38.8231634
OS 43.23461254 -38.80744588
OS 43.2309143 -38.7908038
OS 43.22814062 -38.7723126
OS 43.2262915 -38.75289684
OS 43.22536694 -38.73255652
OS 43.22536694 -38.73163196
OS 43.22536694 -38.72700916
OS 43.22536694 -38.7214618
OS 43.2262915 -38.71314076
OS 43.22721606 -38.7029706
OS 43.22814062 -38.69187588
OS 43.22998974 -38.67893204
OS 43.23276342 -38.6659882
OS 43.2401599 -38.63640228
OS 43.2447827 -38.62160932
OS 43.25033006 -38.6058918
OS 43.25772654 -38.59109884
OS 43.26604758 -38.57723044
OS 43.27529318 -38.56336204
OS 43.28546334 -38.5504182
OS 43.2863879 -38.54949364
OS 43.28823702 -38.54764452
OS 43.29193526 -38.54487084
OS 43.29655806 -38.54024804
OS 43.30210542 -38.53562524
OS 43.3095019 -38.53007788
OS 43.31782294 -38.52360596
OS 43.3279931 -38.5180586
OS 43.33816326 -38.51158668
OS 43.35018254 -38.50603932
OS 43.36312638 -38.50049196
OS 43.37699478 -38.49586916
OS 43.39178774 -38.49124636
OS 43.40750526 -38.48847268
OS 43.42414734 -38.48662356
OS 43.44171398 -38.485699
OS 43.45095958 -38.485699
OS 43.4574315 -38.48662356
OE
OB 43.13938286 -38.48662356 I
OS 43.14955302 -38.48847268
OS 43.1615723 -38.49217092
OS 43.17451614 -38.49679372
OS 43.1893091 -38.50326564
OS 43.20502662 -38.51158668
OS 43.17636526 -38.58370236
OS 43.1754407 -38.5827778
OS 43.17174246 -38.58092868
OS 43.1661951 -38.578155
OS 43.15879862 -38.57538132
OS 43.15047758 -38.57260764
OS 43.14030742 -38.56983396
OS 43.13013726 -38.56798484
OS 43.1199671 -38.56706028
OS 43.1153443 -38.56706028
OS 43.1107215 -38.56798484
OS 43.10424958 -38.5689094
OS 43.09777766 -38.57075852
OS 43.08945662 -38.5735322
OS 43.08113558 -38.57723044
OS 43.0737391 -38.5827778
OS 43.07281454 -38.58370236
OS 43.07004086 -38.58555148
OS 43.06726718 -38.58924972
OS 43.06264438 -38.59387252
OS 43.05802158 -38.60034444
OS 43.05339878 -38.60774092
OS 43.04877598 -38.61606196
OS 43.04507774 -38.62623212
OS 43.04415318 -38.62808124
OS 43.04322862 -38.6336286
OS 43.0413795 -38.64194964
OS 43.03860582 -38.65304436
OS 43.03583214 -38.66691276
OS 43.03398302 -38.68263028
OS 43.03305846 -38.69927236
OS 43.0321339 -38.71776356
OS 43.0321339 -38.95999828
OS 42.9535463 -38.95999828
OS 42.9535463 -38.49586916
OS 43.02473742 -38.49586916
OS 43.02473742 -38.56613572
OS 43.02566198 -38.56521116
OS 43.02936022 -38.55873924
OS 43.03398302 -38.5504182
OS 43.0413795 -38.54024804
OS 43.04877598 -38.53007788
OS 43.05709702 -38.51898316
OS 43.06541806 -38.50973756
OS 43.0737391 -38.50234108
OS 43.07466366 -38.50141652
OS 43.07743734 -38.4995674
OS 43.0829847 -38.49679372
OS 43.08853206 -38.49402004
OS 43.09592854 -38.49124636
OS 43.10517414 -38.48847268
OS 43.11441974 -38.48662356
OS 43.1245899 -38.485699
OS 43.13106182 -38.485699
OS 43.13938286 -38.48662356
OE
OB 43.95022198 -38.95999828 I
OS 43.87533262 -38.95999828
OS 43.70059078 -38.49586916
OS 43.78380118 -38.49586916
OS 43.88365366 -38.77416172
OS 43.88365366 -38.77508628
OS 43.88457822 -38.77601084
OS 43.88550278 -38.77878452
OS 43.88642734 -38.7815582
OS 43.88920102 -38.7908038
OS 43.89289926 -38.80282308
OS 43.89752206 -38.81669148
OS 43.90306942 -38.832409
OS 43.90769222 -38.84997564
OS 43.91323958 -38.86754228
OS 43.91416414 -38.86569316
OS 43.9150887 -38.86107036
OS 43.91786238 -38.85367388
OS 43.92063606 -38.84257916
OS 43.92525886 -38.83055988
OS 43.92988166 -38.81484236
OS 43.93635358 -38.79820028
OS 43.9428255 -38.77970908
OS 44.04545166 -38.49586916
OS 44.12681294 -38.49586916
OS 43.95022198 -38.95999828
OE
OB 44.2756671 -38.40988508 I
OS 44.1970795 -38.40988508
OS 44.1970795 -38.32020276
OS 44.2756671 -38.32020276
OS 44.2756671 -38.40988508
OE
OB 44.5669035 -38.48662356 I
OS 44.5807719 -38.48754812
OS 44.59556486 -38.48939724
OS 44.61128238 -38.49309548
OS 44.62792446 -38.49679372
OS 44.64364198 -38.50234108
OS 44.64456654 -38.50234108
OS 44.6454911 -38.50326564
OS 44.6501139 -38.50511476
OS 44.65751038 -38.508813
OS 44.66675598 -38.5134358
OS 44.67692614 -38.51990772
OS 44.6870963 -38.5273042
OS 44.6963419 -38.53562524
OS 44.70466294 -38.54487084
OS 44.7055875 -38.5457954
OS 44.70743662 -38.54949364
OS 44.71113486 -38.55596556
OS 44.71575766 -38.56336204
OS 44.72038046 -38.57445676
OS 44.72500326 -38.58647604
OS 44.7287015 -38.60034444
OS 44.73239974 -38.61606196
OS 44.65566126 -38.62623212
OS 44.65566126 -38.624383
OS 44.6547367 -38.62068476
OS 44.65288758 -38.61421284
OS 44.6501139 -38.6058918
OS 44.6454911 -38.59757076
OS 44.63994374 -38.58832516
OS 44.63347182 -38.57907956
OS 44.62422622 -38.57075852
OS 44.62330166 -38.56983396
OS 44.61960342 -38.56798484
OS 44.61405606 -38.5642866
OS 44.60573502 -38.56058836
OS 44.59648942 -38.55689012
OS 44.58447014 -38.55319188
OS 44.56967718 -38.55134276
OS 44.55395966 -38.5504182
OS 44.54471406 -38.5504182
OS 44.53546846 -38.55134276
OS 44.52344918 -38.55226732
OS 44.5114299 -38.555041
OS 44.49848606 -38.55781468
OS 44.48646678 -38.56243748
OS 44.47629662 -38.5689094
OS 44.47537206 -38.56983396
OS 44.47259838 -38.57168308
OS 44.46890014 -38.57538132
OS 44.4652019 -38.58092868
OS 44.4605791 -38.58647604
OS 44.45688086 -38.59387252
OS 44.45410718 -38.60219356
OS 44.45318262 -38.6105146
OS 44.45318262 -38.61143916
OS 44.45318262 -38.61328828
OS 44.45410718 -38.61606196
OS 44.45410718 -38.6197602
OS 44.45688086 -38.6290058
OS 44.46242822 -38.6382514
OS 44.46335278 -38.63917596
OS 44.46427734 -38.64010052
OS 44.46612646 -38.6428742
OS 44.4698247 -38.64564788
OS 44.47352294 -38.64842156
OS 44.4790703 -38.6521198
OS 44.48554222 -38.65489348
OS 44.4929387 -38.65859172
OS 44.49386326 -38.65859172
OS 44.49571238 -38.65951628
OS 44.49941062 -38.66044084
OS 44.50588254 -38.66321452
OS 44.51512814 -38.6659882
OS 44.52714742 -38.66876188
OS 44.5345439 -38.67153556
OS 44.54286494 -38.67338468
OS 44.55211054 -38.67615836
OS 44.5622807 -38.67893204
OS 44.56320526 -38.67893204
OS 44.56597894 -38.6798566
OS 44.57060174 -38.68078116
OS 44.5761491 -38.68263028
OS 44.58262102 -38.6844794
OS 44.59094206 -38.68632852
OS 44.6085087 -38.69187588
OS 44.62792446 -38.69742324
OS 44.64734022 -38.70389516
OS 44.66490686 -38.71036708
OS 44.67230334 -38.71314076
OS 44.67877526 -38.71591444
OS 44.68062438 -38.716839
OS 44.68432262 -38.71868812
OS 44.68986998 -38.7214618
OS 44.69819102 -38.7260846
OS 44.70651206 -38.73163196
OS 44.7148331 -38.73902844
OS 44.72315414 -38.74734948
OS 44.73055062 -38.75659508
OS 44.73147518 -38.75751964
OS 44.7333243 -38.76121788
OS 44.73702254 -38.76676524
OS 44.74072078 -38.77508628
OS 44.74349446 -38.78525644
OS 44.7471927 -38.79635116
OS 44.74904182 -38.809295
OS 44.74996638 -38.82408796
OS 44.74996638 -38.82593708
OS 44.74996638 -38.83055988
OS 44.74904182 -38.83795636
OS 44.7471927 -38.84812652
OS 44.74441902 -38.85922124
OS 44.73979622 -38.87124052
OS 44.73424886 -38.88510892
OS 44.72685238 -38.89805276
OS 44.72592782 -38.89990188
OS 44.72222958 -38.90360012
OS 44.71760678 -38.91007204
OS 44.7102103 -38.91746852
OS 44.70004014 -38.92578956
OS 44.68894542 -38.93503516
OS 44.67600158 -38.9433562
OS 44.66028406 -38.95167724
OS 44.6593595 -38.95167724
OS 44.65843494 -38.9526018
OS 44.65288758 -38.95445092
OS 44.64364198 -38.9572246
OS 44.6316227 -38.96092284
OS 44.61682974 -38.96462108
OS 44.60018766 -38.96739476
OS 44.58262102 -38.96924388
OS 44.5622807 -38.97016844
OS 44.55395966 -38.97016844
OS 44.54748774 -38.96924388
OS 44.54009126 -38.96924388
OS 44.53084566 -38.96831932
OS 44.52160006 -38.96739476
OS 44.5114299 -38.96554564
OS 44.48924046 -38.96092284
OS 44.46612646 -38.95445092
OS 44.44393702 -38.94520532
OS 44.43376686 -38.93965796
OS 44.42452126 -38.93318604
OS 44.4235967 -38.93226148
OS 44.42267214 -38.93133692
OS 44.41712478 -38.92578956
OS 44.40880374 -38.91746852
OS 44.39955814 -38.90452468
OS 44.38938798 -38.88880716
OS 44.37921782 -38.87031596
OS 44.37089678 -38.84720196
OS 44.36442486 -38.82131428
OS 44.4420879 -38.809295
OS 44.4420879 -38.81021956
OS 44.4420879 -38.81114412
OS 44.44393702 -38.81669148
OS 44.44578614 -38.82593708
OS 44.44948438 -38.83610724
OS 44.45410718 -38.84720196
OS 44.45965454 -38.85922124
OS 44.46797558 -38.87124052
OS 44.47814574 -38.88141068
OS 44.47999486 -38.88233524
OS 44.4836931 -38.88510892
OS 44.49108958 -38.88880716
OS 44.50033518 -38.89342996
OS 44.51235446 -38.89805276
OS 44.52622286 -38.901751
OS 44.54286494 -38.90452468
OS 44.5622807 -38.90544924
OS 44.5715263 -38.90544924
OS 44.5807719 -38.90452468
OS 44.59279118 -38.90267556
OS 44.60573502 -38.89990188
OS 44.61960342 -38.89620364
OS 44.6316227 -38.89158084
OS 44.64271742 -38.88418436
OS 44.64364198 -38.8832598
OS 44.64734022 -38.88048612
OS 44.65103846 -38.87586332
OS 44.65658582 -38.8693914
OS 44.66120862 -38.86199492
OS 44.66583142 -38.85274932
OS 44.6686051 -38.84350372
OS 44.66952966 -38.832409
OS 44.66952966 -38.83148444
OS 44.66952966 -38.8277862
OS 44.6686051 -38.8231634
OS 44.66675598 -38.81669148
OS 44.6639823 -38.81021956
OS 44.6593595 -38.80374764
OS 44.65381214 -38.79635116
OS 44.6454911 -38.7908038
OS 44.64456654 -38.78987924
OS 44.64179286 -38.78895468
OS 44.63717006 -38.786181
OS 44.62977358 -38.78340732
OS 44.61867886 -38.77970908
OS 44.61220694 -38.7769354
OS 44.60481046 -38.77508628
OS 44.59648942 -38.7723126
OS 44.58724382 -38.76953892
OS 44.57707366 -38.76676524
OS 44.56505438 -38.76399156
OS 44.56412982 -38.76399156
OS 44.56135614 -38.763067
OS 44.55673334 -38.76214244
OS 44.55118598 -38.76029332
OS 44.5437895 -38.7584442
OS 44.53546846 -38.75567052
OS 44.51790182 -38.75104772
OS 44.4975615 -38.7445758
OS 44.47814574 -38.73902844
OS 44.45965454 -38.73255652
OS 44.4513335 -38.72885828
OS 44.44486158 -38.7260846
OS 44.44301246 -38.72516004
OS 44.43931422 -38.72331092
OS 44.43376686 -38.71961268
OS 44.42637038 -38.71498988
OS 44.41804934 -38.70851796
OS 44.4097283 -38.70112148
OS 44.40140726 -38.69280044
OS 44.39401078 -38.68263028
OS 44.39308622 -38.68170572
OS 44.3912371 -38.67800748
OS 44.38846342 -38.67153556
OS 44.38568974 -38.66413908
OS 44.38291606 -38.65489348
OS 44.38014238 -38.64379876
OS 44.37829326 -38.63270404
OS 44.3773687 -38.6197602
OS 44.3773687 -38.61791108
OS 44.3773687 -38.61421284
OS 44.37829326 -38.60866548
OS 44.37921782 -38.60034444
OS 44.38106694 -38.5920234
OS 44.38291606 -38.58185324
OS 44.3866143 -38.57260764
OS 44.3912371 -38.56243748
OS 44.39216166 -38.56151292
OS 44.39401078 -38.55781468
OS 44.39678446 -38.55319188
OS 44.40140726 -38.54671996
OS 44.40695462 -38.54024804
OS 44.41342654 -38.531927
OS 44.42082302 -38.52453052
OS 44.43006862 -38.5180586
OS 44.43099318 -38.51713404
OS 44.43376686 -38.51620948
OS 44.4374651 -38.5134358
OS 44.44301246 -38.51066212
OS 44.45040894 -38.50696388
OS 44.45872998 -38.50326564
OS 44.46890014 -38.4995674
OS 44.47999486 -38.49586916
OS 44.48184398 -38.4949446
OS 44.48554222 -38.49402004
OS 44.49201414 -38.49217092
OS 44.50033518 -38.4903218
OS 44.51050534 -38.48847268
OS 44.52160006 -38.48754812
OS 44.5345439 -38.485699
OS 44.55673334 -38.485699
OS 44.5669035 -38.48662356
OE
OB 33.15968222 -38.32112732 I
OS 33.17539974 -38.32205188
OS 33.19204182 -38.32297644
OS 33.20775934 -38.32482556
OS 33.22162774 -38.32667468
OS 33.22347686 -38.32667468
OS 33.22994878 -38.3285238
OS 33.23826982 -38.33037292
OS 33.24936454 -38.3331466
OS 33.26138382 -38.3377694
OS 33.27432766 -38.34331676
OS 33.28819606 -38.34978868
OS 33.30021534 -38.35718516
OS 33.30206446 -38.35810972
OS 33.3057627 -38.3608834
OS 33.31131006 -38.36643076
OS 33.31870654 -38.37290268
OS 33.32702758 -38.38122372
OS 33.33534862 -38.39231844
OS 33.34459422 -38.40433772
OS 33.3519907 -38.41820612
OS 33.35291526 -38.42005524
OS 33.35476438 -38.42467804
OS 33.35846262 -38.43299908
OS 33.36216086 -38.4440938
OS 33.36493454 -38.45703764
OS 33.36863278 -38.4718306
OS 33.3704819 -38.48847268
OS 33.37140646 -38.50603932
OS 33.37140646 -38.50696388
OS 33.37140646 -38.50973756
OS 33.37140646 -38.5134358
OS 33.3704819 -38.51990772
OS 33.36955734 -38.52637964
OS 33.36863278 -38.53470068
OS 33.36678366 -38.54394628
OS 33.36493454 -38.55411644
OS 33.35846262 -38.57538132
OS 33.35476438 -38.58647604
OS 33.34921702 -38.59849532
OS 33.3427451 -38.6105146
OS 33.33627318 -38.62160932
OS 33.32795214 -38.63270404
OS 33.31870654 -38.64379876
OS 33.31778198 -38.64472332
OS 33.31593286 -38.64657244
OS 33.31315918 -38.64934612
OS 33.30853638 -38.6521198
OS 33.30298902 -38.6567426
OS 33.29559254 -38.6613654
OS 33.28634694 -38.66691276
OS 33.27617678 -38.67153556
OS 33.2641575 -38.67708292
OS 33.2502891 -38.68263028
OS 33.23549614 -38.68725308
OS 33.2179295 -38.69095132
OS 33.1994383 -38.69464956
OS 33.17909798 -38.69742324
OS 33.15598398 -38.69927236
OS 33.13194542 -38.70019692
OS 32.9682983 -38.70019692
OS 32.9682983 -38.95999828
OS 32.88323878 -38.95999828
OS 32.88323878 -38.32020276
OS 33.14581382 -38.32020276
OS 33.15968222 -38.32112732
OE
OB 32.75195126 -38.98403684 I
OS 32.75195126 -38.9849614
OS 32.75195126 -38.98773508
OS 32.75195126 -38.99235788
OS 32.75195126 -38.99790524
OS 32.7510267 -39.00530172
OS 32.7510267 -39.0126982
OS 32.74917758 -39.0311894
OS 32.7464039 -39.05060516
OS 32.74270566 -39.07094548
OS 32.7371583 -39.08851212
OS 32.73346006 -39.09683316
OS 32.72976182 -39.10330508
OS 32.72976182 -39.10422964
OS 32.72883726 -39.1051542
OS 32.72421446 -39.109777
OS 32.71681798 -39.11717348
OS 32.70757238 -39.12549452
OS 32.69462854 -39.13381556
OS 32.67798646 -39.14028748
OS 32.6585707 -39.14583484
OS 32.64747598 -39.1467594
OS 32.6354567 -39.14768396
OS 32.62990934 -39.14768396
OS 32.62436198 -39.1467594
OS 32.61604094 -39.1467594
OS 32.60679534 -39.14583484
OS 32.59662518 -39.14398572
OS 32.57443574 -39.13843836
OS 32.5892287 -39.07187004
OS 32.59015326 -39.07187004
OS 32.59292694 -39.0727946
OS 32.59754974 -39.07371916
OS 32.60217254 -39.07464372
OS 32.61419182 -39.0774174
OS 32.61973918 -39.07834196
OS 32.62898478 -39.07834196
OS 32.63360758 -39.0774174
OS 32.63915494 -39.07649284
OS 32.6447023 -39.07464372
OS 32.65024966 -39.07094548
OS 32.65672158 -39.06724724
OS 32.66134438 -39.06169988
OS 32.66226894 -39.06077532
OS 32.6631935 -39.05800164
OS 32.66504262 -39.05337884
OS 32.6678163 -39.04598236
OS 32.66966542 -39.0358122
OS 32.67058998 -39.02841572
OS 32.67151454 -39.0219438
OS 32.6724391 -39.01362276
OS 32.6724391 -39.0034526
OS 32.67336366 -38.99328244
OS 32.67336366 -38.98218772
OS 32.67336366 -38.49586916
OS 32.75195126 -38.49586916
OS 32.75195126 -38.98403684
OE
OB 33.77174094 -38.3100326 I
OS 33.78006198 -38.31095716
OS 33.79023214 -38.31188172
OS 33.8004023 -38.31280628
OS 33.81242158 -38.31557996
OS 33.8373847 -38.32112732
OS 33.8651215 -38.32944836
OS 33.8789899 -38.33499572
OS 33.89193374 -38.34146764
OS 33.90487758 -38.34978868
OS 33.91782142 -38.35810972
OS 33.91874598 -38.35903428
OS 33.9205951 -38.35995884
OS 33.92429334 -38.36273252
OS 33.92891614 -38.36735532
OS 33.93353894 -38.37197812
OS 33.94001086 -38.37845004
OS 33.94648278 -38.38584652
OS 33.95387926 -38.393243
OS 33.96127574 -38.4024886
OS 33.96867222 -38.41358332
OS 33.97699326 -38.42467804
OS 33.98438974 -38.43669732
OS 33.99086166 -38.45056572
OS 33.99825814 -38.46443412
OS 34.0038055 -38.47922708
OS 34.00935286 -38.49586916
OS 33.92614246 -38.51528492
OS 33.92614246 -38.51436036
OS 33.9252179 -38.51251124
OS 33.92336878 -38.508813
OS 33.92151966 -38.5041902
OS 33.91967054 -38.49864284
OS 33.91689686 -38.49124636
OS 33.90950038 -38.4764534
OS 33.90025478 -38.45981132
OS 33.88916006 -38.44316924
OS 33.87529166 -38.42745172
OS 33.8604987 -38.41358332
OS 33.85864958 -38.4117342
OS 33.85310222 -38.40803596
OS 33.84385662 -38.40341316
OS 33.83183734 -38.39694124
OS 33.81611982 -38.39139388
OS 33.79855318 -38.38584652
OS 33.7772883 -38.38214828
OS 33.7541743 -38.38122372
OS 33.74677782 -38.38122372
OS 33.74215502 -38.38214828
OS 33.7356831 -38.38214828
OS 33.72828662 -38.38307284
OS 33.71071998 -38.38584652
OS 33.69130422 -38.38954476
OS 33.6709639 -38.39601668
OS 33.64969902 -38.40526228
OS 33.63028326 -38.41728156
OS 33.6293587 -38.41728156
OS 33.62843414 -38.41913068
OS 33.62196222 -38.42375348
OS 33.61364118 -38.43114996
OS 33.60347102 -38.44224468
OS 33.59145174 -38.45611308
OS 33.58035702 -38.4718306
OS 33.57018686 -38.49124636
OS 33.56094126 -38.51251124
OS 33.56094126 -38.5134358
OS 33.5600167 -38.51528492
OS 33.55909214 -38.5180586
OS 33.55816758 -38.5226814
OS 33.55631846 -38.52822876
OS 33.55446934 -38.53470068
OS 33.55169566 -38.5504182
OS 33.54799742 -38.5689094
OS 33.54429918 -38.58924972
OS 33.54245006 -38.61143916
OS 33.5415255 -38.63547772
OS 33.5415255 -38.63640228
OS 33.5415255 -38.63917596
OS 33.5415255 -38.64379876
OS 33.5415255 -38.64934612
OS 33.54245006 -38.65581804
OS 33.54245006 -38.66413908
OS 33.54337462 -38.67338468
OS 33.54429918 -38.68355484
OS 33.54707286 -38.70574428
OS 33.55169566 -38.72978284
OS 33.55724302 -38.7538214
OS 33.5646395 -38.77785996
OS 33.5646395 -38.77878452
OS 33.56556406 -38.78063364
OS 33.56741318 -38.78340732
OS 33.5692623 -38.78803012
OS 33.57480966 -38.79912484
OS 33.5831307 -38.81206868
OS 33.59330086 -38.82686164
OS 33.6062447 -38.84257916
OS 33.62103766 -38.85644756
OS 33.6386043 -38.8693914
OS 33.63952886 -38.8693914
OS 33.64137798 -38.87031596
OS 33.64415166 -38.87216508
OS 33.6478499 -38.8740142
OS 33.6524727 -38.87586332
OS 33.65802006 -38.878637
OS 33.6709639 -38.88418436
OS 33.68760598 -38.88973172
OS 33.70609718 -38.89435452
OS 33.7264375 -38.89805276
OS 33.74770238 -38.89897732
OS 33.7541743 -38.89897732
OS 33.75972166 -38.89805276
OS 33.76619358 -38.89805276
OS 33.7726655 -38.8971282
OS 33.78930758 -38.89342996
OS 33.80872334 -38.88880716
OS 33.8281391 -38.88141068
OS 33.84847942 -38.87124052
OS 33.85864958 -38.86569316
OS 33.86789518 -38.85829668
OS 33.86881974 -38.85737212
OS 33.8697443 -38.85644756
OS 33.87251798 -38.85367388
OS 33.87621622 -38.8509002
OS 33.87991446 -38.8462774
OS 33.88453726 -38.84073004
OS 33.89008462 -38.83518268
OS 33.89470742 -38.8277862
OS 33.90025478 -38.81946516
OS 33.9067267 -38.81021956
OS 33.91227406 -38.80097396
OS 33.91782142 -38.78987924
OS 33.92244422 -38.77785996
OS 33.92706702 -38.76491612
OS 33.93168982 -38.75104772
OS 33.93538806 -38.73625476
OS 34.02044758 -38.75751964
OS 34.02044758 -38.7584442
OS 34.01952302 -38.76214244
OS 34.0176739 -38.7676898
OS 34.01490022 -38.77508628
OS 34.01212654 -38.78340732
OS 34.0084283 -38.79357748
OS 34.0038055 -38.8046722
OS 33.99825814 -38.81669148
OS 33.9853143 -38.84257916
OS 33.96867222 -38.86846684
OS 33.95850206 -38.88141068
OS 33.9483319 -38.89435452
OS 33.93723718 -38.90544924
OS 33.92429334 -38.91654396
OS 33.92336878 -38.91746852
OS 33.92151966 -38.91931764
OS 33.91689686 -38.92116676
OS 33.91227406 -38.924865
OS 33.90487758 -38.9294878
OS 33.8974811 -38.9341106
OS 33.88731094 -38.9387334
OS 33.87714078 -38.9433562
OS 33.8651215 -38.94890356
OS 33.85217766 -38.95352636
OS 33.83830926 -38.95814916
OS 33.8235163 -38.96277196
OS 33.80779878 -38.9664702
OS 33.7911567 -38.96831932
OS 33.77359006 -38.97016844
OS 33.75509886 -38.971093
OS 33.7449287 -38.971093
OS 33.73753222 -38.97016844
OS 33.72921118 -38.97016844
OS 33.71904102 -38.96924388
OS 33.7079463 -38.96739476
OS 33.69500246 -38.96554564
OS 33.66819022 -38.96092284
OS 33.64045342 -38.95352636
OS 33.61271662 -38.9433562
OS 33.59977278 -38.93688428
OS 33.58682894 -38.9294878
OS 33.58590438 -38.92856324
OS 33.58405526 -38.92763868
OS 33.58035702 -38.924865
OS 33.57665878 -38.92116676
OS 33.57111142 -38.91746852
OS 33.5646395 -38.91192116
OS 33.55724302 -38.90544924
OS 33.54984654 -38.89805276
OS 33.54245006 -38.88973172
OS 33.53412902 -38.88141068
OS 33.51748694 -38.8601458
OS 33.50176942 -38.83518268
OS 33.48790102 -38.80744588
OS 33.48790102 -38.80652132
OS 33.4860519 -38.80374764
OS 33.48512734 -38.79912484
OS 33.48235366 -38.79357748
OS 33.48050454 -38.786181
OS 33.47773086 -38.7769354
OS 33.47403262 -38.76676524
OS 33.47125894 -38.75567052
OS 33.46848526 -38.74365124
OS 33.46478702 -38.72978284
OS 33.46016422 -38.70112148
OS 33.45646598 -38.66876188
OS 33.45461686 -38.63547772
OS 33.45461686 -38.63455316
OS 33.45461686 -38.63085492
OS 33.45461686 -38.62530756
OS 33.45554142 -38.61883564
OS 33.45554142 -38.60959004
OS 33.45646598 -38.60034444
OS 33.45739054 -38.58832516
OS 33.45923966 -38.57630588
OS 33.46386246 -38.54949364
OS 33.47033438 -38.51990772
OS 33.47957998 -38.4903218
OS 33.49252382 -38.46166044
OS 33.49344838 -38.46073588
OS 33.49437294 -38.4579622
OS 33.49622206 -38.45426396
OS 33.4999203 -38.44964116
OS 33.50361854 -38.44316924
OS 33.50824134 -38.43577276
OS 33.52026062 -38.41913068
OS 33.53597814 -38.40063948
OS 33.55446934 -38.38214828
OS 33.57573422 -38.36365708
OS 33.60069734 -38.34793956
OS 33.6016219 -38.347015
OS 33.60439558 -38.34609044
OS 33.60809382 -38.34424132
OS 33.61271662 -38.34146764
OS 33.6201131 -38.33869396
OS 33.62750958 -38.33592028
OS 33.63675518 -38.33222204
OS 33.64692534 -38.3285238
OS 33.65802006 -38.32482556
OS 33.67003934 -38.32112732
OS 33.69592702 -38.31557996
OS 33.72551294 -38.31095716
OS 33.75602342 -38.30910804
OS 33.76526902 -38.30910804
OS 33.77174094 -38.3100326
OE
OB 35.15858094 -39.1375138 I
OS 34.63805366 -39.1375138
OS 34.63805366 -39.08111564
OS 35.15858094 -39.08111564
OS 35.15858094 -39.1375138
OE
OB 34.37917686 -38.32112732 I
OS 34.38657334 -38.32112732
OS 34.40321542 -38.32297644
OS 34.42170662 -38.32482556
OS 34.44112238 -38.3285238
OS 34.46053814 -38.3331466
OS 34.47810478 -38.33961852
OS 34.47902934 -38.33961852
OS 34.4799539 -38.34054308
OS 34.48550126 -38.34331676
OS 34.4938223 -38.34793956
OS 34.5030679 -38.35441148
OS 34.51416262 -38.36273252
OS 34.5261819 -38.37290268
OS 34.53727662 -38.38584652
OS 34.54744678 -38.39971492
OS 34.54837134 -38.40156404
OS 34.55114502 -38.4071114
OS 34.55576782 -38.41450788
OS 34.56039062 -38.4256026
OS 34.56501342 -38.43854644
OS 34.56963622 -38.45241484
OS 34.5724099 -38.46813236
OS 34.57333446 -38.48384988
OS 34.57333446 -38.485699
OS 34.57333446 -38.4903218
OS 34.5724099 -38.49864284
OS 34.57056078 -38.508813
OS 34.5677871 -38.52083228
OS 34.5631643 -38.53377612
OS 34.55761694 -38.54671996
OS 34.55022046 -38.56058836
OS 34.5492959 -38.56243748
OS 34.54652222 -38.56613572
OS 34.54097486 -38.5735322
OS 34.53357838 -38.58092868
OS 34.52433278 -38.59017428
OS 34.51323806 -38.60034444
OS 34.49936966 -38.60959004
OS 34.48365214 -38.61883564
OS 34.4845767 -38.61883564
OS 34.48642582 -38.6197602
OS 34.4891995 -38.62068476
OS 34.49289774 -38.62253388
OS 34.50399246 -38.62623212
OS 34.5169363 -38.63270404
OS 34.5308047 -38.64102508
OS 34.54652222 -38.65119524
OS 34.56039062 -38.66321452
OS 34.57333446 -38.67800748
OS 34.57425902 -38.6798566
OS 34.57795726 -38.68540396
OS 34.58350462 -38.693725
OS 34.58905198 -38.70481972
OS 34.59459934 -38.71961268
OS 34.6001467 -38.7353302
OS 34.60384494 -38.7538214
OS 34.6047695 -38.77416172
OS 34.6047695 -38.77508628
OS 34.6047695 -38.77601084
OS 34.6047695 -38.7815582
OS 34.60384494 -38.7908038
OS 34.60199582 -38.80189852
OS 34.6001467 -38.81484236
OS 34.59644846 -38.82871076
OS 34.59182566 -38.84350372
OS 34.58535374 -38.85829668
OS 34.58442918 -38.8601458
OS 34.5816555 -38.8647686
OS 34.57795726 -38.87124052
OS 34.5724099 -38.88048612
OS 34.56501342 -38.88973172
OS 34.55761694 -38.89990188
OS 34.54837134 -38.91007204
OS 34.53820118 -38.91839308
OS 34.53727662 -38.91931764
OS 34.53357838 -38.92209132
OS 34.52710646 -38.92578956
OS 34.51878542 -38.9294878
OS 34.50861526 -38.93503516
OS 34.49659598 -38.94058252
OS 34.48365214 -38.94520532
OS 34.46793462 -38.94982812
OS 34.4660855 -38.94982812
OS 34.46053814 -38.95167724
OS 34.45129254 -38.9526018
OS 34.43927326 -38.95445092
OS 34.4244803 -38.95630004
OS 34.40691366 -38.95814916
OS 34.3874979 -38.95907372
OS 34.36530846 -38.95999828
OS 34.12122462 -38.95999828
OS 34.12122462 -38.32020276
OS 34.37270494 -38.32020276
OS 34.37917686 -38.32112732
OE
OB 31.74233174 -38.95999828 I
OS 31.65264942 -38.95999828
OS 31.65264942 -38.87031596
OS 31.74233174 -38.87031596
OS 31.74233174 -38.95999828
OE
OB 31.52968294 -38.42745172 I
OS 31.50841806 -38.54671996
OS 31.45941638 -38.54671996
OS 31.44000062 -38.42745172
OS 31.44000062 -38.32020276
OS 31.52968294 -38.32020276
OS 31.52968294 -38.42745172
OE
OB 32.0992119 -38.48662356 I
OS 32.10568382 -38.48754812
OS 32.11955222 -38.48939724
OS 32.1361943 -38.49309548
OS 32.15376094 -38.49864284
OS 32.17132758 -38.50696388
OS 32.18889422 -38.51713404
OS 32.18981878 -38.51713404
OS 32.19074334 -38.51898316
OS 32.1962907 -38.5226814
OS 32.20461174 -38.53007788
OS 32.2147819 -38.53932348
OS 32.22587662 -38.55134276
OS 32.23697134 -38.56613572
OS 32.24806606 -38.58370236
OS 32.25731166 -38.60311812
OS 32.25731166 -38.60404268
OS 32.25823622 -38.6058918
OS 32.25916078 -38.60866548
OS 32.2610099 -38.61236372
OS 32.26285902 -38.61791108
OS 32.26470814 -38.624383
OS 32.26933094 -38.63917596
OS 32.27395374 -38.65766716
OS 32.27765198 -38.67800748
OS 32.28042566 -38.70112148
OS 32.28135022 -38.72516004
OS 32.28135022 -38.7260846
OS 32.28135022 -38.72793372
OS 32.28135022 -38.73163196
OS 32.28135022 -38.73717932
OS 32.28042566 -38.74365124
OS 32.28042566 -38.75104772
OS 32.27857654 -38.7676898
OS 32.2748783 -38.78803012
OS 32.2702555 -38.809295
OS 32.26378358 -38.83148444
OS 32.25546254 -38.85367388
OS 32.25546254 -38.85459844
OS 32.25453798 -38.85644756
OS 32.25268886 -38.85922124
OS 32.25083974 -38.86291948
OS 32.24436782 -38.87308964
OS 32.23604678 -38.88603348
OS 32.22587662 -38.89990188
OS 32.21293278 -38.91377028
OS 32.19813982 -38.92763868
OS 32.18057318 -38.94058252
OS 32.17964862 -38.94058252
OS 32.17872406 -38.94150708
OS 32.17595038 -38.9433562
OS 32.17225214 -38.94520532
OS 32.16300654 -38.94982812
OS 32.1500627 -38.95537548
OS 32.13434518 -38.96092284
OS 32.1177031 -38.96554564
OS 32.09828734 -38.96924388
OS 32.07887158 -38.97016844
OS 32.07239966 -38.97016844
OS 32.06500318 -38.96924388
OS 32.05575758 -38.96831932
OS 32.04466286 -38.9664702
OS 32.03264358 -38.96369652
OS 32.0206243 -38.95999828
OS 32.00860502 -38.95445092
OS 32.00768046 -38.95352636
OS 32.00305766 -38.95167724
OS 31.9975103 -38.947979
OS 31.99011382 -38.94243164
OS 31.98271734 -38.93688428
OS 31.97347174 -38.9294878
OS 31.9651507 -38.92116676
OS 31.95775422 -38.91192116
OS 31.95775422 -39.1375138
OS 31.87916662 -39.1375138
OS 31.87916662 -38.49586916
OS 31.95035774 -38.49586916
OS 31.95035774 -38.55689012
OS 31.9512823 -38.555041
OS 31.95498054 -38.55134276
OS 31.95960334 -38.54487084
OS 31.96699982 -38.53747436
OS 31.97532086 -38.52822876
OS 31.98456646 -38.51990772
OS 31.99566118 -38.51158668
OS 32.0067559 -38.5041902
OS 32.00860502 -38.50326564
OS 32.01230326 -38.50141652
OS 32.01969974 -38.49864284
OS 32.02894534 -38.4949446
OS 32.04004006 -38.49124636
OS 32.0529839 -38.48847268
OS 32.06777686 -38.48662356
OS 32.08441894 -38.485699
OS 32.0945891 -38.485699
OS 32.0992119 -38.48662356
OE
OB 32.5614919 -38.48662356 I
OS 32.57166206 -38.48847268
OS 32.58368134 -38.49217092
OS 32.59662518 -38.49679372
OS 32.61141814 -38.50326564
OS 32.62713566 -38.51158668
OS 32.5984743 -38.58370236
OS 32.59754974 -38.5827778
OS 32.5938515 -38.58092868
OS 32.58830414 -38.578155
OS 32.58090766 -38.57538132
OS 32.57258662 -38.57260764
OS 32.56241646 -38.56983396
OS 32.5522463 -38.56798484
OS 32.54207614 -38.56706028
OS 32.53745334 -38.56706028
OS 32.53283054 -38.56798484
OS 32.52635862 -38.5689094
OS 32.5198867 -38.57075852
OS 32.51156566 -38.5735322
OS 32.50324462 -38.57723044
OS 32.49584814 -38.5827778
OS 32.49492358 -38.58370236
OS 32.4921499 -38.58555148
OS 32.48937622 -38.58924972
OS 32.48475342 -38.59387252
OS 32.48013062 -38.60034444
OS 32.47550782 -38.60774092
OS 32.47088502 -38.61606196
OS 32.46718678 -38.62623212
OS 32.46626222 -38.62808124
OS 32.46533766 -38.6336286
OS 32.46348854 -38.64194964
OS 32.46071486 -38.65304436
OS 32.45794118 -38.66691276
OS 32.45609206 -38.68263028
OS 32.4551675 -38.69927236
OS 32.45424294 -38.71776356
OS 32.45424294 -38.95999828
OS 32.37565534 -38.95999828
OS 32.37565534 -38.49586916
OS 32.44684646 -38.49586916
OS 32.44684646 -38.56613572
OS 32.44777102 -38.56521116
OS 32.45146926 -38.55873924
OS 32.45609206 -38.5504182
OS 32.46348854 -38.54024804
OS 32.47088502 -38.53007788
OS 32.47920606 -38.51898316
OS 32.4875271 -38.50973756
OS 32.49584814 -38.50234108
OS 32.4967727 -38.50141652
OS 32.49954638 -38.4995674
OS 32.50509374 -38.49679372
OS 32.5106411 -38.49402004
OS 32.51803758 -38.49124636
OS 32.52728318 -38.48847268
OS 32.53652878 -38.48662356
OS 32.54669894 -38.485699
OS 32.55317086 -38.485699
OS 32.5614919 -38.48662356
OE
OB 32.75195126 -38.4117342 I
OS 32.67336366 -38.4117342
OS 32.67336366 -38.32020276
OS 32.75195126 -38.32020276
OS 32.75195126 -38.4117342
OE
OB 36.56668582 -38.95999828 I
OS 36.47885262 -38.95999828
OS 36.1441619 -38.4579622
OS 36.1441619 -38.95999828
OS 36.06280062 -38.95999828
OS 36.06280062 -38.32020276
OS 36.14970926 -38.32020276
OS 36.48532454 -38.8231634
OS 36.48532454 -38.32020276
OS 36.56668582 -38.32020276
OS 36.56668582 -38.95999828
OE
OB 35.74382742 -38.32112732 I
OS 35.75954494 -38.32205188
OS 35.77618702 -38.32297644
OS 35.79190454 -38.32482556
OS 35.80577294 -38.32667468
OS 35.80762206 -38.32667468
OS 35.81409398 -38.3285238
OS 35.82241502 -38.33037292
OS 35.83350974 -38.3331466
OS 35.84552902 -38.3377694
OS 35.85847286 -38.34331676
OS 35.87234126 -38.34978868
OS 35.88436054 -38.35718516
OS 35.88620966 -38.35810972
OS 35.8899079 -38.3608834
OS 35.89545526 -38.36643076
OS 35.90285174 -38.37290268
OS 35.91117278 -38.38122372
OS 35.91949382 -38.39231844
OS 35.92873942 -38.40433772
OS 35.9361359 -38.41820612
OS 35.93706046 -38.42005524
OS 35.93890958 -38.42467804
OS 35.94260782 -38.43299908
OS 35.94630606 -38.4440938
OS 35.94907974 -38.45703764
OS 35.95277798 -38.4718306
OS 35.9546271 -38.48847268
OS 35.95555166 -38.50603932
OS 35.95555166 -38.50696388
OS 35.95555166 -38.50973756
OS 35.95555166 -38.5134358
OS 35.9546271 -38.51990772
OS 35.95370254 -38.52637964
OS 35.95277798 -38.53470068
OS 35.95092886 -38.54394628
OS 35.94907974 -38.55411644
OS 35.94260782 -38.57538132
OS 35.93890958 -38.58647604
OS 35.93336222 -38.59849532
OS 35.9268903 -38.6105146
OS 35.92041838 -38.62160932
OS 35.91209734 -38.63270404
OS 35.90285174 -38.64379876
OS 35.90192718 -38.64472332
OS 35.90007806 -38.64657244
OS 35.89730438 -38.64934612
OS 35.89268158 -38.6521198
OS 35.88713422 -38.6567426
OS 35.87973774 -38.6613654
OS 35.87049214 -38.66691276
OS 35.86032198 -38.67153556
OS 35.8483027 -38.67708292
OS 35.8344343 -38.68263028
OS 35.81964134 -38.68725308
OS 35.8020747 -38.69095132
OS 35.7835835 -38.69464956
OS 35.76324318 -38.69742324
OS 35.74012918 -38.69927236
OS 35.71609062 -38.70019692
OS 35.5524435 -38.70019692
OS 35.5524435 -38.95999828
OS 35.46738398 -38.95999828
OS 35.46738398 -38.32020276
OS 35.72995902 -38.32020276
OS 35.74382742 -38.32112732
OE
OB 36.76916446 -38.42745172 I
OS 36.74789958 -38.54671996
OS 36.6988979 -38.54671996
OS 36.67948214 -38.42745172
OS 36.67948214 -38.32020276
OS 36.76916446 -38.32020276
OS 36.76916446 -38.42745172
OE
OB 38.2382903 -38.39601668 I
OS 37.86014526 -38.39601668
OS 37.86014526 -38.59109884
OS 38.21425174 -38.59109884
OS 38.21425174 -38.66691276
OS 37.86014526 -38.66691276
OS 37.86014526 -38.88418436
OS 38.25308326 -38.88418436
OS 38.25308326 -38.95999828
OS 37.77508574 -38.95999828
OS 37.77508574 -38.32020276
OS 38.2382903 -38.32020276
OS 38.2382903 -38.39601668
OE
OB 37.4339231 -38.32112732 I
OS 37.44224414 -38.32112732
OS 37.4616599 -38.32205188
OS 37.48200022 -38.32482556
OS 37.50418966 -38.32759924
OS 37.52452998 -38.33222204
OS 37.53470014 -38.33499572
OS 37.54302118 -38.3377694
OS 37.54394574 -38.3377694
OS 37.5448703 -38.33869396
OS 37.55041766 -38.34146764
OS 37.5587387 -38.34516588
OS 37.56890886 -38.3516378
OS 37.58000358 -38.35995884
OS 37.59202286 -38.37105356
OS 37.60311758 -38.3839974
OS 37.6142123 -38.39879036
OS 37.6142123 -38.39971492
OS 37.61513686 -38.40063948
OS 37.6188351 -38.40618684
OS 37.62253334 -38.41543244
OS 37.6280807 -38.42745172
OS 37.6327035 -38.44132012
OS 37.6373263 -38.4579622
OS 37.64009998 -38.47552884
OS 37.64102454 -38.4949446
OS 37.64102454 -38.49586916
OS 37.64102454 -38.49771828
OS 37.64102454 -38.50141652
OS 37.64009998 -38.50603932
OS 37.64009998 -38.51251124
OS 37.63917542 -38.51898316
OS 37.63547718 -38.53470068
OS 37.62992982 -38.55319188
OS 37.62253334 -38.57260764
OS 37.61143862 -38.5920234
OS 37.60404214 -38.601269
OS 37.59664566 -38.6105146
OS 37.5957211 -38.61143916
OS 37.59479654 -38.61236372
OS 37.59202286 -38.6151374
OS 37.58832462 -38.61791108
OS 37.58370182 -38.62160932
OS 37.57815446 -38.62530756
OS 37.57075798 -38.62993036
OS 37.5633615 -38.63547772
OS 37.5541159 -38.64010052
OS 37.54394574 -38.64472332
OS 37.53285102 -38.65027068
OS 37.52083174 -38.65489348
OS 37.50696334 -38.65859172
OS 37.49309494 -38.66321452
OS 37.47737742 -38.6659882
OS 37.46073534 -38.66876188
OS 37.46258446 -38.66968644
OS 37.4662827 -38.67153556
OS 37.47183006 -38.6752338
OS 37.47922654 -38.67893204
OS 37.49586862 -38.6891022
OS 37.50418966 -38.69557412
OS 37.51158614 -38.70112148
OS 37.51343526 -38.7029706
OS 37.51805806 -38.7075934
OS 37.52545454 -38.71498988
OS 37.53470014 -38.72423548
OS 37.5448703 -38.73717932
OS 37.55688958 -38.75104772
OS 37.56890886 -38.7676898
OS 37.5818527 -38.786181
OS 37.69187534 -38.95999828
OS 37.5864755 -38.95999828
OS 37.50234054 -38.82686164
OS 37.50234054 -38.82593708
OS 37.50049142 -38.82408796
OS 37.4986423 -38.82131428
OS 37.49586862 -38.81761604
OS 37.4893967 -38.80744588
OS 37.48107566 -38.79450204
OS 37.4709055 -38.78063364
OS 37.46073534 -38.76584068
OS 37.45056518 -38.75197228
OS 37.44131958 -38.73902844
OS 37.44039502 -38.73810388
OS 37.43762134 -38.73440564
OS 37.43299854 -38.72885828
OS 37.42652662 -38.72238636
OS 37.41265822 -38.70851796
OS 37.40526174 -38.70204604
OS 37.39786526 -38.69649868
OS 37.3969407 -38.69557412
OS 37.39509158 -38.69464956
OS 37.39139334 -38.69280044
OS 37.38584598 -38.69002676
OS 37.38029862 -38.68725308
OS 37.3738267 -38.6844794
OS 37.35903374 -38.6798566
OS 37.35810918 -38.6798566
OS 37.35626006 -38.67893204
OS 37.35256182 -38.67893204
OS 37.34793902 -38.67800748
OS 37.3414671 -38.67708292
OS 37.33407062 -38.67708292
OS 37.32390046 -38.67615836
OS 37.21480238 -38.67615836
OS 37.21480238 -38.95999828
OS 37.12974286 -38.95999828
OS 37.12974286 -38.32020276
OS 37.42652662 -38.32020276
OS 37.4339231 -38.32112732
OE
OB 35.31760526 -38.95999828 I
OS 35.23254574 -38.95999828
OS 35.23254574 -38.32020276
OS 35.31760526 -38.32020276
OS 35.31760526 -38.95999828
OE
OB 42.12051774 -38.66413908 H
OS 41.95224782 -38.66413908
OS 41.95224782 -38.88418436
OS 42.13438614 -38.88418436
OS 42.1538019 -38.8832598
OS 42.16212294 -38.88233524
OS 42.16951942 -38.88141068
OS 42.17044398 -38.88141068
OS 42.17414222 -38.88048612
OS 42.17968958 -38.87956156
OS 42.1861615 -38.87771244
OS 42.20187902 -38.87216508
OS 42.21759654 -38.8647686
OS 42.2185211 -38.86384404
OS 42.22129478 -38.86199492
OS 42.22499302 -38.85922124
OS 42.22961582 -38.855523
OS 42.23423862 -38.84997564
OS 42.24071054 -38.84442828
OS 42.24533334 -38.8370318
OS 42.2508807 -38.82871076
OS 42.25180526 -38.8277862
OS 42.25272982 -38.82501252
OS 42.25457894 -38.81946516
OS 42.25735262 -38.81299324
OS 42.2601263 -38.80559676
OS 42.26197542 -38.79635116
OS 42.26289998 -38.78525644
OS 42.26382454 -38.77416172
OS 42.26382454 -38.7723126
OS 42.26382454 -38.76861436
OS 42.26289998 -38.76121788
OS 42.26105086 -38.75289684
OS 42.25920174 -38.74365124
OS 42.2555035 -38.73348108
OS 42.2508807 -38.72331092
OS 42.24440878 -38.71314076
OS 42.24348422 -38.7122162
OS 42.24071054 -38.70851796
OS 42.2370123 -38.70389516
OS 42.23146494 -38.6983478
OS 42.22406846 -38.69187588
OS 42.21482286 -38.68540396
OS 42.2046527 -38.6798566
OS 42.19263342 -38.6752338
OS 42.1907843 -38.67430924
OS 42.18708606 -38.67338468
OS 42.17876502 -38.67153556
OS 42.16859486 -38.66968644
OS 42.15565102 -38.66783732
OS 42.1399335 -38.6659882
OS 42.12051774 -38.66413908
OE
OB 45.22981302 -38.5504182 H
OS 45.22426566 -38.5504182
OS 45.21964286 -38.55134276
OS 45.2094727 -38.55226732
OS 45.1956043 -38.55596556
OS 45.17988678 -38.56151292
OS 45.1632447 -38.5689094
OS 45.14752718 -38.58000412
OS 45.13920614 -38.5874006
OS 45.13180966 -38.59479708
OS 45.13180966 -38.59572164
OS 45.12996054 -38.5966462
OS 45.12811142 -38.59941988
OS 45.12533774 -38.60311812
OS 45.12256406 -38.60774092
OS 45.11979038 -38.61328828
OS 45.11609214 -38.62068476
OS 45.1123939 -38.62808124
OS 45.10869566 -38.63732684
OS 45.10499742 -38.64657244
OS 45.10222374 -38.65766716
OS 45.09945006 -38.66968644
OS 45.09667638 -38.68263028
OS 45.09482726 -38.69649868
OS 45.0939027 -38.7122162
OS 45.09297814 -38.72793372
OS 45.09297814 -38.72885828
OS 45.09297814 -38.73163196
OS 45.09297814 -38.73625476
OS 45.0939027 -38.74272668
OS 45.0939027 -38.75012316
OS 45.09482726 -38.7584442
OS 45.09760094 -38.77785996
OS 45.10222374 -38.8000494
OS 45.10962022 -38.82223884
OS 45.11886582 -38.84350372
OS 45.12533774 -38.85274932
OS 45.13180966 -38.86199492
OS 45.13273422 -38.86199492
OS 45.13365878 -38.86384404
OS 45.13920614 -38.86846684
OS 45.14752718 -38.87586332
OS 45.1586219 -38.8832598
OS 45.1724903 -38.89158084
OS 45.18913238 -38.89897732
OS 45.20854814 -38.90360012
OS 45.2187183 -38.90452468
OS 45.22981302 -38.90544924
OS 45.23536038 -38.90544924
OS 45.23998318 -38.90452468
OS 45.25015334 -38.90267556
OS 45.26402174 -38.89990188
OS 45.2788147 -38.89435452
OS 45.29545678 -38.88695804
OS 45.3111743 -38.87586332
OS 45.31949534 -38.86846684
OS 45.32689182 -38.86107036
OS 45.32781638 -38.8601458
OS 45.32874094 -38.85922124
OS 45.33059006 -38.85644756
OS 45.33336374 -38.85274932
OS 45.33613742 -38.84812652
OS 45.33983566 -38.84257916
OS 45.3435339 -38.83518268
OS 45.34723214 -38.8277862
OS 45.35093038 -38.8185406
OS 45.35370406 -38.80837044
OS 45.3574023 -38.79727572
OS 45.36017598 -38.78525644
OS 45.36294966 -38.77138804
OS 45.36479878 -38.75751964
OS 45.3666479 -38.74180212
OS 45.3666479 -38.72516004
OS 45.3666479 -38.72423548
OS 45.3666479 -38.7214618
OS 45.3666479 -38.716839
OS 45.36572334 -38.71129164
OS 45.36572334 -38.70389516
OS 45.36479878 -38.69557412
OS 45.3620251 -38.67615836
OS 45.3574023 -38.65581804
OS 45.35000582 -38.6336286
OS 45.33983566 -38.61328828
OS 45.3342883 -38.60311812
OS 45.32689182 -38.59479708
OS 45.32689182 -38.59387252
OS 45.3250427 -38.59294796
OS 45.31949534 -38.5874006
OS 45.3111743 -38.58092868
OS 45.30007958 -38.57260764
OS 45.28621118 -38.5642866
OS 45.2695691 -38.55689012
OS 45.2510779 -38.55226732
OS 45.24090774 -38.55134276
OS 45.22981302 -38.5504182
OE
OB 32.07702246 -38.54764452 H
OS 32.07239966 -38.54764452
OS 32.06870142 -38.54856908
OS 32.05945582 -38.5504182
OS 32.04743654 -38.55319188
OS 32.03356814 -38.55873924
OS 32.01877518 -38.56706028
OS 32.01045414 -38.57260764
OS 32.00305766 -38.57907956
OS 31.99566118 -38.58647604
OS 31.9882647 -38.59479708
OS 31.9882647 -38.59572164
OS 31.98641558 -38.5966462
OS 31.98456646 -38.59941988
OS 31.98271734 -38.60311812
OS 31.97994366 -38.60866548
OS 31.97624542 -38.61421284
OS 31.97254718 -38.62160932
OS 31.9697735 -38.6290058
OS 31.96607526 -38.6382514
OS 31.96237702 -38.64842156
OS 31.95960334 -38.65951628
OS 31.9559051 -38.67153556
OS 31.95405598 -38.68540396
OS 31.95220686 -38.69927236
OS 31.95035774 -38.71406532
OS 31.95035774 -38.7307074
OS 31.95035774 -38.73163196
OS 31.95035774 -38.73440564
OS 31.95035774 -38.73902844
OS 31.9512823 -38.74550036
OS 31.9512823 -38.75289684
OS 31.95220686 -38.76121788
OS 31.95498054 -38.78063364
OS 31.95960334 -38.80282308
OS 31.9651507 -38.82408796
OS 31.9743963 -38.84535284
OS 31.97994366 -38.85459844
OS 31.98641558 -38.86291948
OS 31.9882647 -38.8647686
OS 31.9928875 -38.8693914
OS 32.00028398 -38.87678788
OS 32.01045414 -38.88418436
OS 32.02339798 -38.89158084
OS 32.03819094 -38.89897732
OS 32.05483302 -38.90360012
OS 32.06407862 -38.90452468
OS 32.07332422 -38.90544924
OS 32.07887158 -38.90544924
OS 32.08256982 -38.90452468
OS 32.09181542 -38.90267556
OS 32.10475926 -38.89990188
OS 32.11862766 -38.89435452
OS 32.13342062 -38.88695804
OS 32.14821358 -38.87586332
OS 32.15561006 -38.8693914
OS 32.16300654 -38.86199492
OS 32.16300654 -38.86107036
OS 32.16485566 -38.8601458
OS 32.16670478 -38.85737212
OS 32.1685539 -38.85367388
OS 32.17225214 -38.84905108
OS 32.17502582 -38.84257916
OS 32.17872406 -38.83610724
OS 32.1824223 -38.8277862
OS 32.18519598 -38.81946516
OS 32.18889422 -38.80837044
OS 32.19259246 -38.79727572
OS 32.19536614 -38.78525644
OS 32.19721526 -38.77138804
OS 32.19906438 -38.75659508
OS 32.2009135 -38.74087756
OS 32.2009135 -38.72423548
OS 32.2009135 -38.72331092
OS 32.2009135 -38.72053724
OS 32.2009135 -38.71591444
OS 32.19998894 -38.70944252
OS 32.19998894 -38.70204604
OS 32.19906438 -38.693725
OS 32.1962907 -38.67430924
OS 32.1916679 -38.65304436
OS 32.18519598 -38.63177948
OS 32.17595038 -38.6105146
OS 32.17040302 -38.60034444
OS 32.1639311 -38.5920234
OS 32.1639311 -38.59109884
OS 32.16208198 -38.59017428
OS 32.15745918 -38.58462692
OS 32.1500627 -38.578155
OS 32.13989254 -38.56983396
OS 32.1269487 -38.56151292
OS 32.11215574 -38.55411644
OS 32.09551366 -38.54949364
OS 32.08626806 -38.54856908
OS 32.07702246 -38.54764452
OE
OB 42.10387566 -38.39601668 H
OS 41.95224782 -38.39601668
OS 41.95224782 -38.58832516
OS 42.10942302 -38.58832516
OS 42.1214423 -38.5874006
OS 42.13438614 -38.58647604
OS 42.14732998 -38.58555148
OS 42.16027382 -38.58370236
OS 42.17044398 -38.58185324
OS 42.1722931 -38.58092868
OS 42.17599134 -38.58000412
OS 42.1815387 -38.57723044
OS 42.18893518 -38.5735322
OS 42.19633166 -38.56983396
OS 42.2046527 -38.5642866
OS 42.21297374 -38.55689012
OS 42.21944566 -38.54949364
OS 42.22037022 -38.54856908
OS 42.22221934 -38.5457954
OS 42.22499302 -38.54024804
OS 42.2277667 -38.53377612
OS 42.23054038 -38.52637964
OS 42.23331406 -38.51713404
OS 42.23516318 -38.50603932
OS 42.23608774 -38.49402004
OS 42.23608774 -38.49217092
OS 42.23608774 -38.48847268
OS 42.23516318 -38.48292532
OS 42.23423862 -38.47552884
OS 42.2323895 -38.46628324
OS 42.22961582 -38.45703764
OS 42.22591758 -38.44779204
OS 42.22037022 -38.43854644
OS 42.21944566 -38.43762188
OS 42.21759654 -38.4348482
OS 42.2138983 -38.4302254
OS 42.2092755 -38.4256026
OS 42.20280358 -38.42005524
OS 42.1954071 -38.41450788
OS 42.1861615 -38.40896052
OS 42.17599134 -38.40526228
OS 42.17506678 -38.40526228
OS 42.17044398 -38.40341316
OS 42.16397206 -38.4024886
OS 42.1538019 -38.40063948
OS 42.1399335 -38.39879036
OS 42.12421598 -38.3978658
OS 42.10387566 -38.39601668
OE
OB 37.41635646 -38.39139388 H
OS 37.21480238 -38.39139388
OS 37.21480238 -38.60311812
OS 37.40526174 -38.60311812
OS 37.41635646 -38.60219356
OS 37.4293003 -38.601269
OS 37.44409326 -38.60034444
OS 37.45888622 -38.59849532
OS 37.47367918 -38.59572164
OS 37.48662302 -38.5920234
OS 37.48847214 -38.59109884
OS 37.49217038 -38.58924972
OS 37.49771774 -38.58647604
OS 37.50511422 -38.5827778
OS 37.51343526 -38.57723044
OS 37.5217563 -38.57075852
OS 37.53007734 -38.56243748
OS 37.53654926 -38.55319188
OS 37.53747382 -38.55226732
OS 37.53932294 -38.54856908
OS 37.54209662 -38.54302172
OS 37.54579486 -38.53562524
OS 37.54856854 -38.5273042
OS 37.55134222 -38.5180586
OS 37.55319134 -38.50696388
OS 37.5541159 -38.49586916
OS 37.5541159 -38.4949446
OS 37.5541159 -38.49402004
OS 37.55319134 -38.48847268
OS 37.55226678 -38.48015164
OS 37.55041766 -38.46905692
OS 37.54579486 -38.4579622
OS 37.5402475 -38.44501836
OS 37.53192646 -38.43299908
OS 37.52083174 -38.4209798
OS 37.51898262 -38.42005524
OS 37.51435982 -38.416357
OS 37.50696334 -38.4117342
OS 37.49494406 -38.40618684
OS 37.48107566 -38.40063948
OS 37.46258446 -38.39601668
OS 37.44131958 -38.39231844
OS 37.41635646 -38.39139388
OE
OB 39.82298614 -38.54764452 H
OS 39.81836334 -38.54764452
OS 39.8146651 -38.54856908
OS 39.8054195 -38.5504182
OS 39.79340022 -38.55319188
OS 39.77953182 -38.55873924
OS 39.76473886 -38.56706028
OS 39.75641782 -38.57260764
OS 39.74902134 -38.57907956
OS 39.74162486 -38.58647604
OS 39.73422838 -38.59479708
OS 39.73422838 -38.59572164
OS 39.73237926 -38.5966462
OS 39.73053014 -38.59941988
OS 39.72868102 -38.60311812
OS 39.72590734 -38.60866548
OS 39.7222091 -38.61421284
OS 39.71851086 -38.62160932
OS 39.71573718 -38.6290058
OS 39.71203894 -38.6382514
OS 39.7083407 -38.64842156
OS 39.70556702 -38.65951628
OS 39.70186878 -38.67153556
OS 39.70001966 -38.68540396
OS 39.69817054 -38.69927236
OS 39.69632142 -38.71406532
OS 39.69632142 -38.7307074
OS 39.69632142 -38.73163196
OS 39.69632142 -38.73440564
OS 39.69632142 -38.73902844
OS 39.69724598 -38.74550036
OS 39.69724598 -38.75289684
OS 39.69817054 -38.76121788
OS 39.70094422 -38.78063364
OS 39.70556702 -38.80282308
OS 39.71111438 -38.82408796
OS 39.72035998 -38.84535284
OS 39.72590734 -38.85459844
OS 39.73237926 -38.86291948
OS 39.73422838 -38.8647686
OS 39.73885118 -38.8693914
OS 39.74624766 -38.87678788
OS 39.75641782 -38.88418436
OS 39.76936166 -38.89158084
OS 39.78415462 -38.89897732
OS 39.8007967 -38.90360012
OS 39.8100423 -38.90452468
OS 39.8192879 -38.90544924
OS 39.82483526 -38.90544924
OS 39.8285335 -38.90452468
OS 39.8377791 -38.90267556
OS 39.85072294 -38.89990188
OS 39.86459134 -38.89435452
OS 39.8793843 -38.88695804
OS 39.89417726 -38.87586332
OS 39.90157374 -38.8693914
OS 39.90897022 -38.86199492
OS 39.90897022 -38.86107036
OS 39.91081934 -38.8601458
OS 39.91266846 -38.85737212
OS 39.91451758 -38.85367388
OS 39.91821582 -38.84905108
OS 39.9209895 -38.84257916
OS 39.92468774 -38.83610724
OS 39.92838598 -38.8277862
OS 39.93115966 -38.81946516
OS 39.9348579 -38.80837044
OS 39.93855614 -38.79727572
OS 39.94132982 -38.78525644
OS 39.94317894 -38.77138804
OS 39.94502806 -38.75659508
OS 39.94687718 -38.74087756
OS 39.94687718 -38.72423548
OS 39.94687718 -38.72331092
OS 39.94687718 -38.72053724
OS 39.94687718 -38.71591444
OS 39.94595262 -38.70944252
OS 39.94595262 -38.70204604
OS 39.94502806 -38.693725
OS 39.94225438 -38.67430924
OS 39.93763158 -38.65304436
OS 39.93115966 -38.63177948
OS 39.92191406 -38.6105146
OS 39.9163667 -38.60034444
OS 39.90989478 -38.5920234
OS 39.90989478 -38.59109884
OS 39.90804566 -38.59017428
OS 39.90342286 -38.58462692
OS 39.89602638 -38.578155
OS 39.88585622 -38.56983396
OS 39.87291238 -38.56151292
OS 39.85811942 -38.55411644
OS 39.84147734 -38.54949364
OS 39.83223174 -38.54856908
OS 39.82298614 -38.54764452
OE
OB 35.73550638 -38.39601668 H
OS 35.5524435 -38.39601668
OS 35.5524435 -38.624383
OS 35.72441166 -38.624383
OS 35.73088358 -38.62345844
OS 35.7373555 -38.62345844
OS 35.74475198 -38.62253388
OS 35.76231862 -38.62068476
OS 35.78173438 -38.61698652
OS 35.80115014 -38.61143916
OS 35.81871678 -38.60404268
OS 35.82703782 -38.59941988
OS 35.83350974 -38.59387252
OS 35.83535886 -38.5920234
OS 35.8390571 -38.58832516
OS 35.84460446 -38.58092868
OS 35.85107638 -38.57168308
OS 35.8575483 -38.5596638
OS 35.86309566 -38.54487084
OS 35.8667939 -38.52822876
OS 35.86864302 -38.508813
OS 35.86864302 -38.50788844
OS 35.86864302 -38.50696388
OS 35.86864302 -38.50234108
OS 35.86771846 -38.49402004
OS 35.86586934 -38.48477444
OS 35.86402022 -38.47460428
OS 35.86032198 -38.462585
OS 35.85477462 -38.45149028
OS 35.8483027 -38.44039556
OS 35.84737814 -38.439471
OS 35.84460446 -38.43577276
OS 35.83998166 -38.43114996
OS 35.8344343 -38.42467804
OS 35.82611326 -38.41820612
OS 35.81686766 -38.41265876
OS 35.8066975 -38.4071114
OS 35.79467822 -38.4024886
OS 35.79375366 -38.4024886
OS 35.79005542 -38.40156404
OS 35.78450806 -38.40063948
OS 35.77711158 -38.39879036
OS 35.76601686 -38.3978658
OS 35.75214846 -38.39694124
OS 35.73550638 -38.39601668
OE
OB 43.44263854 -38.5504182 H
OS 43.43709118 -38.5504182
OS 43.43339294 -38.55134276
OS 43.42322278 -38.55226732
OS 43.4112035 -38.555041
OS 43.39641054 -38.5596638
OS 43.38069302 -38.56613572
OS 43.36590006 -38.57538132
OS 43.3511071 -38.5874006
OS 43.34925798 -38.58924972
OS 43.34555974 -38.59387252
OS 43.33908782 -38.60219356
OS 43.3326159 -38.61328828
OS 43.32521942 -38.62623212
OS 43.3187475 -38.6428742
OS 43.31320014 -38.66228996
OS 43.31042646 -38.68355484
OS 43.57022782 -38.68355484
OS 43.57022782 -38.68263028
OS 43.57022782 -38.68078116
OS 43.56930326 -38.67800748
OS 43.56930326 -38.67430924
OS 43.56745414 -38.66321452
OS 43.56468046 -38.65119524
OS 43.56005766 -38.63640228
OS 43.55543486 -38.62253388
OS 43.54803838 -38.60866548
OS 43.53971734 -38.5966462
OS 43.53971734 -38.59572164
OS 43.53786822 -38.59479708
OS 43.53324542 -38.58924972
OS 43.52492438 -38.58185324
OS 43.51382966 -38.5735322
OS 43.49996126 -38.56521116
OS 43.48331918 -38.55781468
OS 43.46390342 -38.55226732
OS 43.45373326 -38.55134276
OS 43.44263854 -38.5504182
OE
OB 34.35791198 -38.39601668 H
OS 34.20628414 -38.39601668
OS 34.20628414 -38.58832516
OS 34.36345934 -38.58832516
OS 34.37547862 -38.5874006
OS 34.38842246 -38.58647604
OS 34.4013663 -38.58555148
OS 34.41431014 -38.58370236
OS 34.4244803 -38.58185324
OS 34.42632942 -38.58092868
OS 34.43002766 -38.58000412
OS 34.43557502 -38.57723044
OS 34.4429715 -38.5735322
OS 34.45036798 -38.56983396
OS 34.45868902 -38.5642866
OS 34.46701006 -38.55689012
OS 34.47348198 -38.54949364
OS 34.47440654 -38.54856908
OS 34.47625566 -38.5457954
OS 34.47902934 -38.54024804
OS 34.48180302 -38.53377612
OS 34.4845767 -38.52637964
OS 34.48735038 -38.51713404
OS 34.4891995 -38.50603932
OS 34.49012406 -38.49402004
OS 34.49012406 -38.49217092
OS 34.49012406 -38.48847268
OS 34.4891995 -38.48292532
OS 34.48827494 -38.47552884
OS 34.48642582 -38.46628324
OS 34.48365214 -38.45703764
OS 34.4799539 -38.44779204
OS 34.47440654 -38.43854644
OS 34.47348198 -38.43762188
OS 34.47163286 -38.4348482
OS 34.46793462 -38.4302254
OS 34.46331182 -38.4256026
OS 34.4568399 -38.42005524
OS 34.44944342 -38.41450788
OS 34.44019782 -38.40896052
OS 34.43002766 -38.40526228
OS 34.4291031 -38.40526228
OS 34.4244803 -38.40341316
OS 34.41800838 -38.4024886
OS 34.40783822 -38.40063948
OS 34.39396982 -38.39879036
OS 34.3782523 -38.3978658
OS 34.35791198 -38.39601668
OE
OB 40.89732486 -38.39601668 H
OS 40.71426198 -38.39601668
OS 40.71426198 -38.624383
OS 40.88623014 -38.624383
OS 40.89270206 -38.62345844
OS 40.89917398 -38.62345844
OS 40.90657046 -38.62253388
OS 40.9241371 -38.62068476
OS 40.94355286 -38.61698652
OS 40.96296862 -38.61143916
OS 40.98053526 -38.60404268
OS 40.9888563 -38.59941988
OS 40.99532822 -38.59387252
OS 40.99717734 -38.5920234
OS 41.00087558 -38.58832516
OS 41.00642294 -38.58092868
OS 41.01289486 -38.57168308
OS 41.01936678 -38.5596638
OS 41.02491414 -38.54487084
OS 41.02861238 -38.52822876
OS 41.0304615 -38.508813
OS 41.0304615 -38.50788844
OS 41.0304615 -38.50696388
OS 41.0304615 -38.50234108
OS 41.02953694 -38.49402004
OS 41.02768782 -38.48477444
OS 41.0258387 -38.47460428
OS 41.02214046 -38.462585
OS 41.0165931 -38.45149028
OS 41.01012118 -38.44039556
OS 41.00919662 -38.439471
OS 41.00642294 -38.43577276
OS 41.00180014 -38.43114996
OS 40.99625278 -38.42467804
OS 40.98793174 -38.41820612
OS 40.97868614 -38.41265876
OS 40.96851598 -38.4071114
OS 40.9564967 -38.4024886
OS 40.95557214 -38.4024886
OS 40.9518739 -38.40156404
OS 40.94632654 -38.40063948
OS 40.93893006 -38.39879036
OS 40.92783534 -38.3978658
OS 40.91396694 -38.39694124
OS 40.89732486 -38.39601668
OE
OB 33.15136118 -38.39601668 H
OS 32.9682983 -38.39601668
OS 32.9682983 -38.624383
OS 33.14026646 -38.624383
OS 33.14673838 -38.62345844
OS 33.1532103 -38.62345844
OS 33.16060678 -38.62253388
OS 33.17817342 -38.62068476
OS 33.19758918 -38.61698652
OS 33.21700494 -38.61143916
OS 33.23457158 -38.60404268
OS 33.24289262 -38.59941988
OS 33.24936454 -38.59387252
OS 33.25121366 -38.5920234
OS 33.2549119 -38.58832516
OS 33.26045926 -38.58092868
OS 33.26693118 -38.57168308
OS 33.2734031 -38.5596638
OS 33.27895046 -38.54487084
OS 33.2826487 -38.52822876
OS 33.28449782 -38.508813
OS 33.28449782 -38.50788844
OS 33.28449782 -38.50696388
OS 33.28449782 -38.50234108
OS 33.28357326 -38.49402004
OS 33.28172414 -38.48477444
OS 33.27987502 -38.47460428
OS 33.27617678 -38.462585
OS 33.27062942 -38.45149028
OS 33.2641575 -38.44039556
OS 33.26323294 -38.439471
OS 33.26045926 -38.43577276
OS 33.25583646 -38.43114996
OS 33.2502891 -38.42467804
OS 33.24196806 -38.41820612
OS 33.23272246 -38.41265876
OS 33.2225523 -38.4071114
OS 33.21053302 -38.4024886
OS 33.20960846 -38.4024886
OS 33.20591022 -38.40156404
OS 33.20036286 -38.40063948
OS 33.19296638 -38.39879036
OS 33.18187166 -38.3978658
OS 33.16800326 -38.39694124
OS 33.15136118 -38.39601668
OE
OB 34.37455406 -38.66413908 H
OS 34.20628414 -38.66413908
OS 34.20628414 -38.88418436
OS 34.38842246 -38.88418436
OS 34.40783822 -38.8832598
OS 34.41615926 -38.88233524
OS 34.42355574 -38.88141068
OS 34.4244803 -38.88141068
OS 34.42817854 -38.88048612
OS 34.4337259 -38.87956156
OS 34.44019782 -38.87771244
OS 34.45591534 -38.87216508
OS 34.47163286 -38.8647686
OS 34.47255742 -38.86384404
OS 34.4753311 -38.86199492
OS 34.47902934 -38.85922124
OS 34.48365214 -38.855523
OS 34.48827494 -38.84997564
OS 34.49474686 -38.84442828
OS 34.49936966 -38.8370318
OS 34.50491702 -38.82871076
OS 34.50584158 -38.8277862
OS 34.50676614 -38.82501252
OS 34.50861526 -38.81946516
OS 34.51138894 -38.81299324
OS 34.51416262 -38.80559676
OS 34.51601174 -38.79635116
OS 34.5169363 -38.78525644
OS 34.51786086 -38.77416172
OS 34.51786086 -38.7723126
OS 34.51786086 -38.76861436
OS 34.5169363 -38.76121788
OS 34.51508718 -38.75289684
OS 34.51323806 -38.74365124
OS 34.50953982 -38.73348108
OS 34.50491702 -38.72331092
OS 34.4984451 -38.71314076
OS 34.49752054 -38.7122162
OS 34.49474686 -38.70851796
OS 34.49104862 -38.70389516
OS 34.48550126 -38.6983478
OS 34.47810478 -38.69187588
OS 34.46885918 -38.68540396
OS 34.45868902 -38.6798566
OS 34.44666974 -38.6752338
OS 34.44482062 -38.67430924
OS 34.44112238 -38.67338468
OS 34.43280134 -38.67153556
OS 34.42263118 -38.66968644
OS 34.40968734 -38.66783732
OS 34.39396982 -38.6659882
OS 34.37455406 -38.66413908
OE
SE
S P 0
OB 48.49040086 -36.61402634 I
OS 48.17420134 -36.61402634
OS 48.17420134 -37.45999874
OS 48.04661206 -37.45999874
OS 48.04661206 -36.61402634
OS 47.73041254 -36.61402634
OS 47.73041254 -36.50030546
OS 48.49040086 -36.50030546
OS 48.49040086 -36.61402634
OE
OB 47.69990206 -37.45999874 I
OS 47.5556707 -37.45999874
OS 47.44333666 -37.16876234
OS 47.04115306 -37.16876234
OS 46.93714006 -37.45999874
OS 46.80261658 -37.45999874
OS 47.16874234 -36.50030546
OS 47.30742634 -36.50030546
OS 47.69990206 -37.45999874
OE
OB 49.31834434 -36.61402634 I
OS 48.75112678 -36.61402634
OS 48.75112678 -36.90664958
OS 49.2822865 -36.90664958
OS 49.2822865 -37.02037046
OS 48.75112678 -37.02037046
OS 48.75112678 -37.34627786
OS 49.34053378 -37.34627786
OS 49.34053378 -37.45999874
OS 48.6235375 -37.45999874
OS 48.6235375 -36.50030546
OS 49.31834434 -36.50030546
OS 49.31834434 -36.61402634
OE
OB 46.33386466 -36.5016923 I
OS 46.36160146 -36.50307914
OS 46.38933826 -36.50585282
OS 46.41707506 -36.51001334
OS 46.44065134 -36.51417386
OS 46.44203818 -36.51417386
OS 46.44481186 -36.5155607
OS 46.44897238 -36.5155607
OS 46.45451974 -36.51833438
OS 46.46977498 -36.5224949
OS 46.48919074 -36.5294291
OS 46.51138018 -36.53913698
OS 46.53495646 -36.55161854
OS 46.55853274 -36.56548694
OS 46.58072218 -36.58351586
OS 46.58210902 -36.5849027
OS 46.58349586 -36.58628954
OS 46.58765638 -36.59045006
OS 46.59320374 -36.59461058
OS 46.60707214 -36.60847898
OS 46.62371422 -36.62789474
OS 46.64174314 -36.65147102
OS 46.6611589 -36.67920782
OS 46.67918782 -36.71110514
OS 46.69444306 -36.74716298
OS 46.69444306 -36.74854982
OS 46.6958299 -36.7513235
OS 46.69860358 -36.75687086
OS 46.69999042 -36.7651919
OS 46.70415094 -36.77489978
OS 46.70692462 -36.7859945
OS 46.7096983 -36.79847606
OS 46.71385882 -36.8137313
OS 46.71801934 -36.82898654
OS 46.72079302 -36.84701546
OS 46.72772722 -36.88584698
OS 46.73188774 -36.92883902
OS 46.73327458 -36.97599158
OS 46.73327458 -36.97737842
OS 46.73327458 -36.9801521
OS 46.73327458 -36.9870863
OS 46.73327458 -36.9940205
OS 46.73188774 -37.00372838
OS 46.73188774 -37.0148231
OS 46.7305009 -37.04117306
OS 46.72634038 -37.07168354
OS 46.72217986 -37.10358086
OS 46.71524566 -37.13686502
OS 46.70692462 -37.17014918
OS 46.70692462 -37.17153602
OS 46.70553778 -37.1743097
OS 46.70415094 -37.17847022
OS 46.7027641 -37.18401758
OS 46.69721674 -37.19927282
OS 46.6888957 -37.21868858
OS 46.68057466 -37.24087802
OS 46.66947994 -37.26306746
OS 46.65561154 -37.28664374
OS 46.64174314 -37.30883318
OS 46.6403563 -37.31160686
OS 46.63480894 -37.31854106
OS 46.6264879 -37.32824894
OS 46.61539318 -37.3407305
OS 46.60291162 -37.3545989
OS 46.58765638 -37.3684673
OS 46.57240114 -37.38372254
OS 46.55437222 -37.3962041
OS 46.55159854 -37.39759094
OS 46.54605118 -37.40175146
OS 46.5363433 -37.40729882
OS 46.5224749 -37.41423302
OS 46.50583282 -37.42255406
OS 46.48641706 -37.42948826
OS 46.46422762 -37.4378093
OS 46.4392645 -37.4447435
OS 46.43649082 -37.4447435
OS 46.4323303 -37.44613034
OS 46.42816978 -37.44751718
OS 46.41430138 -37.44890402
OS 46.39488562 -37.4516777
OS 46.37269618 -37.45445138
OS 46.34634622 -37.45722506
OS 46.31722258 -37.4586119
OS 46.28532526 -37.45999874
OS 45.9400021 -37.45999874
OS 45.9400021 -36.50030546
OS 46.30890154 -36.50030546
OS 46.33386466 -36.5016923
OE
OB 46.28948578 -36.61402634 H
OS 46.06759138 -36.61402634
OS 46.06759138 -37.34627786
OS 46.29503314 -37.34627786
OS 46.30474102 -37.34489102
OS 46.32554362 -37.34350418
OS 46.3491199 -37.34211734
OS 46.37408302 -37.33934366
OS 46.39904614 -37.33518314
OS 46.41984874 -37.32963578
OS 46.42262242 -37.32824894
OS 46.42955662 -37.3268621
OS 46.4392645 -37.32270158
OS 46.45174606 -37.31715422
OS 46.46561446 -37.30883318
OS 46.47948286 -37.30051214
OS 46.49335126 -37.29080426
OS 46.50721966 -37.27970954
OS 46.5086065 -37.27693586
OS 46.51415386 -37.2713885
OS 46.5224749 -37.26168062
OS 46.53218278 -37.24781222
OS 46.5432775 -37.2297833
OS 46.55575906 -37.2089807
OS 46.56685378 -37.18540442
OS 46.57656166 -37.15905446
OS 46.57656166 -37.15766762
OS 46.5779485 -37.15489394
OS 46.57933534 -37.15073342
OS 46.58072218 -37.14518606
OS 46.58210902 -37.13825186
OS 46.5848827 -37.12854398
OS 46.58765638 -37.1188361
OS 46.59043006 -37.10774138
OS 46.59459058 -37.08000458
OS 46.5987511 -37.04810726
OS 46.60152478 -37.01204942
OS 46.60291162 -36.9732179
OS 46.60291162 -36.97183106
OS 46.60291162 -36.9662837
OS 46.60291162 -36.9593495
OS 46.60152478 -36.94825478
OS 46.60152478 -36.93577322
OS 46.60013794 -36.92190482
OS 46.5987511 -36.90526274
OS 46.59736426 -36.88862066
OS 46.59043006 -36.85117598
OS 46.58210902 -36.81234446
OS 46.56962746 -36.77628662
OS 46.56130642 -36.7582577
OS 46.55298538 -36.74300246
OS 46.55298538 -36.74161562
OS 46.5502117 -36.73884194
OS 46.54743802 -36.73468142
OS 46.54466434 -36.72913406
OS 46.53356962 -36.71526566
OS 46.51970122 -36.69862358
OS 46.5016723 -36.68059466
OS 46.4808697 -36.66256574
OS 46.45729342 -36.6473105
OS 46.4323303 -36.63482894
OS 46.42955662 -36.6334421
OS 46.42262242 -36.63205526
OS 46.41014086 -36.62789474
OS 46.39211194 -36.62373422
OS 46.3699225 -36.62096054
OS 46.3421857 -36.61680002
OS 46.32554362 -36.61541318
OS 46.3075147 -36.61541318
OS 46.28948578 -36.61402634
OE
OB 47.23531066 -36.60015794 H
OS 47.23531066 -36.60154478
OS 47.23392382 -36.60431846
OS 47.23392382 -36.60986582
OS 47.23115014 -36.61541318
OS 47.2297633 -36.62512106
OS 47.22698962 -36.63482894
OS 47.22144226 -36.65840522
OS 47.21450806 -36.68614202
OS 47.20480018 -36.7166525
OS 47.1950923 -36.74993666
OS 47.18261074 -36.78460766
OS 47.07859774 -37.06474934
OS 47.4031183 -37.06474934
OS 47.30326582 -36.80124974
OS 47.30326582 -36.7998629
OS 47.30187898 -36.79570238
OS 47.2991053 -36.78876818
OS 47.29633162 -36.78044714
OS 47.2921711 -36.77073926
OS 47.28801058 -36.7582577
OS 47.28385006 -36.7443893
OS 47.2783027 -36.7305209
OS 47.26720798 -36.69862358
OS 47.25611326 -36.66533942
OS 47.24501854 -36.63205526
OS 47.23531066 -36.60015794
OE
SE
S P 0
OB 53.57408132 -38.30725892 I
OS 53.5861006 -38.30910804
OS 53.60089356 -38.31188172
OS 53.61753564 -38.31650452
OS 53.63417772 -38.32205188
OS 53.6508198 -38.32944836
OS 53.65174436 -38.32944836
OS 53.65266892 -38.33037292
OS 53.65821628 -38.3331466
OS 53.66653732 -38.33869396
OS 53.67578292 -38.34516588
OS 53.68687764 -38.35441148
OS 53.69797236 -38.36458164
OS 53.70906708 -38.37660092
OS 53.71831268 -38.39046932
OS 53.71923724 -38.39231844
OS 53.72201092 -38.39694124
OS 53.72570916 -38.40526228
OS 53.73033196 -38.41543244
OS 53.73495476 -38.42745172
OS 53.738653 -38.44132012
OS 53.74142668 -38.45703764
OS 53.74235124 -38.47275516
OS 53.74235124 -38.47460428
OS 53.74235124 -38.48015164
OS 53.74142668 -38.48754812
OS 53.73957756 -38.49771828
OS 53.73680388 -38.50973756
OS 53.73218108 -38.5226814
OS 53.72663372 -38.53562524
OS 53.71923724 -38.54856908
OS 53.71831268 -38.5504182
OS 53.715539 -38.55411644
OS 53.70999164 -38.56058836
OS 53.70259516 -38.56798484
OS 53.69334956 -38.57630588
OS 53.68225484 -38.58555148
OS 53.669311 -38.59387252
OS 53.65359348 -38.60219356
OS 53.65451804 -38.60219356
OS 53.65636716 -38.60311812
OS 53.65914084 -38.60404268
OS 53.66283908 -38.60496724
OS 53.67300924 -38.60866548
OS 53.68595308 -38.61421284
OS 53.70074604 -38.62160932
OS 53.715539 -38.63085492
OS 53.7294074 -38.6428742
OS 53.74235124 -38.6567426
OS 53.7432758 -38.65859172
OS 53.74697404 -38.66413908
OS 53.7525214 -38.67338468
OS 53.75806876 -38.68540396
OS 53.76361612 -38.70019692
OS 53.76916348 -38.71776356
OS 53.77286172 -38.73810388
OS 53.77378628 -38.76029332
OS 53.77378628 -38.76121788
OS 53.77378628 -38.76399156
OS 53.77378628 -38.76861436
OS 53.77286172 -38.77416172
OS 53.77193716 -38.7815582
OS 53.77008804 -38.78987924
OS 53.76823892 -38.79912484
OS 53.7663898 -38.809295
OS 53.75899332 -38.83148444
OS 53.75344596 -38.84350372
OS 53.7478986 -38.85459844
OS 53.74050212 -38.86661772
OS 53.73218108 -38.878637
OS 53.72293548 -38.89065628
OS 53.71184076 -38.901751
OS 53.7109162 -38.90267556
OS 53.70906708 -38.90452468
OS 53.70536884 -38.90729836
OS 53.70074604 -38.9109966
OS 53.69519868 -38.9156194
OS 53.6878022 -38.9202422
OS 53.67948116 -38.92578956
OS 53.669311 -38.93041236
OS 53.65914084 -38.93595972
OS 53.64712156 -38.94150708
OS 53.63510228 -38.94612988
OS 53.62123388 -38.95075268
OS 53.60644092 -38.95445092
OS 53.5907234 -38.9572246
OS 53.57500588 -38.95907372
OS 53.55743924 -38.95999828
OS 53.5491182 -38.95999828
OS 53.54357084 -38.95907372
OS 53.53617436 -38.95814916
OS 53.52785332 -38.9572246
OS 53.51860772 -38.95537548
OS 53.50843756 -38.95352636
OS 53.48624812 -38.947979
OS 53.46313412 -38.9387334
OS 53.45111484 -38.93318604
OS 53.44002012 -38.92671412
OS 53.4289254 -38.91839308
OS 53.41783068 -38.91007204
OS 53.41690612 -38.90914748
OS 53.415057 -38.90729836
OS 53.41228332 -38.90452468
OS 53.40950964 -38.90082644
OS 53.40488684 -38.89620364
OS 53.40026404 -38.88973172
OS 53.39471668 -38.8832598
OS 53.38916932 -38.87493876
OS 53.38362196 -38.86569316
OS 53.3780746 -38.85644756
OS 53.36790444 -38.83425812
OS 53.3595834 -38.80837044
OS 53.35680972 -38.79450204
OS 53.3549606 -38.77970908
OS 53.4335482 -38.76953892
OS 53.4335482 -38.77046348
OS 53.43447276 -38.7723126
OS 53.43539732 -38.77601084
OS 53.43632188 -38.78063364
OS 53.43724644 -38.786181
OS 53.43909556 -38.79265292
OS 53.44371836 -38.80652132
OS 53.45019028 -38.8231634
OS 53.45851132 -38.83888092
OS 53.46775692 -38.85367388
OS 53.47885164 -38.86661772
OS 53.48070076 -38.86754228
OS 53.484399 -38.87124052
OS 53.49179548 -38.87586332
OS 53.50104108 -38.88048612
OS 53.5121358 -38.88603348
OS 53.5260042 -38.89065628
OS 53.54172172 -38.89435452
OS 53.5583638 -38.89527908
OS 53.56391116 -38.89527908
OS 53.5676094 -38.89435452
OS 53.57777956 -38.89342996
OS 53.5907234 -38.89065628
OS 53.60551636 -38.88603348
OS 53.62123388 -38.87956156
OS 53.6369514 -38.87031596
OS 53.65174436 -38.85737212
OS 53.65359348 -38.855523
OS 53.65821628 -38.84997564
OS 53.66376364 -38.8416546
OS 53.67116012 -38.83055988
OS 53.6785566 -38.81669148
OS 53.68410396 -38.80097396
OS 53.68872676 -38.78248276
OS 53.69057588 -38.76214244
OS 53.69057588 -38.76121788
OS 53.69057588 -38.75936876
OS 53.69057588 -38.75659508
OS 53.68965132 -38.75289684
OS 53.68872676 -38.74272668
OS 53.68595308 -38.7307074
OS 53.68225484 -38.71591444
OS 53.67578292 -38.70112148
OS 53.66653732 -38.68632852
OS 53.65451804 -38.67246012
OS 53.65266892 -38.670611
OS 53.64804612 -38.66691276
OS 53.64064964 -38.6613654
OS 53.63047948 -38.65489348
OS 53.61753564 -38.64842156
OS 53.60181812 -38.6428742
OS 53.58425148 -38.63917596
OS 53.56483572 -38.63732684
OS 53.55651468 -38.63732684
OS 53.55004276 -38.6382514
OS 53.54172172 -38.63917596
OS 53.53247612 -38.64102508
OS 53.5213814 -38.6428742
OS 53.50936212 -38.64564788
OS 53.51860772 -38.57630588
OS 53.52323052 -38.57630588
OS 53.52692876 -38.57723044
OS 53.53894804 -38.57723044
OS 53.5491182 -38.57538132
OS 53.56113748 -38.5735322
OS 53.57500588 -38.57075852
OS 53.5907234 -38.56613572
OS 53.60551636 -38.5596638
OS 53.62123388 -38.55134276
OS 53.62215844 -38.55134276
OS 53.623083 -38.5504182
OS 53.6277058 -38.54671996
OS 53.63417772 -38.54024804
OS 53.6415742 -38.531927
OS 53.64897068 -38.51990772
OS 53.6554426 -38.50603932
OS 53.6600654 -38.4903218
OS 53.66191452 -38.4810762
OS 53.66191452 -38.47090604
OS 53.66191452 -38.46998148
OS 53.66191452 -38.46905692
OS 53.66191452 -38.46350956
OS 53.6600654 -38.45611308
OS 53.65821628 -38.44594292
OS 53.65451804 -38.4348482
OS 53.64989524 -38.42282892
OS 53.64249876 -38.41080964
OS 53.6323286 -38.39971492
OS 53.63140404 -38.39879036
OS 53.62678124 -38.39509212
OS 53.62030932 -38.39046932
OS 53.61198828 -38.38492196
OS 53.60089356 -38.38029916
OS 53.58794972 -38.37567636
OS 53.57315676 -38.37197812
OS 53.55651468 -38.37105356
OS 53.5491182 -38.37105356
OS 53.54079716 -38.37290268
OS 53.52970244 -38.3747518
OS 53.51768316 -38.37845004
OS 53.50566388 -38.38307284
OS 53.49272004 -38.39046932
OS 53.48070076 -38.39971492
OS 53.4797762 -38.40063948
OS 53.47607796 -38.40526228
OS 53.4705306 -38.4117342
OS 53.46405868 -38.4209798
OS 53.45758676 -38.43299908
OS 53.45111484 -38.44779204
OS 53.44556748 -38.46535868
OS 53.44186924 -38.485699
OS 53.36328164 -38.4718306
OS 53.36328164 -38.47090604
OS 53.3642062 -38.46813236
OS 53.36513076 -38.46443412
OS 53.36605532 -38.45888676
OS 53.36790444 -38.45241484
OS 53.37067812 -38.44501836
OS 53.37622548 -38.42745172
OS 53.38547108 -38.4071114
OS 53.3965658 -38.38677108
OS 53.4104342 -38.36735532
OS 53.42800084 -38.34978868
OS 53.4289254 -38.34886412
OS 53.43077452 -38.34793956
OS 53.4335482 -38.34609044
OS 53.43724644 -38.34331676
OS 53.44186924 -38.33961852
OS 53.44834116 -38.33592028
OS 53.45481308 -38.33222204
OS 53.46313412 -38.32759924
OS 53.48162532 -38.32020276
OS 53.5028902 -38.31280628
OS 53.52785332 -38.30818348
OS 53.54079716 -38.30633436
OS 53.56391116 -38.30633436
OS 53.57408132 -38.30725892
OE
OB 54.07889108 -38.30725892 I
OS 54.09091036 -38.30910804
OS 54.10477876 -38.31188172
OS 54.11957172 -38.31557996
OS 54.13528924 -38.32020276
OS 54.1500822 -38.32759924
OS 54.15100676 -38.32759924
OS 54.15193132 -38.3285238
OS 54.15655412 -38.33129748
OS 54.1639506 -38.33592028
OS 54.1731962 -38.3423922
OS 54.18336636 -38.3516378
OS 54.19446108 -38.36180796
OS 54.20463124 -38.37382724
OS 54.2148014 -38.38769564
OS 54.21572596 -38.38954476
OS 54.2194242 -38.39416756
OS 54.22312244 -38.4024886
OS 54.22959436 -38.41450788
OS 54.23514172 -38.42837628
OS 54.2425382 -38.4440938
OS 54.24901012 -38.462585
OS 54.25455748 -38.48292532
OS 54.25455748 -38.48384988
OS 54.25548204 -38.485699
OS 54.2564066 -38.48847268
OS 54.25733116 -38.49309548
OS 54.25825572 -38.49864284
OS 54.25918028 -38.50511476
OS 54.2610294 -38.5134358
OS 54.26195396 -38.5226814
OS 54.26380308 -38.53285156
OS 54.26472764 -38.54394628
OS 54.2656522 -38.55689012
OS 54.26750132 -38.56983396
OS 54.26842588 -38.58462692
OS 54.26842588 -38.59941988
OS 54.26935044 -38.61606196
OS 54.26935044 -38.6336286
OS 54.26935044 -38.63455316
OS 54.26935044 -38.6382514
OS 54.26935044 -38.64472332
OS 54.26935044 -38.6521198
OS 54.26842588 -38.66228996
OS 54.26842588 -38.67338468
OS 54.26750132 -38.68540396
OS 54.26657676 -38.6983478
OS 54.26380308 -38.72793372
OS 54.25918028 -38.7584442
OS 54.25363292 -38.78803012
OS 54.24993468 -38.80189852
OS 54.24531188 -38.81576692
OS 54.24531188 -38.81669148
OS 54.24438732 -38.8185406
OS 54.2425382 -38.82223884
OS 54.24068908 -38.82686164
OS 54.23883996 -38.83333356
OS 54.23514172 -38.83980548
OS 54.22774524 -38.855523
OS 54.21849964 -38.87216508
OS 54.20648036 -38.89065628
OS 54.19261196 -38.90729836
OS 54.17596988 -38.92301588
OS 54.17504532 -38.92301588
OS 54.17412076 -38.924865
OS 54.17134708 -38.92671412
OS 54.16764884 -38.92856324
OS 54.16302604 -38.93133692
OS 54.15840324 -38.93503516
OS 54.14453484 -38.94150708
OS 54.12789276 -38.947979
OS 54.108477 -38.95445092
OS 54.085363 -38.95814916
OS 54.06039988 -38.95999828
OS 54.05115428 -38.95999828
OS 54.04468236 -38.95907372
OS 54.03728588 -38.95814916
OS 54.02804028 -38.95630004
OS 54.01787012 -38.95445092
OS 54.0067754 -38.95167724
OS 53.99568068 -38.947979
OS 53.9836614 -38.94428076
OS 53.97164212 -38.9387334
OS 53.95962284 -38.93226148
OS 53.94760356 -38.924865
OS 53.93558428 -38.9156194
OS 53.92448956 -38.90544924
OS 53.9143194 -38.89435452
OS 53.91339484 -38.89342996
OS 53.91154572 -38.89065628
OS 53.90877204 -38.88603348
OS 53.90414924 -38.878637
OS 53.89952644 -38.87031596
OS 53.89490364 -38.85922124
OS 53.88843172 -38.8462774
OS 53.88288436 -38.83148444
OS 53.877337 -38.81484236
OS 53.87178964 -38.7954266
OS 53.86624228 -38.77416172
OS 53.86161948 -38.75012316
OS 53.85699668 -38.72423548
OS 53.854223 -38.69649868
OS 53.85237388 -38.6659882
OS 53.85144932 -38.6336286
OS 53.85144932 -38.63270404
OS 53.85144932 -38.6290058
OS 53.85144932 -38.62253388
OS 53.85144932 -38.6151374
OS 53.85237388 -38.60496724
OS 53.85237388 -38.59387252
OS 53.85329844 -38.58185324
OS 53.854223 -38.56798484
OS 53.85699668 -38.53932348
OS 53.86161948 -38.508813
OS 53.86716684 -38.47830252
OS 53.87086508 -38.46443412
OS 53.87456332 -38.45056572
OS 53.87456332 -38.44964116
OS 53.87548788 -38.44779204
OS 53.877337 -38.4440938
OS 53.87918612 -38.439471
OS 53.88103524 -38.43299908
OS 53.88473348 -38.42652716
OS 53.89212996 -38.41080964
OS 53.90137556 -38.39416756
OS 53.91339484 -38.37660092
OS 53.92726324 -38.35903428
OS 53.94390532 -38.34424132
OS 53.94482988 -38.34424132
OS 53.94575444 -38.3423922
OS 53.94852812 -38.34054308
OS 53.95222636 -38.33869396
OS 53.95684916 -38.33499572
OS 53.96239652 -38.33222204
OS 53.97626492 -38.32482556
OS 53.992907 -38.31835364
OS 54.01232276 -38.31188172
OS 54.03543676 -38.30818348
OS 54.06039988 -38.30633436
OS 54.06872092 -38.30633436
OS 54.07889108 -38.30725892
OE
OB 53.23846604 -38.94890356 I
OS 53.14878372 -38.94890356
OS 53.14878372 -38.85922124
OS 53.23846604 -38.85922124
OS 53.23846604 -38.94890356
OE
OB 53.00177868 -38.39231844 I
OS 52.74567556 -38.39231844
OS 52.71146684 -38.56521116
OS 52.7123914 -38.5642866
OS 52.71424052 -38.56336204
OS 52.7170142 -38.56151292
OS 52.721637 -38.55873924
OS 52.72718436 -38.55596556
OS 52.73365628 -38.55226732
OS 52.74844924 -38.54487084
OS 52.76694044 -38.53747436
OS 52.78728076 -38.53100244
OS 52.8094702 -38.52637964
OS 52.82056492 -38.52453052
OS 52.84090524 -38.52453052
OS 52.8464526 -38.52545508
OS 52.85384908 -38.52637964
OS 52.86217012 -38.5273042
OS 52.87141572 -38.52915332
OS 52.88158588 -38.531927
OS 52.90377532 -38.53839892
OS 52.9157946 -38.54302172
OS 52.92781388 -38.54949364
OS 52.93983316 -38.55596556
OS 52.95185244 -38.56336204
OS 52.96294716 -38.57260764
OS 52.97404188 -38.5827778
OS 52.97496644 -38.58370236
OS 52.97681556 -38.58555148
OS 52.97958924 -38.58832516
OS 52.98328748 -38.59294796
OS 52.98791028 -38.59941988
OS 52.99253308 -38.6058918
OS 52.99808044 -38.61421284
OS 53.0036278 -38.62345844
OS 53.0082506 -38.6336286
OS 53.01379796 -38.64472332
OS 53.01842076 -38.65766716
OS 53.02304356 -38.670611
OS 53.0267418 -38.6844794
OS 53.02951548 -38.70019692
OS 53.0313646 -38.71591444
OS 53.03228916 -38.73255652
OS 53.03228916 -38.73348108
OS 53.03228916 -38.73625476
OS 53.03228916 -38.74087756
OS 53.0313646 -38.74734948
OS 53.03044004 -38.75474596
OS 53.02951548 -38.763067
OS 53.02766636 -38.77323716
OS 53.02581724 -38.78340732
OS 53.02026988 -38.80744588
OS 53.01102428 -38.832409
OS 53.00547692 -38.84535284
OS 52.99808044 -38.85737212
OS 52.99068396 -38.87031596
OS 52.98143836 -38.88233524
OS 52.9805138 -38.8832598
OS 52.97866468 -38.88603348
OS 52.97496644 -38.88973172
OS 52.97034364 -38.89435452
OS 52.96387172 -38.89990188
OS 52.95647524 -38.90729836
OS 52.94722964 -38.91377028
OS 52.93705948 -38.92116676
OS 52.92596476 -38.92856324
OS 52.91302092 -38.93503516
OS 52.89915252 -38.94150708
OS 52.88435956 -38.947979
OS 52.86864204 -38.9526018
OS 52.8510754 -38.95630004
OS 52.8325842 -38.95907372
OS 52.81316844 -38.95999828
OS 52.8048474 -38.95999828
OS 52.79837548 -38.95907372
OS 52.790979 -38.95814916
OS 52.78265796 -38.9572246
OS 52.7724878 -38.95630004
OS 52.76231764 -38.95352636
OS 52.73920364 -38.947979
OS 52.71608964 -38.93965796
OS 52.70407036 -38.9341106
OS 52.69205108 -38.92763868
OS 52.68095636 -38.9202422
OS 52.66986164 -38.91192116
OS 52.66893708 -38.9109966
OS 52.66708796 -38.91007204
OS 52.66523884 -38.9063738
OS 52.6615406 -38.90267556
OS 52.6569178 -38.89805276
OS 52.652295 -38.8925054
OS 52.64674764 -38.88510892
OS 52.64212484 -38.87678788
OS 52.63657748 -38.86846684
OS 52.63103012 -38.85829668
OS 52.62085996 -38.83610724
OS 52.61253892 -38.81021956
OS 52.60976524 -38.79635116
OS 52.60791612 -38.7815582
OS 52.69020196 -38.77508628
OS 52.69020196 -38.77601084
OS 52.69020196 -38.77785996
OS 52.69112652 -38.78063364
OS 52.69205108 -38.78525644
OS 52.69482476 -38.7954266
OS 52.698523 -38.809295
OS 52.70407036 -38.8231634
OS 52.71146684 -38.83888092
OS 52.72071244 -38.85274932
OS 52.73180716 -38.86569316
OS 52.73365628 -38.86661772
OS 52.73735452 -38.87031596
OS 52.744751 -38.87493876
OS 52.75492116 -38.88048612
OS 52.76601588 -38.88603348
OS 52.77988428 -38.89065628
OS 52.7956018 -38.89435452
OS 52.81316844 -38.89527908
OS 52.8187158 -38.89527908
OS 52.82241404 -38.89435452
OS 52.83350876 -38.89342996
OS 52.8464526 -38.88973172
OS 52.86217012 -38.88510892
OS 52.87788764 -38.87771244
OS 52.89452972 -38.86661772
OS 52.9019262 -38.8601458
OS 52.90932268 -38.85274932
OS 52.91024724 -38.85182476
OS 52.9111718 -38.8509002
OS 52.91302092 -38.84812652
OS 52.9157946 -38.84535284
OS 52.92226652 -38.83518268
OS 52.929663 -38.82223884
OS 52.93613492 -38.80652132
OS 52.94260684 -38.78710556
OS 52.94722964 -38.76399156
OS 52.94907876 -38.75197228
OS 52.94907876 -38.73902844
OS 52.94907876 -38.73810388
OS 52.94907876 -38.73625476
OS 52.94907876 -38.73255652
OS 52.9481542 -38.72793372
OS 52.9481542 -38.72238636
OS 52.94722964 -38.71591444
OS 52.94445596 -38.70112148
OS 52.93983316 -38.68355484
OS 52.93336124 -38.6659882
OS 52.92411564 -38.64934612
OS 52.9111718 -38.6336286
OS 52.9111718 -38.63270404
OS 52.90932268 -38.63177948
OS 52.90469988 -38.62715668
OS 52.89637884 -38.62068476
OS 52.88528412 -38.61328828
OS 52.87049116 -38.60681636
OS 52.85384908 -38.60034444
OS 52.83443332 -38.59572164
OS 52.8233386 -38.59387252
OS 52.80577196 -38.59387252
OS 52.79837548 -38.59479708
OS 52.78912988 -38.59572164
OS 52.77803516 -38.59849532
OS 52.76694044 -38.601269
OS 52.75492116 -38.6058918
OS 52.74290188 -38.61143916
OS 52.74197732 -38.61236372
OS 52.73827908 -38.61421284
OS 52.73273172 -38.61883564
OS 52.72533524 -38.62345844
OS 52.71793876 -38.62993036
OS 52.71054228 -38.6382514
OS 52.70222124 -38.64657244
OS 52.69574932 -38.6567426
OS 52.62178452 -38.64657244
OS 52.68373004 -38.31742908
OS 53.00177868 -38.31742908
OS 53.00177868 -38.39231844
OE
OB 53.23846604 -38.57445676 I
OS 53.14878372 -38.57445676
OS 53.14878372 -38.48477444
OS 53.23846604 -38.48477444
OS 53.23846604 -38.57445676
OE
OB 54.48199924 -38.57445676 I
OS 54.39231692 -38.57445676
OS 54.39231692 -38.48477444
OS 54.48199924 -38.48477444
OS 54.48199924 -38.57445676
OE
OB 56.14990548 -38.3100326 I
OS 56.165623 -38.31095716
OS 56.18226508 -38.31188172
OS 56.1979826 -38.31373084
OS 56.211851 -38.31557996
OS 56.21370012 -38.31557996
OS 56.22017204 -38.31742908
OS 56.22849308 -38.3192782
OS 56.2395878 -38.32205188
OS 56.25160708 -38.32667468
OS 56.26455092 -38.33222204
OS 56.27841932 -38.33869396
OS 56.2904386 -38.34609044
OS 56.29228772 -38.347015
OS 56.29598596 -38.34978868
OS 56.30153332 -38.35533604
OS 56.3089298 -38.36180796
OS 56.31725084 -38.370129
OS 56.32557188 -38.38122372
OS 56.33481748 -38.393243
OS 56.34221396 -38.4071114
OS 56.34313852 -38.40896052
OS 56.34498764 -38.41358332
OS 56.34868588 -38.42190436
OS 56.35238412 -38.43299908
OS 56.3551578 -38.44594292
OS 56.35885604 -38.46073588
OS 56.36070516 -38.47737796
OS 56.36162972 -38.4949446
OS 56.36162972 -38.49586916
OS 56.36162972 -38.49864284
OS 56.36162972 -38.50234108
OS 56.36070516 -38.508813
OS 56.3597806 -38.51528492
OS 56.35885604 -38.52360596
OS 56.35700692 -38.53285156
OS 56.3551578 -38.54302172
OS 56.34868588 -38.5642866
OS 56.34498764 -38.57538132
OS 56.33944028 -38.5874006
OS 56.33296836 -38.59941988
OS 56.32649644 -38.6105146
OS 56.3181754 -38.62160932
OS 56.3089298 -38.63270404
OS 56.30800524 -38.6336286
OS 56.30615612 -38.63547772
OS 56.30338244 -38.6382514
OS 56.29875964 -38.64102508
OS 56.29321228 -38.64564788
OS 56.2858158 -38.65027068
OS 56.2765702 -38.65581804
OS 56.26640004 -38.66044084
OS 56.25438076 -38.6659882
OS 56.24051236 -38.67153556
OS 56.2257194 -38.67615836
OS 56.20815276 -38.6798566
OS 56.18966156 -38.68355484
OS 56.16932124 -38.68632852
OS 56.14620724 -38.68817764
OS 56.12216868 -38.6891022
OS 55.95852156 -38.6891022
OS 55.95852156 -38.94890356
OS 55.87346204 -38.94890356
OS 55.87346204 -38.30910804
OS 56.13603708 -38.30910804
OS 56.14990548 -38.3100326
OE
OB 57.07723916 -38.94890356 I
OS 56.99587788 -38.94890356
OS 56.99587788 -38.41358332
OS 56.80911676 -38.94890356
OS 56.73330284 -38.94890356
OS 56.54839084 -38.40433772
OS 56.54839084 -38.94890356
OS 56.46702956 -38.94890356
OS 56.46702956 -38.30910804
OS 56.59369428 -38.30910804
OS 56.74532212 -38.763067
OS 56.74532212 -38.76399156
OS 56.74624668 -38.76584068
OS 56.74717124 -38.76861436
OS 56.74902036 -38.77323716
OS 56.7527186 -38.78433188
OS 56.7573414 -38.79820028
OS 56.7619642 -38.8139178
OS 56.76751156 -38.82963532
OS 56.77213436 -38.84442828
OS 56.7758326 -38.85737212
OS 56.77675716 -38.855523
OS 56.77768172 -38.8509002
OS 56.7804554 -38.84257916
OS 56.78415364 -38.83148444
OS 56.78877644 -38.81669148
OS 56.79524836 -38.79912484
OS 56.80172028 -38.77878452
OS 56.81004132 -38.75474596
OS 56.96351828 -38.30910804
OS 57.07723916 -38.30910804
OS 57.07723916 -38.94890356
OE
OB 55.3150278 -38.30725892 I
OS 55.32704708 -38.30910804
OS 55.34184004 -38.31188172
OS 55.35848212 -38.31650452
OS 55.3751242 -38.32205188
OS 55.39176628 -38.32944836
OS 55.39269084 -38.32944836
OS 55.3936154 -38.33037292
OS 55.39916276 -38.3331466
OS 55.4074838 -38.33869396
OS 55.4167294 -38.34516588
OS 55.42782412 -38.35441148
OS 55.43891884 -38.36458164
OS 55.45001356 -38.37660092
OS 55.45925916 -38.39046932
OS 55.46018372 -38.39231844
OS 55.4629574 -38.39694124
OS 55.46665564 -38.40526228
OS 55.47127844 -38.41543244
OS 55.47590124 -38.42745172
OS 55.47959948 -38.44132012
OS 55.48237316 -38.45703764
OS 55.48329772 -38.47275516
OS 55.48329772 -38.47460428
OS 55.48329772 -38.48015164
OS 55.48237316 -38.48754812
OS 55.48052404 -38.49771828
OS 55.47775036 -38.50973756
OS 55.47312756 -38.5226814
OS 55.4675802 -38.53562524
OS 55.46018372 -38.54856908
OS 55.45925916 -38.5504182
OS 55.45648548 -38.55411644
OS 55.45093812 -38.56058836
OS 55.44354164 -38.56798484
OS 55.43429604 -38.57630588
OS 55.42320132 -38.58555148
OS 55.41025748 -38.59387252
OS 55.39453996 -38.60219356
OS 55.39546452 -38.60219356
OS 55.39731364 -38.60311812
OS 55.40008732 -38.60404268
OS 55.40378556 -38.60496724
OS 55.41395572 -38.60866548
OS 55.42689956 -38.61421284
OS 55.44169252 -38.62160932
OS 55.45648548 -38.63085492
OS 55.47035388 -38.6428742
OS 55.48329772 -38.6567426
OS 55.48422228 -38.65859172
OS 55.48792052 -38.66413908
OS 55.49346788 -38.67338468
OS 55.49901524 -38.68540396
OS 55.5045626 -38.70019692
OS 55.51010996 -38.71776356
OS 55.5138082 -38.73810388
OS 55.51473276 -38.76029332
OS 55.51473276 -38.76121788
OS 55.51473276 -38.76399156
OS 55.51473276 -38.76861436
OS 55.5138082 -38.77416172
OS 55.51288364 -38.7815582
OS 55.51103452 -38.78987924
OS 55.5091854 -38.79912484
OS 55.50733628 -38.809295
OS 55.4999398 -38.83148444
OS 55.49439244 -38.84350372
OS 55.48884508 -38.85459844
OS 55.4814486 -38.86661772
OS 55.47312756 -38.878637
OS 55.46388196 -38.89065628
OS 55.45278724 -38.901751
OS 55.45186268 -38.90267556
OS 55.45001356 -38.90452468
OS 55.44631532 -38.90729836
OS 55.44169252 -38.9109966
OS 55.43614516 -38.9156194
OS 55.42874868 -38.9202422
OS 55.42042764 -38.92578956
OS 55.41025748 -38.93041236
OS 55.40008732 -38.93595972
OS 55.38806804 -38.94150708
OS 55.37604876 -38.94612988
OS 55.36218036 -38.95075268
OS 55.3473874 -38.95445092
OS 55.33166988 -38.9572246
OS 55.31595236 -38.95907372
OS 55.29838572 -38.95999828
OS 55.29006468 -38.95999828
OS 55.28451732 -38.95907372
OS 55.27712084 -38.95814916
OS 55.2687998 -38.9572246
OS 55.2595542 -38.95537548
OS 55.24938404 -38.95352636
OS 55.2271946 -38.947979
OS 55.2040806 -38.9387334
OS 55.19206132 -38.93318604
OS 55.1809666 -38.92671412
OS 55.16987188 -38.91839308
OS 55.15877716 -38.91007204
OS 55.1578526 -38.90914748
OS 55.15600348 -38.90729836
OS 55.1532298 -38.90452468
OS 55.15045612 -38.90082644
OS 55.14583332 -38.89620364
OS 55.14121052 -38.88973172
OS 55.13566316 -38.8832598
OS 55.1301158 -38.87493876
OS 55.12456844 -38.86569316
OS 55.11902108 -38.85644756
OS 55.10885092 -38.83425812
OS 55.10052988 -38.80837044
OS 55.0977562 -38.79450204
OS 55.09590708 -38.77970908
OS 55.17449468 -38.76953892
OS 55.17449468 -38.77046348
OS 55.17541924 -38.7723126
OS 55.1763438 -38.77601084
OS 55.17726836 -38.78063364
OS 55.17819292 -38.786181
OS 55.18004204 -38.79265292
OS 55.18466484 -38.80652132
OS 55.19113676 -38.8231634
OS 55.1994578 -38.83888092
OS 55.2087034 -38.85367388
OS 55.21979812 -38.86661772
OS 55.22164724 -38.86754228
OS 55.22534548 -38.87124052
OS 55.23274196 -38.87586332
OS 55.24198756 -38.88048612
OS 55.25308228 -38.88603348
OS 55.26695068 -38.89065628
OS 55.2826682 -38.89435452
OS 55.29931028 -38.89527908
OS 55.30485764 -38.89527908
OS 55.30855588 -38.89435452
OS 55.31872604 -38.89342996
OS 55.33166988 -38.89065628
OS 55.34646284 -38.88603348
OS 55.36218036 -38.87956156
OS 55.37789788 -38.87031596
OS 55.39269084 -38.85737212
OS 55.39453996 -38.855523
OS 55.39916276 -38.84997564
OS 55.40471012 -38.8416546
OS 55.4121066 -38.83055988
OS 55.41950308 -38.81669148
OS 55.42505044 -38.80097396
OS 55.42967324 -38.78248276
OS 55.43152236 -38.76214244
OS 55.43152236 -38.76121788
OS 55.43152236 -38.75936876
OS 55.43152236 -38.75659508
OS 55.4305978 -38.75289684
OS 55.42967324 -38.74272668
OS 55.42689956 -38.7307074
OS 55.42320132 -38.71591444
OS 55.4167294 -38.70112148
OS 55.4074838 -38.68632852
OS 55.39546452 -38.67246012
OS 55.3936154 -38.670611
OS 55.3889926 -38.66691276
OS 55.38159612 -38.6613654
OS 55.37142596 -38.65489348
OS 55.35848212 -38.64842156
OS 55.3427646 -38.6428742
OS 55.32519796 -38.63917596
OS 55.3057822 -38.63732684
OS 55.29746116 -38.63732684
OS 55.29098924 -38.6382514
OS 55.2826682 -38.63917596
OS 55.2734226 -38.64102508
OS 55.26232788 -38.6428742
OS 55.2503086 -38.64564788
OS 55.2595542 -38.57630588
OS 55.264177 -38.57630588
OS 55.26787524 -38.57723044
OS 55.27989452 -38.57723044
OS 55.29006468 -38.57538132
OS 55.30208396 -38.5735322
OS 55.31595236 -38.57075852
OS 55.33166988 -38.56613572
OS 55.34646284 -38.5596638
OS 55.36218036 -38.55134276
OS 55.36310492 -38.55134276
OS 55.36402948 -38.5504182
OS 55.36865228 -38.54671996
OS 55.3751242 -38.54024804
OS 55.38252068 -38.531927
OS 55.38991716 -38.51990772
OS 55.39638908 -38.50603932
OS 55.40101188 -38.4903218
OS 55.402861 -38.4810762
OS 55.402861 -38.47090604
OS 55.402861 -38.46998148
OS 55.402861 -38.46905692
OS 55.402861 -38.46350956
OS 55.40101188 -38.45611308
OS 55.39916276 -38.44594292
OS 55.39546452 -38.4348482
OS 55.39084172 -38.42282892
OS 55.38344524 -38.41080964
OS 55.37327508 -38.39971492
OS 55.37235052 -38.39879036
OS 55.36772772 -38.39509212
OS 55.3612558 -38.39046932
OS 55.35293476 -38.38492196
OS 55.34184004 -38.38029916
OS 55.3288962 -38.37567636
OS 55.31410324 -38.37197812
OS 55.29746116 -38.37105356
OS 55.29006468 -38.37105356
OS 55.28174364 -38.37290268
OS 55.27064892 -38.3747518
OS 55.25862964 -38.37845004
OS 55.24661036 -38.38307284
OS 55.23366652 -38.39046932
OS 55.22164724 -38.39971492
OS 55.22072268 -38.40063948
OS 55.21702444 -38.40526228
OS 55.21147708 -38.4117342
OS 55.20500516 -38.4209798
OS 55.19853324 -38.43299908
OS 55.19206132 -38.44779204
OS 55.18651396 -38.46535868
OS 55.18281572 -38.485699
OS 55.10422812 -38.4718306
OS 55.10422812 -38.47090604
OS 55.10515268 -38.46813236
OS 55.10607724 -38.46443412
OS 55.1070018 -38.45888676
OS 55.10885092 -38.45241484
OS 55.1116246 -38.44501836
OS 55.11717196 -38.42745172
OS 55.12641756 -38.4071114
OS 55.13751228 -38.38677108
OS 55.15138068 -38.36735532
OS 55.16894732 -38.34978868
OS 55.16987188 -38.34886412
OS 55.171721 -38.34793956
OS 55.17449468 -38.34609044
OS 55.17819292 -38.34331676
OS 55.18281572 -38.33961852
OS 55.18928764 -38.33592028
OS 55.19575956 -38.33222204
OS 55.2040806 -38.32759924
OS 55.2225718 -38.32020276
OS 55.24383668 -38.31280628
OS 55.2687998 -38.30818348
OS 55.28174364 -38.30633436
OS 55.30485764 -38.30633436
OS 55.3150278 -38.30725892
OE
OB 54.48199924 -38.94890356 I
OS 54.39231692 -38.94890356
OS 54.39231692 -38.85922124
OS 54.48199924 -38.85922124
OS 54.48199924 -38.94890356
OE
OB 54.9914318 -38.39231844 I
OS 54.73532868 -38.39231844
OS 54.70111996 -38.56521116
OS 54.70204452 -38.5642866
OS 54.70389364 -38.56336204
OS 54.70666732 -38.56151292
OS 54.71129012 -38.55873924
OS 54.71683748 -38.55596556
OS 54.7233094 -38.55226732
OS 54.73810236 -38.54487084
OS 54.75659356 -38.53747436
OS 54.77693388 -38.53100244
OS 54.79912332 -38.52637964
OS 54.81021804 -38.52453052
OS 54.83055836 -38.52453052
OS 54.83610572 -38.52545508
OS 54.8435022 -38.52637964
OS 54.85182324 -38.5273042
OS 54.86106884 -38.52915332
OS 54.871239 -38.531927
OS 54.89342844 -38.53839892
OS 54.90544772 -38.54302172
OS 54.917467 -38.54949364
OS 54.92948628 -38.55596556
OS 54.94150556 -38.56336204
OS 54.95260028 -38.57260764
OS 54.963695 -38.5827778
OS 54.96461956 -38.58370236
OS 54.96646868 -38.58555148
OS 54.96924236 -38.58832516
OS 54.9729406 -38.59294796
OS 54.9775634 -38.59941988
OS 54.9821862 -38.6058918
OS 54.98773356 -38.61421284
OS 54.99328092 -38.62345844
OS 54.99790372 -38.6336286
OS 55.00345108 -38.64472332
OS 55.00807388 -38.65766716
OS 55.01269668 -38.670611
OS 55.01639492 -38.6844794
OS 55.0191686 -38.70019692
OS 55.02101772 -38.71591444
OS 55.02194228 -38.73255652
OS 55.02194228 -38.73348108
OS 55.02194228 -38.73625476
OS 55.02194228 -38.74087756
OS 55.02101772 -38.74734948
OS 55.02009316 -38.75474596
OS 55.0191686 -38.763067
OS 55.01731948 -38.77323716
OS 55.01547036 -38.78340732
OS 55.009923 -38.80744588
OS 55.0006774 -38.832409
OS 54.99513004 -38.84535284
OS 54.98773356 -38.85737212
OS 54.98033708 -38.87031596
OS 54.97109148 -38.88233524
OS 54.97016692 -38.8832598
OS 54.9683178 -38.88603348
OS 54.96461956 -38.88973172
OS 54.95999676 -38.89435452
OS 54.95352484 -38.89990188
OS 54.94612836 -38.90729836
OS 54.93688276 -38.91377028
OS 54.9267126 -38.92116676
OS 54.91561788 -38.92856324
OS 54.90267404 -38.93503516
OS 54.88880564 -38.94150708
OS 54.87401268 -38.947979
OS 54.85829516 -38.9526018
OS 54.84072852 -38.95630004
OS 54.82223732 -38.95907372
OS 54.80282156 -38.95999828
OS 54.79450052 -38.95999828
OS 54.7880286 -38.95907372
OS 54.78063212 -38.95814916
OS 54.77231108 -38.9572246
OS 54.76214092 -38.95630004
OS 54.75197076 -38.95352636
OS 54.72885676 -38.947979
OS 54.70574276 -38.93965796
OS 54.69372348 -38.9341106
OS 54.6817042 -38.92763868
OS 54.67060948 -38.9202422
OS 54.65951476 -38.91192116
OS 54.6585902 -38.9109966
OS 54.65674108 -38.91007204
OS 54.65489196 -38.9063738
OS 54.65119372 -38.90267556
OS 54.64657092 -38.89805276
OS 54.64194812 -38.8925054
OS 54.63640076 -38.88510892
OS 54.63177796 -38.87678788
OS 54.6262306 -38.86846684
OS 54.62068324 -38.85829668
OS 54.61051308 -38.83610724
OS 54.60219204 -38.81021956
OS 54.59941836 -38.79635116
OS 54.59756924 -38.7815582
OS 54.67985508 -38.77508628
OS 54.67985508 -38.77601084
OS 54.67985508 -38.77785996
OS 54.68077964 -38.78063364
OS 54.6817042 -38.78525644
OS 54.68447788 -38.7954266
OS 54.68817612 -38.809295
OS 54.69372348 -38.8231634
OS 54.70111996 -38.83888092
OS 54.71036556 -38.85274932
OS 54.72146028 -38.86569316
OS 54.7233094 -38.86661772
OS 54.72700764 -38.87031596
OS 54.73440412 -38.87493876
OS 54.74457428 -38.88048612
OS 54.755669 -38.88603348
OS 54.7695374 -38.89065628
OS 54.78525492 -38.89435452
OS 54.80282156 -38.89527908
OS 54.80836892 -38.89527908
OS 54.81206716 -38.89435452
OS 54.82316188 -38.89342996
OS 54.83610572 -38.88973172
OS 54.85182324 -38.88510892
OS 54.86754076 -38.87771244
OS 54.88418284 -38.86661772
OS 54.89157932 -38.8601458
OS 54.8989758 -38.85274932
OS 54.89990036 -38.85182476
OS 54.90082492 -38.8509002
OS 54.90267404 -38.84812652
OS 54.90544772 -38.84535284
OS 54.91191964 -38.83518268
OS 54.91931612 -38.82223884
OS 54.92578804 -38.80652132
OS 54.93225996 -38.78710556
OS 54.93688276 -38.76399156
OS 54.93873188 -38.75197228
OS 54.93873188 -38.73902844
OS 54.93873188 -38.73810388
OS 54.93873188 -38.73625476
OS 54.93873188 -38.73255652
OS 54.93780732 -38.72793372
OS 54.93780732 -38.72238636
OS 54.93688276 -38.71591444
OS 54.93410908 -38.70112148
OS 54.92948628 -38.68355484
OS 54.92301436 -38.6659882
OS 54.91376876 -38.64934612
OS 54.90082492 -38.6336286
OS 54.90082492 -38.63270404
OS 54.8989758 -38.63177948
OS 54.894353 -38.62715668
OS 54.88603196 -38.62068476
OS 54.87493724 -38.61328828
OS 54.86014428 -38.60681636
OS 54.8435022 -38.60034444
OS 54.82408644 -38.59572164
OS 54.81299172 -38.59387252
OS 54.79542508 -38.59387252
OS 54.7880286 -38.59479708
OS 54.778783 -38.59572164
OS 54.76768828 -38.59849532
OS 54.75659356 -38.601269
OS 54.74457428 -38.6058918
OS 54.732555 -38.61143916
OS 54.73163044 -38.61236372
OS 54.7279322 -38.61421284
OS 54.72238484 -38.61883564
OS 54.71498836 -38.62345844
OS 54.70759188 -38.62993036
OS 54.7001954 -38.6382514
OS 54.69187436 -38.64657244
OS 54.68540244 -38.6567426
OS 54.61143764 -38.64657244
OS 54.67338316 -38.31742908
OS 54.9914318 -38.31742908
OS 54.9914318 -38.39231844
OE
OB 49.95350436 -38.72331092 I
OS 50.040413 -38.72331092
OS 50.040413 -38.7954266
OS 49.95350436 -38.7954266
OS 49.95350436 -38.94890356
OS 49.87491676 -38.94890356
OS 49.87491676 -38.7954266
OS 49.5966242 -38.7954266
OS 49.5966242 -38.72331092
OS 49.88970972 -38.30910804
OS 49.95350436 -38.30910804
OS 49.95350436 -38.72331092
OE
OB 50.1467374 -38.95999828 I
OS 50.08386732 -38.95999828
OS 50.26970388 -38.29801332
OS 50.33257396 -38.29801332
OS 50.1467374 -38.95999828
OE
OB 49.35346492 -38.30725892 I
OS 49.3608614 -38.30818348
OS 49.370107 -38.30910804
OS 49.38027716 -38.31095716
OS 49.39044732 -38.31280628
OS 49.41448588 -38.3192782
OS 49.43852444 -38.3285238
OS 49.45054372 -38.33407116
OS 49.462563 -38.34054308
OS 49.47365772 -38.34886412
OS 49.48382788 -38.35810972
OS 49.48475244 -38.35903428
OS 49.48660156 -38.35995884
OS 49.48845068 -38.36365708
OS 49.49214892 -38.36735532
OS 49.49677172 -38.37197812
OS 49.50139452 -38.37845004
OS 49.50601732 -38.38492196
OS 49.51156468 -38.393243
OS 49.52081028 -38.41080964
OS 49.53005588 -38.43299908
OS 49.53375412 -38.4440938
OS 49.53560324 -38.45703764
OS 49.53745236 -38.46998148
OS 49.53837692 -38.48384988
OS 49.53837692 -38.485699
OS 49.53837692 -38.4903218
OS 49.53745236 -38.49771828
OS 49.5365278 -38.50788844
OS 49.53467868 -38.51898316
OS 49.53098044 -38.531927
OS 49.5272822 -38.5457954
OS 49.52173484 -38.5596638
OS 49.52081028 -38.56151292
OS 49.51896116 -38.56613572
OS 49.51526292 -38.5735322
OS 49.50971556 -38.58370236
OS 49.50231908 -38.59479708
OS 49.49307348 -38.60866548
OS 49.48197876 -38.62253388
OS 49.46903492 -38.6382514
OS 49.4671858 -38.64010052
OS 49.462563 -38.64564788
OS 49.4579402 -38.65027068
OS 49.4533174 -38.65489348
OS 49.44777004 -38.66044084
OS 49.44037356 -38.66783732
OS 49.43297708 -38.6752338
OS 49.42373148 -38.68355484
OS 49.41448588 -38.69280044
OS 49.40339116 -38.7029706
OS 49.39137188 -38.71314076
OS 49.37842804 -38.72516004
OS 49.36363508 -38.73717932
OS 49.34884212 -38.75012316
OS 49.34791756 -38.75104772
OS 49.34606844 -38.75289684
OS 49.3423702 -38.75567052
OS 49.3377474 -38.75936876
OS 49.33220004 -38.76491612
OS 49.32572812 -38.77046348
OS 49.31093516 -38.78248276
OS 49.29521764 -38.79635116
OS 49.28042468 -38.81021956
OS 49.26748084 -38.82223884
OS 49.26193348 -38.82686164
OS 49.25731068 -38.83148444
OS 49.25638612 -38.832409
OS 49.25361244 -38.83518268
OS 49.2499142 -38.83888092
OS 49.2452914 -38.84442828
OS 49.2406686 -38.8509002
OS 49.23512124 -38.85737212
OS 49.22402652 -38.87308964
OS 49.53930148 -38.87308964
OS 49.53930148 -38.94890356
OS 49.11492844 -38.94890356
OS 49.11492844 -38.947979
OS 49.11492844 -38.94428076
OS 49.11492844 -38.9387334
OS 49.115853 -38.93133692
OS 49.11677756 -38.92301588
OS 49.11862668 -38.91377028
OS 49.1204758 -38.90452468
OS 49.12417404 -38.89435452
OS 49.12417404 -38.89342996
OS 49.1250986 -38.8925054
OS 49.12694772 -38.88695804
OS 49.13064596 -38.878637
OS 49.13619332 -38.86754228
OS 49.1435898 -38.85459844
OS 49.1528354 -38.83980548
OS 49.16300556 -38.82501252
OS 49.1759494 -38.809295
OS 49.1759494 -38.80837044
OS 49.17779852 -38.80744588
OS 49.18242132 -38.80189852
OS 49.19074236 -38.79357748
OS 49.20276164 -38.7815582
OS 49.21663004 -38.7676898
OS 49.23419668 -38.75104772
OS 49.25546156 -38.73255652
OS 49.27857556 -38.71314076
OS 49.27950012 -38.7122162
OS 49.28319836 -38.70944252
OS 49.28874572 -38.70481972
OS 49.29521764 -38.69927236
OS 49.30353868 -38.69187588
OS 49.31370884 -38.68355484
OS 49.323879 -38.67430924
OS 49.33589828 -38.66413908
OS 49.35901228 -38.64194964
OS 49.38212628 -38.6197602
OS 49.393221 -38.60866548
OS 49.40339116 -38.59757076
OS 49.41263676 -38.5874006
OS 49.42003324 -38.57723044
OS 49.42003324 -38.57630588
OS 49.42188236 -38.57538132
OS 49.42373148 -38.57260764
OS 49.4255806 -38.5689094
OS 49.43205252 -38.55873924
OS 49.439449 -38.54671996
OS 49.44592092 -38.531927
OS 49.45239284 -38.51620948
OS 49.45609108 -38.49864284
OS 49.4579402 -38.48200076
OS 49.4579402 -38.4810762
OS 49.4579402 -38.48015164
OS 49.45701564 -38.47460428
OS 49.45609108 -38.46535868
OS 49.4533174 -38.45518852
OS 49.44961916 -38.44224468
OS 49.44314724 -38.42930084
OS 49.4348262 -38.416357
OS 49.42373148 -38.40341316
OS 49.42188236 -38.40156404
OS 49.41725956 -38.3978658
OS 49.41078764 -38.393243
OS 49.40061748 -38.38677108
OS 49.38767364 -38.38122372
OS 49.37288068 -38.37567636
OS 49.35531404 -38.37197812
OS 49.33589828 -38.37105356
OS 49.33035092 -38.37105356
OS 49.32665268 -38.37197812
OS 49.31555796 -38.37290268
OS 49.30261412 -38.37567636
OS 49.28874572 -38.3793746
OS 49.2730282 -38.38584652
OS 49.25823524 -38.39416756
OS 49.24436684 -38.40526228
OS 49.24251772 -38.4071114
OS 49.23881948 -38.4117342
OS 49.23327212 -38.41913068
OS 49.22772476 -38.4302254
OS 49.22125284 -38.44316924
OS 49.21570548 -38.45981132
OS 49.21200724 -38.47830252
OS 49.21015812 -38.4995674
OS 49.1297214 -38.49124636
OS 49.1297214 -38.4903218
OS 49.13064596 -38.48754812
OS 49.13064596 -38.48292532
OS 49.13157052 -38.4764534
OS 49.13341964 -38.46905692
OS 49.13526876 -38.46073588
OS 49.13804244 -38.45056572
OS 49.14081612 -38.44039556
OS 49.1482126 -38.41820612
OS 49.15930732 -38.39601668
OS 49.16577924 -38.38492196
OS 49.17410028 -38.37382724
OS 49.18242132 -38.36365708
OS 49.19166692 -38.35441148
OS 49.19259148 -38.35348692
OS 49.1944406 -38.35256236
OS 49.19721428 -38.34978868
OS 49.20183708 -38.347015
OS 49.20738444 -38.34331676
OS 49.21385636 -38.33961852
OS 49.22125284 -38.33499572
OS 49.23049844 -38.33037292
OS 49.2406686 -38.32575012
OS 49.25176332 -38.32112732
OS 49.2637826 -38.31742908
OS 49.27672644 -38.31373084
OS 49.29059484 -38.31095716
OS 49.3053878 -38.30818348
OS 49.32110532 -38.30725892
OS 49.3377474 -38.30633436
OS 49.346993 -38.30633436
OS 49.35346492 -38.30725892
OE
OB 48.67576244 -38.94890356 I
OS 48.59717484 -38.94890356
OS 48.59717484 -38.4487166
OS 48.59625028 -38.44964116
OS 48.59162748 -38.4533394
OS 48.58608012 -38.45888676
OS 48.57683452 -38.46535868
OS 48.56666436 -38.47367972
OS 48.55372052 -38.48292532
OS 48.53892756 -38.49309548
OS 48.52228548 -38.50326564
OS 48.52136092 -38.50326564
OS 48.52043636 -38.5041902
OS 48.514889 -38.50788844
OS 48.5056434 -38.51251124
OS 48.49454868 -38.5180586
OS 48.48160484 -38.52453052
OS 48.46773644 -38.53100244
OS 48.45386804 -38.53747436
OS 48.43999964 -38.54302172
OS 48.43999964 -38.4672078
OS 48.4409242 -38.4672078
OS 48.44277332 -38.46535868
OS 48.44647156 -38.46443412
OS 48.45109436 -38.46166044
OS 48.45664172 -38.45888676
OS 48.46311364 -38.45518852
OS 48.47883116 -38.44594292
OS 48.49732236 -38.43577276
OS 48.51581356 -38.42282892
OS 48.53522932 -38.40803596
OS 48.55464508 -38.39231844
OS 48.55556964 -38.39139388
OS 48.5564942 -38.39046932
OS 48.55926788 -38.38769564
OS 48.56296612 -38.38492196
OS 48.57128716 -38.37567636
OS 48.58238188 -38.36458164
OS 48.5934766 -38.3516378
OS 48.60549588 -38.33684484
OS 48.61566604 -38.32205188
OS 48.62491164 -38.30633436
OS 48.67576244 -38.30633436
OS 48.67576244 -38.94890356
OE
OB 48.9032042 -38.95999828 I
OS 48.84033412 -38.95999828
OS 49.02617068 -38.29801332
OS 49.08904076 -38.29801332
OS 48.9032042 -38.95999828
OE
OB 50.59699812 -38.30725892 I
OS 50.6043946 -38.30818348
OS 50.6136402 -38.30910804
OS 50.62381036 -38.31095716
OS 50.63398052 -38.31280628
OS 50.65801908 -38.3192782
OS 50.68205764 -38.3285238
OS 50.69407692 -38.33407116
OS 50.7060962 -38.34054308
OS 50.71719092 -38.34886412
OS 50.72736108 -38.35810972
OS 50.72828564 -38.35903428
OS 50.73013476 -38.35995884
OS 50.73198388 -38.36365708
OS 50.73568212 -38.36735532
OS 50.74030492 -38.37197812
OS 50.74492772 -38.37845004
OS 50.74955052 -38.38492196
OS 50.75509788 -38.393243
OS 50.76434348 -38.41080964
OS 50.77358908 -38.43299908
OS 50.77728732 -38.4440938
OS 50.77913644 -38.45703764
OS 50.78098556 -38.46998148
OS 50.78191012 -38.48384988
OS 50.78191012 -38.485699
OS 50.78191012 -38.4903218
OS 50.78098556 -38.49771828
OS 50.780061 -38.50788844
OS 50.77821188 -38.51898316
OS 50.77451364 -38.531927
OS 50.7708154 -38.5457954
OS 50.76526804 -38.5596638
OS 50.76434348 -38.56151292
OS 50.76249436 -38.56613572
OS 50.75879612 -38.5735322
OS 50.75324876 -38.58370236
OS 50.74585228 -38.59479708
OS 50.73660668 -38.60866548
OS 50.72551196 -38.62253388
OS 50.71256812 -38.6382514
OS 50.710719 -38.64010052
OS 50.7060962 -38.64564788
OS 50.7014734 -38.65027068
OS 50.6968506 -38.65489348
OS 50.69130324 -38.66044084
OS 50.68390676 -38.66783732
OS 50.67651028 -38.6752338
OS 50.66726468 -38.68355484
OS 50.65801908 -38.69280044
OS 50.64692436 -38.7029706
OS 50.63490508 -38.71314076
OS 50.62196124 -38.72516004
OS 50.60716828 -38.73717932
OS 50.59237532 -38.75012316
OS 50.59145076 -38.75104772
OS 50.58960164 -38.75289684
OS 50.5859034 -38.75567052
OS 50.5812806 -38.75936876
OS 50.57573324 -38.76491612
OS 50.56926132 -38.77046348
OS 50.55446836 -38.78248276
OS 50.53875084 -38.79635116
OS 50.52395788 -38.81021956
OS 50.51101404 -38.82223884
OS 50.50546668 -38.82686164
OS 50.50084388 -38.83148444
OS 50.49991932 -38.832409
OS 50.49714564 -38.83518268
OS 50.4934474 -38.83888092
OS 50.4888246 -38.84442828
OS 50.4842018 -38.8509002
OS 50.47865444 -38.85737212
OS 50.46755972 -38.87308964
OS 50.78283468 -38.87308964
OS 50.78283468 -38.94890356
OS 50.35846164 -38.94890356
OS 50.35846164 -38.947979
OS 50.35846164 -38.94428076
OS 50.35846164 -38.9387334
OS 50.3593862 -38.93133692
OS 50.36031076 -38.92301588
OS 50.36215988 -38.91377028
OS 50.364009 -38.90452468
OS 50.36770724 -38.89435452
OS 50.36770724 -38.89342996
OS 50.3686318 -38.8925054
OS 50.37048092 -38.88695804
OS 50.37417916 -38.878637
OS 50.37972652 -38.86754228
OS 50.387123 -38.85459844
OS 50.3963686 -38.83980548
OS 50.40653876 -38.82501252
OS 50.4194826 -38.809295
OS 50.4194826 -38.80837044
OS 50.42133172 -38.80744588
OS 50.42595452 -38.80189852
OS 50.43427556 -38.79357748
OS 50.44629484 -38.7815582
OS 50.46016324 -38.7676898
OS 50.47772988 -38.75104772
OS 50.49899476 -38.73255652
OS 50.52210876 -38.71314076
OS 50.52303332 -38.7122162
OS 50.52673156 -38.70944252
OS 50.53227892 -38.70481972
OS 50.53875084 -38.69927236
OS 50.54707188 -38.69187588
OS 50.55724204 -38.68355484
OS 50.5674122 -38.67430924
OS 50.57943148 -38.66413908
OS 50.60254548 -38.64194964
OS 50.62565948 -38.6197602
OS 50.6367542 -38.60866548
OS 50.64692436 -38.59757076
OS 50.65616996 -38.5874006
OS 50.66356644 -38.57723044
OS 50.66356644 -38.57630588
OS 50.66541556 -38.57538132
OS 50.66726468 -38.57260764
OS 50.6691138 -38.5689094
OS 50.67558572 -38.55873924
OS 50.6829822 -38.54671996
OS 50.68945412 -38.531927
OS 50.69592604 -38.51620948
OS 50.69962428 -38.49864284
OS 50.7014734 -38.48200076
OS 50.7014734 -38.4810762
OS 50.7014734 -38.48015164
OS 50.70054884 -38.47460428
OS 50.69962428 -38.46535868
OS 50.6968506 -38.45518852
OS 50.69315236 -38.44224468
OS 50.68668044 -38.42930084
OS 50.6783594 -38.416357
OS 50.66726468 -38.40341316
OS 50.66541556 -38.40156404
OS 50.66079276 -38.3978658
OS 50.65432084 -38.393243
OS 50.64415068 -38.38677108
OS 50.63120684 -38.38122372
OS 50.61641388 -38.37567636
OS 50.59884724 -38.37197812
OS 50.57943148 -38.37105356
OS 50.57388412 -38.37105356
OS 50.57018588 -38.37197812
OS 50.55909116 -38.37290268
OS 50.54614732 -38.37567636
OS 50.53227892 -38.3793746
OS 50.5165614 -38.38584652
OS 50.50176844 -38.39416756
OS 50.48790004 -38.40526228
OS 50.48605092 -38.4071114
OS 50.48235268 -38.4117342
OS 50.47680532 -38.41913068
OS 50.47125796 -38.4302254
OS 50.46478604 -38.44316924
OS 50.45923868 -38.45981132
OS 50.45554044 -38.47830252
OS 50.45369132 -38.4995674
OS 50.3732546 -38.49124636
OS 50.3732546 -38.4903218
OS 50.37417916 -38.48754812
OS 50.37417916 -38.48292532
OS 50.37510372 -38.4764534
OS 50.37695284 -38.46905692
OS 50.37880196 -38.46073588
OS 50.38157564 -38.45056572
OS 50.38434932 -38.44039556
OS 50.3917458 -38.41820612
OS 50.40284052 -38.39601668
OS 50.40931244 -38.38492196
OS 50.41763348 -38.37382724
OS 50.42595452 -38.36365708
OS 50.43520012 -38.35441148
OS 50.43612468 -38.35348692
OS 50.4379738 -38.35256236
OS 50.44074748 -38.34978868
OS 50.44537028 -38.347015
OS 50.45091764 -38.34331676
OS 50.45738956 -38.33961852
OS 50.46478604 -38.33499572
OS 50.47403164 -38.33037292
OS 50.4842018 -38.32575012
OS 50.49529652 -38.32112732
OS 50.5073158 -38.31742908
OS 50.52025964 -38.31373084
OS 50.53412804 -38.31095716
OS 50.548921 -38.30818348
OS 50.56463852 -38.30725892
OS 50.5812806 -38.30633436
OS 50.5905262 -38.30633436
OS 50.59699812 -38.30725892
OE
OB 51.0944114 -38.30725892 I
OS 51.10643068 -38.30910804
OS 51.12029908 -38.31188172
OS 51.13509204 -38.31557996
OS 51.15080956 -38.32020276
OS 51.16560252 -38.32759924
OS 51.16652708 -38.32759924
OS 51.16745164 -38.3285238
OS 51.17207444 -38.33129748
OS 51.17947092 -38.33592028
OS 51.18871652 -38.3423922
OS 51.19888668 -38.3516378
OS 51.2099814 -38.36180796
OS 51.22015156 -38.37382724
OS 51.23032172 -38.38769564
OS 51.23124628 -38.38954476
OS 51.23494452 -38.39416756
OS 51.23864276 -38.4024886
OS 51.24511468 -38.41450788
OS 51.25066204 -38.42837628
OS 51.25805852 -38.4440938
OS 51.26453044 -38.462585
OS 51.2700778 -38.48292532
OS 51.2700778 -38.48384988
OS 51.27100236 -38.485699
OS 51.27192692 -38.48847268
OS 51.27285148 -38.49309548
OS 51.27377604 -38.49864284
OS 51.2747006 -38.50511476
OS 51.27654972 -38.5134358
OS 51.27747428 -38.5226814
OS 51.2793234 -38.53285156
OS 51.28024796 -38.54394628
OS 51.28117252 -38.55689012
OS 51.28302164 -38.56983396
OS 51.2839462 -38.58462692
OS 51.2839462 -38.59941988
OS 51.28487076 -38.61606196
OS 51.28487076 -38.6336286
OS 51.28487076 -38.63455316
OS 51.28487076 -38.6382514
OS 51.28487076 -38.64472332
OS 51.28487076 -38.6521198
OS 51.2839462 -38.66228996
OS 51.2839462 -38.67338468
OS 51.28302164 -38.68540396
OS 51.28209708 -38.6983478
OS 51.2793234 -38.72793372
OS 51.2747006 -38.7584442
OS 51.26915324 -38.78803012
OS 51.265455 -38.80189852
OS 51.2608322 -38.81576692
OS 51.2608322 -38.81669148
OS 51.25990764 -38.8185406
OS 51.25805852 -38.82223884
OS 51.2562094 -38.82686164
OS 51.25436028 -38.83333356
OS 51.25066204 -38.83980548
OS 51.24326556 -38.855523
OS 51.23401996 -38.87216508
OS 51.22200068 -38.89065628
OS 51.20813228 -38.90729836
OS 51.1914902 -38.92301588
OS 51.19056564 -38.92301588
OS 51.18964108 -38.924865
OS 51.1868674 -38.92671412
OS 51.18316916 -38.92856324
OS 51.17854636 -38.93133692
OS 51.17392356 -38.93503516
OS 51.16005516 -38.94150708
OS 51.14341308 -38.947979
OS 51.12399732 -38.95445092
OS 51.10088332 -38.95814916
OS 51.0759202 -38.95999828
OS 51.0666746 -38.95999828
OS 51.06020268 -38.95907372
OS 51.0528062 -38.95814916
OS 51.0435606 -38.95630004
OS 51.03339044 -38.95445092
OS 51.02229572 -38.95167724
OS 51.011201 -38.947979
OS 50.99918172 -38.94428076
OS 50.98716244 -38.9387334
OS 50.97514316 -38.93226148
OS 50.96312388 -38.924865
OS 50.9511046 -38.9156194
OS 50.94000988 -38.90544924
OS 50.92983972 -38.89435452
OS 50.92891516 -38.89342996
OS 50.92706604 -38.89065628
OS 50.92429236 -38.88603348
OS 50.91966956 -38.878637
OS 50.91504676 -38.87031596
OS 50.91042396 -38.85922124
OS 50.90395204 -38.8462774
OS 50.89840468 -38.83148444
OS 50.89285732 -38.81484236
OS 50.88730996 -38.7954266
OS 50.8817626 -38.77416172
OS 50.8771398 -38.75012316
OS 50.872517 -38.72423548
OS 50.86974332 -38.69649868
OS 50.8678942 -38.6659882
OS 50.86696964 -38.6336286
OS 50.86696964 -38.63270404
OS 50.86696964 -38.6290058
OS 50.86696964 -38.62253388
OS 50.86696964 -38.6151374
OS 50.8678942 -38.60496724
OS 50.8678942 -38.59387252
OS 50.86881876 -38.58185324
OS 50.86974332 -38.56798484
OS 50.872517 -38.53932348
OS 50.8771398 -38.508813
OS 50.88268716 -38.47830252
OS 50.8863854 -38.46443412
OS 50.89008364 -38.45056572
OS 50.89008364 -38.44964116
OS 50.8910082 -38.44779204
OS 50.89285732 -38.4440938
OS 50.89470644 -38.439471
OS 50.89655556 -38.43299908
OS 50.9002538 -38.42652716
OS 50.90765028 -38.41080964
OS 50.91689588 -38.39416756
OS 50.92891516 -38.37660092
OS 50.94278356 -38.35903428
OS 50.95942564 -38.34424132
OS 50.9603502 -38.34424132
OS 50.96127476 -38.3423922
OS 50.96404844 -38.34054308
OS 50.96774668 -38.33869396
OS 50.97236948 -38.33499572
OS 50.97791684 -38.33222204
OS 50.99178524 -38.32482556
OS 51.00842732 -38.31835364
OS 51.02784308 -38.31188172
OS 51.05095708 -38.30818348
OS 51.0759202 -38.30633436
OS 51.08424124 -38.30633436
OS 51.0944114 -38.30725892
OE
OB 51.59182468 -38.30725892 I
OS 51.59922116 -38.30818348
OS 51.60846676 -38.30910804
OS 51.61863692 -38.31095716
OS 51.62880708 -38.31280628
OS 51.65284564 -38.3192782
OS 51.6768842 -38.3285238
OS 51.68890348 -38.33407116
OS 51.70092276 -38.34054308
OS 51.71201748 -38.34886412
OS 51.72218764 -38.35810972
OS 51.7231122 -38.35903428
OS 51.72496132 -38.35995884
OS 51.72681044 -38.36365708
OS 51.73050868 -38.36735532
OS 51.73513148 -38.37197812
OS 51.73975428 -38.37845004
OS 51.74437708 -38.38492196
OS 51.74992444 -38.393243
OS 51.75917004 -38.41080964
OS 51.76841564 -38.43299908
OS 51.77211388 -38.4440938
OS 51.773963 -38.45703764
OS 51.77581212 -38.46998148
OS 51.77673668 -38.48384988
OS 51.77673668 -38.485699
OS 51.77673668 -38.4903218
OS 51.77581212 -38.49771828
OS 51.77488756 -38.50788844
OS 51.77303844 -38.51898316
OS 51.7693402 -38.531927
OS 51.76564196 -38.5457954
OS 51.7600946 -38.5596638
OS 51.75917004 -38.56151292
OS 51.75732092 -38.56613572
OS 51.75362268 -38.5735322
OS 51.74807532 -38.58370236
OS 51.74067884 -38.59479708
OS 51.73143324 -38.60866548
OS 51.72033852 -38.62253388
OS 51.70739468 -38.6382514
OS 51.70554556 -38.64010052
OS 51.70092276 -38.64564788
OS 51.69629996 -38.65027068
OS 51.69167716 -38.65489348
OS 51.6861298 -38.66044084
OS 51.67873332 -38.66783732
OS 51.67133684 -38.6752338
OS 51.66209124 -38.68355484
OS 51.65284564 -38.69280044
OS 51.64175092 -38.7029706
OS 51.62973164 -38.71314076
OS 51.6167878 -38.72516004
OS 51.60199484 -38.73717932
OS 51.58720188 -38.75012316
OS 51.58627732 -38.75104772
OS 51.5844282 -38.75289684
OS 51.58072996 -38.75567052
OS 51.57610716 -38.75936876
OS 51.5705598 -38.76491612
OS 51.56408788 -38.77046348
OS 51.54929492 -38.78248276
OS 51.5335774 -38.79635116
OS 51.51878444 -38.81021956
OS 51.5058406 -38.82223884
OS 51.50029324 -38.82686164
OS 51.49567044 -38.83148444
OS 51.49474588 -38.832409
OS 51.4919722 -38.83518268
OS 51.48827396 -38.83888092
OS 51.48365116 -38.84442828
OS 51.47902836 -38.8509002
OS 51.473481 -38.85737212
OS 51.46238628 -38.87308964
OS 51.77766124 -38.87308964
OS 51.77766124 -38.94890356
OS 51.3532882 -38.94890356
OS 51.3532882 -38.947979
OS 51.3532882 -38.94428076
OS 51.3532882 -38.9387334
OS 51.35421276 -38.93133692
OS 51.35513732 -38.92301588
OS 51.35698644 -38.91377028
OS 51.35883556 -38.90452468
OS 51.3625338 -38.89435452
OS 51.3625338 -38.89342996
OS 51.36345836 -38.8925054
OS 51.36530748 -38.88695804
OS 51.36900572 -38.878637
OS 51.37455308 -38.86754228
OS 51.38194956 -38.85459844
OS 51.39119516 -38.83980548
OS 51.40136532 -38.82501252
OS 51.41430916 -38.809295
OS 51.41430916 -38.80837044
OS 51.41615828 -38.80744588
OS 51.42078108 -38.80189852
OS 51.42910212 -38.79357748
OS 51.4411214 -38.7815582
OS 51.4549898 -38.7676898
OS 51.47255644 -38.75104772
OS 51.49382132 -38.73255652
OS 51.51693532 -38.71314076
OS 51.51785988 -38.7122162
OS 51.52155812 -38.70944252
OS 51.52710548 -38.70481972
OS 51.5335774 -38.69927236
OS 51.54189844 -38.69187588
OS 51.5520686 -38.68355484
OS 51.56223876 -38.67430924
OS 51.57425804 -38.66413908
OS 51.59737204 -38.64194964
OS 51.62048604 -38.6197602
OS 51.63158076 -38.60866548
OS 51.64175092 -38.59757076
OS 51.65099652 -38.5874006
OS 51.658393 -38.57723044
OS 51.658393 -38.57630588
OS 51.66024212 -38.57538132
OS 51.66209124 -38.57260764
OS 51.66394036 -38.5689094
OS 51.67041228 -38.55873924
OS 51.67780876 -38.54671996
OS 51.68428068 -38.531927
OS 51.6907526 -38.51620948
OS 51.69445084 -38.49864284
OS 51.69629996 -38.48200076
OS 51.69629996 -38.4810762
OS 51.69629996 -38.48015164
OS 51.6953754 -38.47460428
OS 51.69445084 -38.46535868
OS 51.69167716 -38.45518852
OS 51.68797892 -38.44224468
OS 51.681507 -38.42930084
OS 51.67318596 -38.416357
OS 51.66209124 -38.40341316
OS 51.66024212 -38.40156404
OS 51.65561932 -38.3978658
OS 51.6491474 -38.393243
OS 51.63897724 -38.38677108
OS 51.6260334 -38.38122372
OS 51.61124044 -38.37567636
OS 51.5936738 -38.37197812
OS 51.57425804 -38.37105356
OS 51.56871068 -38.37105356
OS 51.56501244 -38.37197812
OS 51.55391772 -38.37290268
OS 51.54097388 -38.37567636
OS 51.52710548 -38.3793746
OS 51.51138796 -38.38584652
OS 51.496595 -38.39416756
OS 51.4827266 -38.40526228
OS 51.48087748 -38.4071114
OS 51.47717924 -38.4117342
OS 51.47163188 -38.41913068
OS 51.46608452 -38.4302254
OS 51.4596126 -38.44316924
OS 51.45406524 -38.45981132
OS 51.450367 -38.47830252
OS 51.44851788 -38.4995674
OS 51.36808116 -38.49124636
OS 51.36808116 -38.4903218
OS 51.36900572 -38.48754812
OS 51.36900572 -38.48292532
OS 51.36993028 -38.4764534
OS 51.3717794 -38.46905692
OS 51.37362852 -38.46073588
OS 51.3764022 -38.45056572
OS 51.37917588 -38.44039556
OS 51.38657236 -38.41820612
OS 51.39766708 -38.39601668
OS 51.404139 -38.38492196
OS 51.41246004 -38.37382724
OS 51.42078108 -38.36365708
OS 51.43002668 -38.35441148
OS 51.43095124 -38.35348692
OS 51.43280036 -38.35256236
OS 51.43557404 -38.34978868
OS 51.44019684 -38.347015
OS 51.4457442 -38.34331676
OS 51.45221612 -38.33961852
OS 51.4596126 -38.33499572
OS 51.4688582 -38.33037292
OS 51.47902836 -38.32575012
OS 51.49012308 -38.32112732
OS 51.50214236 -38.31742908
OS 51.5150862 -38.31373084
OS 51.5289546 -38.31095716
OS 51.54374756 -38.30818348
OS 51.55946508 -38.30725892
OS 51.57610716 -38.30633436
OS 51.58535276 -38.30633436
OS 51.59182468 -38.30725892
OE
OB 52.08184148 -38.30725892 I
OS 52.09386076 -38.30910804
OS 52.10865372 -38.31188172
OS 52.1252958 -38.31650452
OS 52.14193788 -38.32205188
OS 52.15857996 -38.32944836
OS 52.15950452 -38.32944836
OS 52.16042908 -38.33037292
OS 52.16597644 -38.3331466
OS 52.17429748 -38.33869396
OS 52.18354308 -38.34516588
OS 52.1946378 -38.35441148
OS 52.20573252 -38.36458164
OS 52.21682724 -38.37660092
OS 52.22607284 -38.39046932
OS 52.2269974 -38.39231844
OS 52.22977108 -38.39694124
OS 52.23346932 -38.40526228
OS 52.23809212 -38.41543244
OS 52.24271492 -38.42745172
OS 52.24641316 -38.44132012
OS 52.24918684 -38.45703764
OS 52.2501114 -38.47275516
OS 52.2501114 -38.47460428
OS 52.2501114 -38.48015164
OS 52.24918684 -38.48754812
OS 52.24733772 -38.49771828
OS 52.24456404 -38.50973756
OS 52.23994124 -38.5226814
OS 52.23439388 -38.53562524
OS 52.2269974 -38.54856908
OS 52.22607284 -38.5504182
OS 52.22329916 -38.55411644
OS 52.2177518 -38.56058836
OS 52.21035532 -38.56798484
OS 52.20110972 -38.57630588
OS 52.190015 -38.58555148
OS 52.17707116 -38.59387252
OS 52.16135364 -38.60219356
OS 52.1622782 -38.60219356
OS 52.16412732 -38.60311812
OS 52.166901 -38.60404268
OS 52.17059924 -38.60496724
OS 52.1807694 -38.60866548
OS 52.19371324 -38.61421284
OS 52.2085062 -38.62160932
OS 52.22329916 -38.63085492
OS 52.23716756 -38.6428742
OS 52.2501114 -38.6567426
OS 52.25103596 -38.65859172
OS 52.2547342 -38.66413908
OS 52.26028156 -38.67338468
OS 52.26582892 -38.68540396
OS 52.27137628 -38.70019692
OS 52.27692364 -38.71776356
OS 52.28062188 -38.73810388
OS 52.28154644 -38.76029332
OS 52.28154644 -38.76121788
OS 52.28154644 -38.76399156
OS 52.28154644 -38.76861436
OS 52.28062188 -38.77416172
OS 52.27969732 -38.7815582
OS 52.2778482 -38.78987924
OS 52.27599908 -38.79912484
OS 52.27414996 -38.809295
OS 52.26675348 -38.83148444
OS 52.26120612 -38.84350372
OS 52.25565876 -38.85459844
OS 52.24826228 -38.86661772
OS 52.23994124 -38.878637
OS 52.23069564 -38.89065628
OS 52.21960092 -38.901751
OS 52.21867636 -38.90267556
OS 52.21682724 -38.90452468
OS 52.213129 -38.90729836
OS 52.2085062 -38.9109966
OS 52.20295884 -38.9156194
OS 52.19556236 -38.9202422
OS 52.18724132 -38.92578956
OS 52.17707116 -38.93041236
OS 52.166901 -38.93595972
OS 52.15488172 -38.94150708
OS 52.14286244 -38.94612988
OS 52.12899404 -38.95075268
OS 52.11420108 -38.95445092
OS 52.09848356 -38.9572246
OS 52.08276604 -38.95907372
OS 52.0651994 -38.95999828
OS 52.05687836 -38.95999828
OS 52.051331 -38.95907372
OS 52.04393452 -38.95814916
OS 52.03561348 -38.9572246
OS 52.02636788 -38.95537548
OS 52.01619772 -38.95352636
OS 51.99400828 -38.947979
OS 51.97089428 -38.9387334
OS 51.958875 -38.93318604
OS 51.94778028 -38.92671412
OS 51.93668556 -38.91839308
OS 51.92559084 -38.91007204
OS 51.92466628 -38.90914748
OS 51.92281716 -38.90729836
OS 51.92004348 -38.90452468
OS 51.9172698 -38.90082644
OS 51.912647 -38.89620364
OS 51.9080242 -38.88973172
OS 51.90247684 -38.8832598
OS 51.89692948 -38.87493876
OS 51.89138212 -38.86569316
OS 51.88583476 -38.85644756
OS 51.8756646 -38.83425812
OS 51.86734356 -38.80837044
OS 51.86456988 -38.79450204
OS 51.86272076 -38.77970908
OS 51.94130836 -38.76953892
OS 51.94130836 -38.77046348
OS 51.94223292 -38.7723126
OS 51.94315748 -38.77601084
OS 51.94408204 -38.78063364
OS 51.9450066 -38.786181
OS 51.94685572 -38.79265292
OS 51.95147852 -38.80652132
OS 51.95795044 -38.8231634
OS 51.96627148 -38.83888092
OS 51.97551708 -38.85367388
OS 51.9866118 -38.86661772
OS 51.98846092 -38.86754228
OS 51.99215916 -38.87124052
OS 51.99955564 -38.87586332
OS 52.00880124 -38.88048612
OS 52.01989596 -38.88603348
OS 52.03376436 -38.89065628
OS 52.04948188 -38.89435452
OS 52.06612396 -38.89527908
OS 52.07167132 -38.89527908
OS 52.07536956 -38.89435452
OS 52.08553972 -38.89342996
OS 52.09848356 -38.89065628
OS 52.11327652 -38.88603348
OS 52.12899404 -38.87956156
OS 52.14471156 -38.87031596
OS 52.15950452 -38.85737212
OS 52.16135364 -38.855523
OS 52.16597644 -38.84997564
OS 52.1715238 -38.8416546
OS 52.17892028 -38.83055988
OS 52.18631676 -38.81669148
OS 52.19186412 -38.80097396
OS 52.19648692 -38.78248276
OS 52.19833604 -38.76214244
OS 52.19833604 -38.76121788
OS 52.19833604 -38.75936876
OS 52.19833604 -38.75659508
OS 52.19741148 -38.75289684
OS 52.19648692 -38.74272668
OS 52.19371324 -38.7307074
OS 52.190015 -38.71591444
OS 52.18354308 -38.70112148
OS 52.17429748 -38.68632852
OS 52.1622782 -38.67246012
OS 52.16042908 -38.670611
OS 52.15580628 -38.66691276
OS 52.1484098 -38.6613654
OS 52.13823964 -38.65489348
OS 52.1252958 -38.64842156
OS 52.10957828 -38.6428742
OS 52.09201164 -38.63917596
OS 52.07259588 -38.63732684
OS 52.06427484 -38.63732684
OS 52.05780292 -38.6382514
OS 52.04948188 -38.63917596
OS 52.04023628 -38.64102508
OS 52.02914156 -38.6428742
OS 52.01712228 -38.64564788
OS 52.02636788 -38.57630588
OS 52.03099068 -38.57630588
OS 52.03468892 -38.57723044
OS 52.0467082 -38.57723044
OS 52.05687836 -38.57538132
OS 52.06889764 -38.5735322
OS 52.08276604 -38.57075852
OS 52.09848356 -38.56613572
OS 52.11327652 -38.5596638
OS 52.12899404 -38.55134276
OS 52.1299186 -38.55134276
OS 52.13084316 -38.5504182
OS 52.13546596 -38.54671996
OS 52.14193788 -38.54024804
OS 52.14933436 -38.531927
OS 52.15673084 -38.51990772
OS 52.16320276 -38.50603932
OS 52.16782556 -38.4903218
OS 52.16967468 -38.4810762
OS 52.16967468 -38.47090604
OS 52.16967468 -38.46998148
OS 52.16967468 -38.46905692
OS 52.16967468 -38.46350956
OS 52.16782556 -38.45611308
OS 52.16597644 -38.44594292
OS 52.1622782 -38.4348482
OS 52.1576554 -38.42282892
OS 52.15025892 -38.41080964
OS 52.14008876 -38.39971492
OS 52.1391642 -38.39879036
OS 52.1345414 -38.39509212
OS 52.12806948 -38.39046932
OS 52.11974844 -38.38492196
OS 52.10865372 -38.38029916
OS 52.09570988 -38.37567636
OS 52.08091692 -38.37197812
OS 52.06427484 -38.37105356
OS 52.05687836 -38.37105356
OS 52.04855732 -38.37290268
OS 52.0374626 -38.3747518
OS 52.02544332 -38.37845004
OS 52.01342404 -38.38307284
OS 52.0004802 -38.39046932
OS 51.98846092 -38.39971492
OS 51.98753636 -38.40063948
OS 51.98383812 -38.40526228
OS 51.97829076 -38.4117342
OS 51.97181884 -38.4209798
OS 51.96534692 -38.43299908
OS 51.958875 -38.44779204
OS 51.95332764 -38.46535868
OS 51.9496294 -38.485699
OS 51.8710418 -38.4718306
OS 51.8710418 -38.47090604
OS 51.87196636 -38.46813236
OS 51.87289092 -38.46443412
OS 51.87381548 -38.45888676
OS 51.8756646 -38.45241484
OS 51.87843828 -38.44501836
OS 51.88398564 -38.42745172
OS 51.89323124 -38.4071114
OS 51.90432596 -38.38677108
OS 51.91819436 -38.36735532
OS 51.935761 -38.34978868
OS 51.93668556 -38.34886412
OS 51.93853468 -38.34793956
OS 51.94130836 -38.34609044
OS 51.9450066 -38.34331676
OS 51.9496294 -38.33961852
OS 51.95610132 -38.33592028
OS 51.96257324 -38.33222204
OS 51.97089428 -38.32759924
OS 51.98938548 -38.32020276
OS 52.01065036 -38.31280628
OS 52.03561348 -38.30818348
OS 52.04855732 -38.30633436
OS 52.07167132 -38.30633436
OS 52.08184148 -38.30725892
OE
OB 51.07499564 -38.37105356 H
OS 51.06944828 -38.37105356
OS 51.06575004 -38.37197812
OS 51.05557988 -38.37382724
OS 51.0435606 -38.37660092
OS 51.0296922 -38.38214828
OS 51.01489924 -38.39046932
OS 51.00750276 -38.39601668
OS 51.00010628 -38.40156404
OS 50.99363436 -38.40896052
OS 50.98716244 -38.41728156
OS 50.98716244 -38.41820612
OS 50.98531332 -38.42005524
OS 50.9834642 -38.42375348
OS 50.98069052 -38.42837628
OS 50.97791684 -38.43577276
OS 50.9742186 -38.4440938
OS 50.97144492 -38.45426396
OS 50.96774668 -38.46628324
OS 50.96404844 -38.48015164
OS 50.9603502 -38.49586916
OS 50.95665196 -38.5134358
OS 50.95387828 -38.53285156
OS 50.9511046 -38.555041
OS 50.94925548 -38.57907956
OS 50.94833092 -38.60496724
OS 50.94740636 -38.6336286
OS 50.94740636 -38.63547772
OS 50.94740636 -38.64010052
OS 50.94740636 -38.64842156
OS 50.94833092 -38.65951628
OS 50.94833092 -38.67153556
OS 50.94925548 -38.68632852
OS 50.95018004 -38.70204604
OS 50.95202916 -38.71868812
OS 50.95665196 -38.75474596
OS 50.95942564 -38.7723126
OS 50.96312388 -38.78895468
OS 50.96682212 -38.8046722
OS 50.97236948 -38.81946516
OS 50.97791684 -38.832409
OS 50.98438876 -38.84350372
OS 50.98438876 -38.84442828
OS 50.98623788 -38.84535284
OS 50.99086068 -38.85182476
OS 50.99918172 -38.8601458
OS 51.00935188 -38.8693914
OS 51.02322028 -38.878637
OS 51.0389378 -38.88695804
OS 51.05650444 -38.89342996
OS 51.06575004 -38.89435452
OS 51.0759202 -38.89527908
OS 51.08146756 -38.89527908
OS 51.0851658 -38.89435452
OS 51.0944114 -38.8925054
OS 51.10735524 -38.88880716
OS 51.12122364 -38.88233524
OS 51.13694116 -38.87308964
OS 51.14433764 -38.86754228
OS 51.15173412 -38.8601458
OS 51.1591306 -38.85274932
OS 51.16652708 -38.84350372
OS 51.16652708 -38.84257916
OS 51.1683762 -38.84073004
OS 51.17022532 -38.83795636
OS 51.17207444 -38.83333356
OS 51.17577268 -38.82686164
OS 51.17854636 -38.8185406
OS 51.1822446 -38.809295
OS 51.18594284 -38.79820028
OS 51.18871652 -38.78433188
OS 51.19241476 -38.76953892
OS 51.196113 -38.75197228
OS 51.19888668 -38.73348108
OS 51.2007358 -38.71129164
OS 51.20258492 -38.68817764
OS 51.20443404 -38.66228996
OS 51.20443404 -38.6336286
OS 51.20443404 -38.63270404
OS 51.20443404 -38.63177948
OS 51.20443404 -38.62715668
OS 51.20443404 -38.61883564
OS 51.20350948 -38.60774092
OS 51.20350948 -38.59572164
OS 51.20258492 -38.58092868
OS 51.20166036 -38.56521116
OS 51.19981124 -38.54764452
OS 51.19518844 -38.51251124
OS 51.19241476 -38.4949446
OS 51.18871652 -38.47830252
OS 51.18501828 -38.462585
OS 51.17947092 -38.44779204
OS 51.17392356 -38.4348482
OS 51.16745164 -38.42375348
OS 51.16745164 -38.42282892
OS 51.16560252 -38.42190436
OS 51.1637534 -38.41913068
OS 51.16097972 -38.41543244
OS 51.15265868 -38.4071114
OS 51.14248852 -38.39694124
OS 51.12862012 -38.38769564
OS 51.1129026 -38.3793746
OS 51.10458156 -38.37567636
OS 51.09533596 -38.37290268
OS 51.0851658 -38.37197812
OS 51.07499564 -38.37105356
OE
OB 54.05947532 -38.37105356 H
OS 54.05392796 -38.37105356
OS 54.05022972 -38.37197812
OS 54.04005956 -38.37382724
OS 54.02804028 -38.37660092
OS 54.01417188 -38.38214828
OS 53.99937892 -38.39046932
OS 53.99198244 -38.39601668
OS 53.98458596 -38.40156404
OS 53.97811404 -38.40896052
OS 53.97164212 -38.41728156
OS 53.97164212 -38.41820612
OS 53.969793 -38.42005524
OS 53.96794388 -38.42375348
OS 53.9651702 -38.42837628
OS 53.96239652 -38.43577276
OS 53.95869828 -38.4440938
OS 53.9559246 -38.45426396
OS 53.95222636 -38.46628324
OS 53.94852812 -38.48015164
OS 53.94482988 -38.49586916
OS 53.94113164 -38.5134358
OS 53.93835796 -38.53285156
OS 53.93558428 -38.555041
OS 53.93373516 -38.57907956
OS 53.9328106 -38.60496724
OS 53.93188604 -38.6336286
OS 53.93188604 -38.63547772
OS 53.93188604 -38.64010052
OS 53.93188604 -38.64842156
OS 53.9328106 -38.65951628
OS 53.9328106 -38.67153556
OS 53.93373516 -38.68632852
OS 53.93465972 -38.70204604
OS 53.93650884 -38.71868812
OS 53.94113164 -38.75474596
OS 53.94390532 -38.7723126
OS 53.94760356 -38.78895468
OS 53.9513018 -38.8046722
OS 53.95684916 -38.81946516
OS 53.96239652 -38.832409
OS 53.96886844 -38.84350372
OS 53.96886844 -38.84442828
OS 53.97071756 -38.84535284
OS 53.97534036 -38.85182476
OS 53.9836614 -38.8601458
OS 53.99383156 -38.8693914
OS 54.00769996 -38.878637
OS 54.02341748 -38.88695804
OS 54.04098412 -38.89342996
OS 54.05022972 -38.89435452
OS 54.06039988 -38.89527908
OS 54.06594724 -38.89527908
OS 54.06964548 -38.89435452
OS 54.07889108 -38.8925054
OS 54.09183492 -38.88880716
OS 54.10570332 -38.88233524
OS 54.12142084 -38.87308964
OS 54.12881732 -38.86754228
OS 54.1362138 -38.8601458
OS 54.14361028 -38.85274932
OS 54.15100676 -38.84350372
OS 54.15100676 -38.84257916
OS 54.15285588 -38.84073004
OS 54.154705 -38.83795636
OS 54.15655412 -38.83333356
OS 54.16025236 -38.82686164
OS 54.16302604 -38.8185406
OS 54.16672428 -38.809295
OS 54.17042252 -38.79820028
OS 54.1731962 -38.78433188
OS 54.17689444 -38.76953892
OS 54.18059268 -38.75197228
OS 54.18336636 -38.73348108
OS 54.18521548 -38.71129164
OS 54.1870646 -38.68817764
OS 54.18891372 -38.66228996
OS 54.18891372 -38.6336286
OS 54.18891372 -38.63270404
OS 54.18891372 -38.63177948
OS 54.18891372 -38.62715668
OS 54.18891372 -38.61883564
OS 54.18798916 -38.60774092
OS 54.18798916 -38.59572164
OS 54.1870646 -38.58092868
OS 54.18614004 -38.56521116
OS 54.18429092 -38.54764452
OS 54.17966812 -38.51251124
OS 54.17689444 -38.4949446
OS 54.1731962 -38.47830252
OS 54.16949796 -38.462585
OS 54.1639506 -38.44779204
OS 54.15840324 -38.4348482
OS 54.15193132 -38.42375348
OS 54.15193132 -38.42282892
OS 54.1500822 -38.42190436
OS 54.14823308 -38.41913068
OS 54.1454594 -38.41543244
OS 54.13713836 -38.4071114
OS 54.1269682 -38.39694124
OS 54.1130998 -38.38769564
OS 54.09738228 -38.3793746
OS 54.08906124 -38.37567636
OS 54.07981564 -38.37290268
OS 54.06964548 -38.37197812
OS 54.05947532 -38.37105356
OE
OB 49.87491676 -38.43669732 H
OS 49.67336268 -38.72331092
OS 49.87491676 -38.72331092
OS 49.87491676 -38.43669732
OE
OB 56.14158444 -38.38492196 H
OS 55.95852156 -38.38492196
OS 55.95852156 -38.61328828
OS 56.13048972 -38.61328828
OS 56.13696164 -38.61236372
OS 56.14343356 -38.61236372
OS 56.15083004 -38.61143916
OS 56.16839668 -38.60959004
OS 56.18781244 -38.6058918
OS 56.2072282 -38.60034444
OS 56.22479484 -38.59294796
OS 56.23311588 -38.58832516
OS 56.2395878 -38.5827778
OS 56.24143692 -38.58092868
OS 56.24513516 -38.57723044
OS 56.25068252 -38.56983396
OS 56.25715444 -38.56058836
OS 56.26362636 -38.54856908
OS 56.26917372 -38.53377612
OS 56.27287196 -38.51713404
OS 56.27472108 -38.49771828
OS 56.27472108 -38.49679372
OS 56.27472108 -38.49586916
OS 56.27472108 -38.49124636
OS 56.27379652 -38.48292532
OS 56.2719474 -38.47367972
OS 56.27009828 -38.46350956
OS 56.26640004 -38.45149028
OS 56.26085268 -38.44039556
OS 56.25438076 -38.42930084
OS 56.2534562 -38.42837628
OS 56.25068252 -38.42467804
OS 56.24605972 -38.42005524
OS 56.24051236 -38.41358332
OS 56.23219132 -38.4071114
OS 56.22294572 -38.40156404
OS 56.21277556 -38.39601668
OS 56.20075628 -38.39139388
OS 56.19983172 -38.39139388
OS 56.19613348 -38.39046932
OS 56.19058612 -38.38954476
OS 56.18318964 -38.38769564
OS 56.17209492 -38.38677108
OS 56.15822652 -38.38584652
OS 56.14158444 -38.38492196
OE
SE
P -2.99999908 16.00000102 7 P 0 0 ;0=6,1=1
P -2.99999908 17.99999956 7 P 0 0 ;0=6,1=1
P -2.99999908 20.00000064 7 P 0 0 ;0=6,1=1
P -2.99999908 21.99999918 7 P 0 0 ;0=6,1=1
P -2.99999908 24.00000026 7 P 0 0 ;0=6,1=1
P -2.99999908 25.9999988 7 P 0 0 ;0=6,1=1
P -2.99999908 27.99999988 7 P 0 0 ;0=6,1=1
P -2.99999908 30.00000096 7 P 0 0 ;0=6,1=1
P -2.99999908 31.9999995 7 P 0 0 ;0=6,1=1
P -2.99999908 34.00000058 7 P 0 0 ;0=6,1=1
P -2.99999908 35.99999912 7 P 0 0 ;0=6,1=1
P -2.99999908 38.0000002 7 P 0 0 ;0=6,1=1
P -2.99999908 39.99999874 7 P 0 0 ;0=6,1=1
P 0.50000154 -3.99999962 7 P 0 0 ;0=6,1=1
P 2.50000008 -3.99999962 7 P 0 0 ;0=6,1=1
P 4.50000116 -3.99999962 7 P 0 0 ;0=6,1=1
P 6.4999997 -3.99999962 7 P 0 0 ;0=6,1=1
P 8.50000078 -3.99999962 7 P 0 0 ;0=6,1=1
P 10.49999932 -3.99999962 7 P 0 0 ;0=6,1=1
P 12.5000004 -3.99999962 7 P 0 0 ;0=6,1=1
P 12.74500118 40.26499948 7 P 0 0 ;0=6,1=1
P 12.74500118 41.21500012 7 P 0 0 ;0=6,1=1
P 12.74500118 44.63999962 7 P 0 0 ;0=6,1=1
P 12.75500116 42.16500076 7 P 0 0 ;0=6,1=1
P 12.98999942 18.0150008 7 P 0 0 ;0=6,1=1
P 14.50000148 -3.99999962 7 P 0 0 ;0=6,1=1
P 15.88470534 21.56499878 7 P 0 0 ;0=6,1=1
P 16.30970576 23.03999964 7 P 0 0 ;0=6,1=1
P 16.50000002 -3.99999962 7 P 0 0 ;0=6,1=1
P 17.57500168 13.89000016 7 P 0 0 ;0=6,1=1
P 17.915001 15.69625258 7 P 0 0 ;0=6,1=1
P 18.8149992 15.10000028 7 P 0 0 ;0=6,1=1
P 18.8149992 15.98270108 7 P 0 0 ;0=6,1=1
P 18.8149992 16.85250122 7 P 0 0 ;0=6,1=1
P 19.01500134 7.39000046 7 P 0 0 ;0=6,1=1
P 19.01500134 8.5900006 7 P 0 0 ;0=6,1=1
P 19.01500134 9.7899982 7 P 0 0 ;0=6,1=1
P 19.01500134 11.09000068 7 P 0 0 ;0=6,1=1
P 19.01500134 12.39000062 7 P 0 0 ;0=6,1=1
P 21.11499968 6.76500044 7 P 0 0 ;0=6,1=1
P 21.11499968 7.78999966 7 P 0 0 ;0=6,1=1
P 21.11499968 8.9899998 7 P 0 0 ;0=6,1=1
P 21.11499968 10.28999974 7 P 0 0 ;0=6,1=1
P 21.11499968 11.38590052 7 P 0 0 ;0=6,1=1
P 22.05919388 12.29000082 7 P 0 0 ;0=6,1=1
P 22.45970616 20.01499934 7 P 0 0 ;0=6,1=1
P 23.29999912 38.90000094 7 P 0 0 ;0=6,1=1
P 23.33999904 44.0138312 7 P 0 0 ;0=6,1=1
P 23.4097068 20.04000056 7 P 0 0 ;0=6,1=1
P 24.35970744 20.04000056 7 P 0 0 ;0=6,1=1
P 24.49999926 -3.50000062 7 P 0 0 ;0=6,1=1
P 25.7999992 38.90000094 7 P 0 0 ;0=6,1=1
P 26.50000034 -3.50000062 7 P 0 0 ;0=6,1=1
P 28.50000142 -3.50000062 7 P 0 0 ;0=6,1=1
P 30.49999996 -3.50000062 7 P 0 0 ;0=6,1=1
P 32.50000104 -3.50000062 7 P 0 0 ;0=6,1=1
P 32.80000044 38.90000094 7 P 0 0 ;0=6,1=1
P 35.30000052 44.0000009 7 P 0 0 ;0=6,1=1
P 38.4999992 -3.50000062 7 P 0 0 ;0=6,1=1
P 39.60000208 38.91499964 7 P 0 0 ;0=6,1=1
P 40.50000028 -3.50000062 7 P 0 0 ;0=6,1=1
P 40.67999992 42.76499956 7 P 0 0 ;0=6,1=1
P 42.2249981 38.91499964 7 P 0 0 ;0=6,1=1
P 44.4999999 0.499999 7 P 0 0 ;0=6,1=1
P 44.4999999 2.50000008 7 P 0 0 ;0=6,1=1
P 44.4999999 4.49999862 7 P 0 0 ;0=6,1=1
P 44.4999999 6.4999997 7 P 0 0 ;0=6,1=1
P 44.4999999 8.49999824 7 P 0 0 ;0=6,1=1
P 44.4999999 10.49999932 7 P 0 0 ;0=6,1=1
P 44.4999999 12.49999786 7 P 0 0 ;0=6,1=1
P 44.4999999 14.49999894 7 P 0 0 ;0=6,1=1
P 44.4999999 16.50000002 7 P 0 0 ;0=6,1=1
P 44.4999999 18.49999856 7 P 0 0 ;0=6,1=1
P 44.4999999 20.49999964 7 P 0 0 ;0=6,1=1
P 44.4999999 22.49999818 7 P 0 0 ;0=6,1=1
P 44.4999999 24.49999926 7 P 0 0 ;0=6,1=1
P 44.4999999 26.4999978 7 P 0 0 ;0=6,1=1
P 44.4999999 28.49999888 7 P 0 0 ;0=6,1=1
P 44.4999999 30.49999996 7 P 0 0 ;0=6,1=1
P 44.4999999 32.4999985 7 P 0 0 ;0=6,1=1
P 44.4999999 34.49999958 7 P 0 0 ;0=6,1=1
P 44.4999999 36.49999812 7 P 0 0 ;0=6,1=1
P 44.4999999 38.4999992 7 P 0 0 ;0=6,1=1
P 44.4999999 40.49999774 7 P 0 0 ;0=6,1=1

### steps/pcb/layers/l02-inner_layer/features
UNITS=MM
#Layer_Physical_Order=2
#Layer_Color=36540
#
#Feature symbol names
#
$0 r199.9996
$1 r99.9998
$2 r2090.0009
$3 r1562.00094
$4 r1524
$5 r1799.99894
$6 r599.9988

#
#Feature attribute names
#
@0 .geometry
@1 .pad_usage
@2 .nomenclature
@3 .string
@4 .string_angle

#
#Feature attribute text strings
#
&0 Pad_Simple_X2090.0009Y2090.0009H1090.0004C2106.0004
&1 Pad_Simple_X1562.0009Y1562.0009H961.9996C1977.9996
&2 Pad_Simple_X1524.0000Y1524.0000H762.0000C1778.0000
&3 Pad_Simple_X1799.9989Y1799.9989H1200.0001C2216.0001
&4 VIA_RoundD599.9988H299.9994C1315.9994

#
#Layer features
#
A 7.10000104 39.85210216 7.84394926 38.05605038 9.64000104 39.85210216 0 P 0 N
A 7.10000104 40.79999968 6.70684968 41.74914688 5.75770248 40.79999968 0 P 0 N
A 8.1739994 40.28310206 8.91794762 38.48705028 10.7139994 40.28310206 0 P 0 N
A 8.65605076 16.54605022 9.39999898 18.342102 6.85999898 18.342102 0 P 0 N
A 9.39999898 35.59999992 8.76360198 37.13639766 7.22720424 35.59999992 0 P 0 N
A 9.72105244 12.5310519 10.46500066 14.32710368 7.92500066 14.32710368 0 P 0 N
A 10.46500066 35.77336254 9.64044554 37.76454728 7.6507848 35.77430742 0 P 0 N
A 11.2219994 38.96010496 11.96594762 37.16405318 13.7619994 38.96010496 0 P 0 N
A 14.26999686 39.24563398 14.80955382 37.94543084 16.1063051 39.24560858 0 P 0 N
A 19.31499312 29.81499244 22.27014088 28.58999616 22.27240148 32.77240588 0 P 0 N
A 20.75207178 32.00292812 22.23112902 31.3899931 22.23183514 33.48269656 0 P 0 N
A 27.82772438 27.82227608 25.97569354 28.5899987 25.975691 25.97224422 0 P 0 N
A 30.38394736 30.34604802 27.86362728 31.39000072 27.86362474 27.82573048 0 P 0 N
L -9.5600012 -24.45999934 40.4400004 -24.45999934 1 P 0
L -9.5600012 -35.9599992 -9.5600012 -24.45999934 1 P 0
L -9.5600012 -35.9599992 28.439999 -35.9599992 1 P 0
L -9.5600012 -39.45999982 -9.5600012 -35.9599992 1 P 0
L -9.5600012 -39.45999982 28.439999 -39.45999982 1 P 0
L -9.5600012 -42.96000044 -9.5600012 -39.45999982 1 P 0
L -9.5600012 -42.96000044 28.439999 -42.96000044 1 P 0
L -10.0600002 -23.96000034 62.93999858 -23.96000034 1 P 0
L -10.0600002 -43.45999944 -10.0600002 -23.96000034 1 P 0
L -10.0600002 -43.45999944 62.93999858 -43.45999944 1 P 0
L 4.8300005 7.63999996 9.72105244 12.5310519 0 P 0
L 4.8300005 12.71999996 8.65605076 16.54605022 0 P 0
L 5.1259994 43.3299997 6.70684968 41.74914942 0 P 0
L 7.10000104 39.85210216 7.10000104 40.79999968 0 P 0
L 7.84394926 38.05605038 8.76360198 37.13639766 0 P 0
L 8.1739994 40.28310206 8.1739994 43.34999966 0 P 0
L 8.91794508 38.48705028 9.63984864 37.76514672 0 P 0
L 9.39999898 18.342102 9.39999898 35.59999992 0 P 0
L 9.63984864 37.76514672 9.64044554 37.76454728 0 P 0
L 10.46499812 35.77336254 10.46500066 35.77330158 0 P 0
L 10.46500066 14.32710368 10.46500066 35.77330158 0 P 0
L 11.2219994 38.96010496 11.2219994 43.34999966 0 P 0
L 11.96594762 37.16405318 19.31500074 29.81500006 0 P 0
L 14.26999686 39.24563398 14.2699994 39.24663982 0 P 0
L 14.2699994 39.24663982 14.2699994 43.34999966 0 P 0
L 14.80955128 37.9454283 14.80955382 37.94543084 0 P 0
L 14.80955382 37.94543084 20.75207432 32.00293066 0 P 0
L 22.2311341 31.38999818 27.86362982 31.39000072 0 P 0
L 22.27014088 28.58999616 25.97569608 28.5899987 0 P 0
L 27.82772438 27.82227608 37.8500005 17.79999996 0 P 0
L 28.439999 -35.96000174 45.44000056 -35.9599992 1 P 0
L 28.439999 -39.45999982 28.439999 -35.9599992 1 P 0
L 28.439999 -39.46000236 45.44000056 -39.45999982 1 P 0
L 28.439999 -42.96000044 28.439999 -39.45999982 1 P 0
L 28.439999 -42.96000298 45.44000056 -42.96000044 1 P 0
L 30.3839499 30.34605056 37.8500005 22.87999996 0 P 0
L 40.4400004 -24.45999934 62.43999958 -24.45999934 1 P 0
L 40.4400004 -35.9599992 40.4400004 -24.45999934 1 P 0
L 45.44000056 -35.9599992 62.43999958 -35.9599992 1 P 0
L 45.44000056 -39.45999982 62.43999958 -39.45999982 1 P 0
L 45.44000056 -42.96000044 45.44000056 -35.9599992 1 P 0
L 45.44000056 -42.96000044 62.43999958 -42.96000044 1 P 0
L 62.43999958 -35.9599992 62.43999958 -24.45999934 1 P 0
L 62.43999958 -42.96000044 62.43999958 -35.9599992 1 P 0
L 62.93999858 -43.45999944 62.93999858 -23.96000034 1 P 0
P 0 40.64 2 P 0 0 ;0=0,1=0
P 4.8300005 7.63999996 5 P 0 0 ;0=3,1=0
P 4.8300005 7.63999996 4 P 0 0 ;0=2,1=0
P 4.8300005 12.71999996 5 P 0 0 ;0=3,1=0
P 4.8300005 12.71999996 4 P 0 0 ;0=2,1=0
P 5.1259994 43.3299997 2 P 0 0 ;0=0,1=0
P 8.1739994 43.3299997 2 P 0 0 ;0=0,1=0
P 11.2219994 43.3299997 2 P 0 0 ;0=0,1=0
P 14.2699994 43.3299997 2 P 0 0 ;0=0,1=0
P 37.8500005 12.71999996 5 P 0 0 ;0=3,1=0
P 37.8500005 12.71999996 3 P 0 0 ;0=1,1=0
P 37.8500005 17.79999996 5 P 0 0 ;0=3,1=0
P 37.8500005 17.79999996 3 P 0 0 ;0=1,1=0
P 37.8500005 22.87999996 3 P 0 0 ;0=1,1=0
P 37.8500005 22.87999996 5 P 0 0 ;0=3,1=0
P 40.67999992 20.33999996 2 P 0 0 ;0=0,1=0
S P 0
OB 43.2467766 45.28782662 I
OS 43.5750081 45.19987658
OS 43.8889648 45.06983112
OS 44.18321872 44.89994068
OS 44.45280162 44.69308308
OS 44.693078 44.45280924
OS 44.89994068 44.18322126
OS 45.06983112 43.8889648
OS 45.19986896 43.57502842
OS 45.28782408 43.24677914
OS 45.33217502 42.90990402
OS 45.33217756 42.7399958
OS 45.33217502 -2.06000096
OS 45.33217502 -2.22990918
OS 45.28782662 -2.56677922
OS 45.19987658 -2.89501072
OS 45.06983112 -3.20896742
OS 44.89994068 -3.50322134
OS 44.69308308 -3.77280424
OS 44.45280924 -4.01308062
OS 44.18322126 -4.2199433
OS 43.8889648 -4.38983374
OS 43.57502842 -4.51987158
OS 43.24677914 -4.6078267
OS 42.90989132 -4.6521751
OS 42.7399958 -4.65217764
OS -2.06000096 -4.65218272
OS -2.22990918 -4.65218272
OS -2.56678938 -4.60783178
OS -2.89502088 -4.51988428
OS -3.20895472 -4.38984644
OS -3.50322388 -4.21994838
OS -3.77279916 -4.0130984
OS -4.0130984 -3.77279916
OS -4.21994584 -3.50322642
OS -4.38984136 -3.2089598
OS -4.51988174 -2.89502088
OS -4.60782924 -2.56679192
OS -4.65218018 -2.22991172
OS -4.65217764 -2.06000604
OS -4.65218526 42.73999834
OS -4.65218526 42.90990656
OS -4.60783432 43.24678422
OS -4.51988682 43.57501318
OS -4.38984644 43.88895464
OS -4.21995092 44.18321872
OS -4.01310094 44.452794
OS -3.77280932 44.69308562
OS -3.50323404 44.89993814
OS -3.20894964 45.06984128
OS -2.89502342 45.19987658
OS -2.56679192 45.28782408
OS -2.22992188 45.33217248
OS -2.07798416 45.33216486
OS -2.07795622 45.33216994
OS 42.74000088 45.33217502
OS 42.90990656 45.33217502
OS 43.2467766 45.28782662
OE
OB 14.42216826 44.87499788 H
OS 14.11783054 44.87499788
OS 13.8193399 44.81562538
OS 13.53816952 44.69915876
OS 13.28511948 44.53007858
OS 13.06992052 44.31487962
OS 12.90084034 44.06182958
OS 12.8147318 43.85394836
OS 12.677267 43.85394836
OS 12.59115846 44.06182958
OS 12.42207828 44.31487962
OS 12.20687932 44.53007858
OS 11.95382928 44.69915876
OS 11.6726589 44.81562538
OS 11.37416826 44.87499788
OS 11.06983054 44.87499788
OS 10.7713399 44.81562538
OS 10.49016952 44.69915876
OS 10.23711948 44.53007858
OS 10.02192052 44.31487962
OS 9.85284034 44.06182958
OS 9.73637372 43.7806592
OS 9.67700122 43.48216856
OS 9.67700122 43.17783084
OS 9.73637372 42.8793402
OS 9.85284034 42.59816982
OS 10.02192052 42.34511978
OS 10.23711948 42.12992082
OS 10.49016952 41.96084064
OS 10.61024548 41.91110236
OS 10.61024548 38.96010496
OS 10.61362876 38.94309458
OS 10.65106836 38.46738306
OS 10.76644786 37.9867922
OS 10.95558896 37.53016624
OS 11.21383076 37.1087523
OS 11.52374124 36.74589298
OS 11.53337292 36.73147848
OS 18.88238794 29.38246346
OS 18.88241842 29.38241774
OS 18.88242604 29.38242536
OS 18.89185706 29.37612362
OS 19.35480762 28.97012494
OS 19.87606642 28.62183252
OS 20.4383259 28.34455596
OS 21.03196708 28.14304252
OS 21.6468325 28.02073898
OS 22.25782696 27.9806908
OS 22.27014088 27.97824224
OS 25.97569608 27.97824478
OS 26.00513722 27.98409948
OS 26.36875092 27.94829056
OS 26.74670546 27.8336375
OS 27.0950309 27.6474555
OS 27.30369698 27.4762087
OS 27.39495918 27.38998078
OS 27.39514714 27.38969884
OS 27.48471516 27.3001359
OS 36.52407986 18.2607712
OS 36.4500033 17.98431252
OS 36.4500033 17.6156874
OS 36.54541078 17.25962258
OS 36.72972334 16.94038268
OS 36.99038322 16.6797228
OS 37.30962312 16.49541024
OS 37.66568794 16.40000276
OS 38.03431306 16.40000276
OS 38.39037788 16.49541024
OS 38.70961778 16.6797228
OS 38.97027766 16.94038268
OS 39.15459022 17.25962258
OS 39.2499977 17.6156874
OS 39.2499977 17.98431252
OS 39.15459022 18.34037734
OS 38.97027766 18.65961724
OS 38.70961778 18.92027712
OS 38.39037788 19.10458968
OS 38.03431306 19.19999716
OS 37.66568794 19.19999716
OS 37.38922926 19.1259206
OS 28.26029908 28.25485078
OS 28.24834076 28.26284162
OS 27.87288812 28.58351154
OS 27.44103732 28.84814906
OS 26.97310582 29.04197138
OS 26.48061506 29.16020838
OS 25.99072272 29.19876304
OS 25.97569608 29.20175262
OS 22.27014088 29.20175008
OS 22.23442086 29.1946457
OS 21.71224766 29.23574036
OS 21.16588858 29.36691104
OS 20.64677608 29.58193474
OS 20.1676889 29.8755181
OS 19.76819008 30.21672392
OS 19.74757544 30.24757476
OS 12.39852232 37.59662788
OS 12.37464378 37.61258416
OS 12.1517537 37.88417366
OS 11.97279038 38.21899138
OS 11.86258486 38.58228758
OS 11.82815008 38.93192874
OS 11.83375332 38.96010496
OS 11.83375332 41.91110236
OS 11.95382928 41.96084064
OS 12.20687932 42.12992082
OS 12.42207828 42.34511978
OS 12.59115846 42.59816982
OS 12.677267 42.80605104
OS 12.8147318 42.80605104
OS 12.90084034 42.59816982
OS 13.06992052 42.34511978
OS 13.28511948 42.12992082
OS 13.53816952 41.96084064
OS 13.65824548 41.91110236
OS 13.65824548 39.24664236
OS 13.65820992 39.24564414
OS 13.65820738 39.24560858
OS 13.67022666 39.12360222
OS 13.70524818 38.76800984
OS 13.84455956 38.3087626
OS 14.0707872 37.88551986
OS 14.37523922 37.5145427
OS 14.37658542 37.51344034
OS 14.37697658 37.5128536
OS 14.3769842 37.51284852
OS 20.31948946 31.57036358
OS 20.31949454 31.57034834
OS 20.31950216 31.57035342
OS 20.34366772 31.55420664
OS 20.64421068 31.29751932
OS 21.00559426 31.0760618
OS 21.39717082 30.91386502
OS 21.80930106 30.81492186
OS 22.20219588 30.7839999
OS 22.2309182 30.77828744
OS 22.2309182 30.77827474
OS 22.23112902 30.77823156
OS 22.23115442 30.77824172
OS 22.35791058 30.77824426
OS 27.86362982 30.7782468
OS 27.8930989 30.78410912
OS 28.32678104 30.7499766
OS 28.7785302 30.64152114
OS 29.2077521 30.4637313
OS 29.60388034 30.22098604
OS 29.86084198 30.00151988
OS 29.95137012 29.91347078
OS 30.04053174 29.82431932
OS 36.52407986 23.3407712
OS 36.4500033 23.06431252
OS 36.4500033 22.6956874
OS 36.54541078 22.33962258
OS 36.72972334 22.02038268
OS 36.99038322 21.7597228
OS 37.30962312 21.57541024
OS 37.66568794 21.48000276
OS 38.03431306 21.48000276
OS 38.39037788 21.57541024
OS 38.70961778 21.7597228
OS 38.97027766 22.02038268
OS 39.15459022 22.33962258
OS 39.2499977 22.6956874
OS 39.2499977 23.06431252
OS 39.15459022 23.42037734
OS 38.97027766 23.73961724
OS 38.70961778 24.00027712
OS 38.39037788 24.18458968
OS 38.03431306 24.27999716
OS 37.66568794 24.27999716
OS 37.38922926 24.2059206
OS 30.8165246 30.77862526
OS 30.79857696 30.7906166
OS 30.40410988 31.13655698
OS 29.95022712 31.43983298
OS 29.46064212 31.68127014
OS 28.94372926 31.85673588
OS 28.4083379 31.963233
OS 27.88477278 31.9975484
OS 27.86362982 32.00175464
OS 22.2311341 32.0017521
OS 22.2104458 31.9976373
OS 21.94170364 32.02410664
OS 21.66272274 32.10873436
OS 21.40561124 32.2461636
OS 21.19649304 32.41778378
OS 21.18464902 32.4355079
OS 15.24212852 38.37800808
OS 15.21664978 38.39503116
OS 15.03748326 38.6285232
OS 14.91418912 38.92618326
OS 14.88848686 39.12141528
OS 14.88175078 39.24562636
OS 14.88175332 39.24563398
OS 14.88165172 39.24613182
OS 14.88175332 39.24663982
OS 14.88175332 41.91110236
OS 15.00182928 41.96084064
OS 15.25487932 42.12992082
OS 15.47007828 42.34511978
OS 15.63915846 42.59816982
OS 15.75562508 42.8793402
OS 15.81499758 43.17783084
OS 15.81499758 43.48216856
OS 15.75562508 43.7806592
OS 15.63915846 44.06182958
OS 15.47007828 44.31487962
OS 15.25487932 44.53007858
OS 15.00182928 44.69915876
OS 14.7206589 44.81562538
OS 14.42216826 44.87499788
OE
OB 2.2419056 44.57499848 H
OS 1.9140932 44.57499848
OS 1.59744664 44.49015486
OS 1.31355084 44.32624866
OS 1.08175044 44.09444826
OS 0.91784424 43.81055246
OS 0.83300062 43.4939059
OS 0.83300062 43.1660935
OS 0.91784424 42.84944694
OS 1.08175044 42.56555114
OS 1.31355084 42.33375074
OS 1.59744664 42.16984454
OS 1.9140932 42.08500092
OS 2.2419056 42.08500092
OS 2.55855216 42.16984454
OS 2.84244796 42.33375074
OS 3.07424836 42.56555114
OS 3.23815456 42.84944694
OS 3.32299818 43.1660935
OS 3.32299818 43.4939059
OS 3.23815456 43.81055246
OS 3.07424836 44.09444826
OS 2.84244796 44.32624866
OS 2.55855216 44.49015486
OS 2.2419056 44.57499848
OE
OB 0.17101566 41.93899918 H
OS 0.12699492 41.93899918
OS 0.12699492 40.76701016
OS 1.29899918 40.76701016
OS 1.29899918 40.81101566
OS 1.2104751 41.141396
OS 1.0394569 41.43760318
OS 0.79760318 41.6794569
OS 0.501396 41.8504751
OS 0.17101566 41.93899918
OE
OB -0.12700508 41.93899918 H
OS -0.17101566 41.93899918
OS -0.501396 41.8504751
OS -0.79760318 41.6794569
OS -1.0394569 41.43760318
OS -1.2104751 41.141396
OS -1.29899918 40.81101566
OS -1.29899918 40.76701016
OS -0.12700508 40.76701016
OS -0.12700508 41.93899918
OE
OB 1.29899918 40.51301016 H
OS 0.12699492 40.51301016
OS 0.12699492 39.34100082
OS 0.17101566 39.34100082
OS 0.501396 39.4295249
OS 0.79760318 39.6005431
OS 1.0394569 39.84239682
OS 1.2104751 40.138604
OS 1.29899918 40.46898434
OS 1.29899918 40.51301016
OE
OB -0.12700508 40.51301016 H
OS -1.29899918 40.51301016
OS -1.29899918 40.46898434
OS -1.2104751 40.138604
OS -1.0394569 39.84239682
OS -0.79760318 39.6005431
OS -0.501396 39.4295249
OS -0.17101566 39.34100082
OS -0.12700508 39.34100082
OS -0.12700508 40.51301016
OE
OB 20.46429994 44.98999892 H
OS 20.01570038 44.98999892
OS 19.57262278 44.9198238
OS 19.14597898 44.78119822
OS 18.74627442 44.57753848
OS 18.38334906 44.31385854
OS 18.06614116 43.99665064
OS 17.80246122 43.63372528
OS 17.59880148 43.23402072
OS 17.4601759 42.80737692
OS 17.39000078 42.36429932
OS 17.39000078 41.91569976
OS 17.4601759 41.47262216
OS 17.59880148 41.04597836
OS 17.80246122 40.6462738
OS 18.06614116 40.28334844
OS 18.38334906 39.96614054
OS 18.74627442 39.7024606
OS 19.14597898 39.49880086
OS 19.57262278 39.36017528
OS 20.01570038 39.29000016
OS 20.46429994 39.29000016
OS 20.90737754 39.36017528
OS 21.33402134 39.49880086
OS 21.7337259 39.7024606
OS 22.09665126 39.96614054
OS 22.41385916 40.28334844
OS 22.6775391 40.6462738
OS 22.88119884 41.04597836
OS 23.01982442 41.47262216
OS 23.08999954 41.91569976
OS 23.08999954 42.36429932
OS 23.01982442 42.80737692
OS 22.88119884 43.23402072
OS 22.6775391 43.63372528
OS 22.41385916 43.99665064
OS 22.09665126 44.31385854
OS 21.7337259 44.57753848
OS 21.33402134 44.78119822
OS 20.90737754 44.9198238
OS 20.46429994 44.98999892
OE
OB 40.79216886 42.18499818 H
OS 40.48783114 42.18499818
OS 40.1893405 42.12562568
OS 39.90817012 42.00915906
OS 39.65512008 41.84007888
OS 39.43992112 41.62487992
OS 39.27084094 41.37182988
OS 39.15437432 41.0906595
OS 39.09500182 40.79216886
OS 39.09500182 40.48783114
OS 39.15437432 40.1893405
OS 39.27084094 39.90817012
OS 39.43992112 39.65512008
OS 39.65512008 39.43992112
OS 39.90817012 39.27084094
OS 40.1893405 39.15437432
OS 40.48783114 39.09500182
OS 40.79216886 39.09500182
OS 41.0906595 39.15437432
OS 41.37182988 39.27084094
OS 41.62487992 39.43992112
OS 41.84007888 39.65512008
OS 42.00915906 39.90817012
OS 42.12562568 40.1893405
OS 42.18499818 40.48783114
OS 42.18499818 40.79216886
OS 42.12562568 41.0906595
OS 42.00915906 41.37182988
OS 41.84007888 41.62487992
OS 41.62487992 41.84007888
OS 41.37182988 42.00915906
OS 41.0906595 42.12562568
OS 40.79216886 42.18499818
OE
OB 36.4019084 42.14999952 H
OS 35.99809412 42.14999952
OS 35.60203954 42.07121888
OS 35.2289618 41.91668528
OS 34.89320428 41.69233978
OS 34.60766256 41.40679806
OS 34.38331706 41.07104054
OS 34.22878346 40.6979628
OS 34.15000282 40.30190822
OS 34.15000282 39.89809394
OS 34.22878346 39.50203936
OS 34.38331706 39.12896162
OS 34.60766256 38.7932041
OS 34.89320428 38.50766238
OS 35.2289618 38.28331688
OS 35.60203954 38.12878328
OS 35.99809412 38.05000264
OS 36.4019084 38.05000264
OS 36.79796298 38.12878328
OS 37.17104072 38.28331688
OS 37.50679824 38.50766238
OS 37.79233996 38.7932041
OS 38.01668546 39.12896162
OS 38.17121906 39.50203936
OS 38.2499997 39.89809394
OS 38.2499997 40.30190822
OS 38.17121906 40.6979628
OS 38.01668546 41.07104054
OS 37.79233996 41.40679806
OS 37.50679824 41.69233978
OS 37.17104072 41.91668528
OS 36.79796298 42.07121888
OS 36.4019084 42.14999952
OE
OB 4.60190596 40.64999744 H
OS 4.19809168 40.64999744
OS 3.8020371 40.5712168
OS 3.42895936 40.4166832
OS 3.09320184 40.1923377
OS 2.80766012 39.90679598
OS 2.58331462 39.57103846
OS 2.42878102 39.19796072
OS 2.35000038 38.80190614
OS 2.35000038 38.39809186
OS 2.42878102 38.00203728
OS 2.58331462 37.62895954
OS 2.80766012 37.29320202
OS 3.09320184 37.0076603
OS 3.42895936 36.7833148
OS 3.8020371 36.6287812
OS 4.19809168 36.55000056
OS 4.60190596 36.55000056
OS 4.99796054 36.6287812
OS 5.37103828 36.7833148
OS 5.7067958 37.0076603
OS 5.99233752 37.29320202
OS 6.21668302 37.62895954
OS 6.37121662 38.00203728
OS 6.44999726 38.39809186
OS 6.44999726 38.80190614
OS 6.37121662 39.19796072
OS 6.21668302 39.57103846
OS 5.99233752 39.90679598
OS 5.7067958 40.1923377
OS 5.37103828 40.4166832
OS 4.99796054 40.5712168
OS 4.60190596 40.64999744
OE
OB 4.9748186 34.13999776 H
OS 4.6851824 34.13999776
OS 4.40541664 34.06503474
OS 4.15458656 33.92021664
OS 3.94978382 33.7154139
OS 3.80496572 33.46458382
OS 3.7300027 33.18481806
OS 3.7300027 32.89518186
OS 3.80496572 32.6154161
OS 3.94978382 32.36458602
OS 4.15458656 32.15978328
OS 4.40541664 32.01496518
OS 4.6851824 31.94000216
OS 4.9748186 31.94000216
OS 5.25458436 32.01496518
OS 5.50541444 32.15978328
OS 5.71021718 32.36458602
OS 5.85503528 32.6154161
OS 5.9299983 32.89518186
OS 5.9299983 33.18481806
OS 5.85503528 33.46458382
OS 5.71021718 33.7154139
OS 5.50541444 33.92021664
OS 5.25458436 34.06503474
OS 4.9748186 34.13999776
OE
OB 38.03431306 34.43999716 H
OS 37.66568794 34.43999716
OS 37.30962312 34.34458968
OS 36.99038322 34.16027712
OS 36.72972334 33.89961724
OS 36.54541078 33.58037734
OS 36.4500033 33.22431252
OS 36.4500033 32.8556874
OS 36.54541078 32.49962258
OS 36.72972334 32.18038268
OS 36.99038322 31.9197228
OS 37.30962312 31.73541024
OS 37.66568794 31.64000276
OS 38.03431306 31.64000276
OS 38.39037788 31.73541024
OS 38.70961778 31.9197228
OS 38.97027766 32.18038268
OS 39.15459022 32.49962258
OS 39.2499977 32.8556874
OS 39.2499977 33.22431252
OS 39.15459022 33.58037734
OS 38.97027766 33.89961724
OS 38.70961778 34.16027712
OS 38.39037788 34.34458968
OS 38.03431306 34.43999716
OE
OB 40.85101558 21.63899914 H
OS 40.80699484 21.63899914
OS 40.80699484 20.46699996
OS 41.9789991 20.46699996
OS 41.9789991 20.51101562
OS 41.89047502 20.84139596
OS 41.71945682 21.13760314
OS 41.4776031 21.37945686
OS 41.18139592 21.55047506
OS 40.85101558 21.63899914
OE
OB 40.55299484 21.63899914 H
OS 40.50898426 21.63899914
OS 40.17860392 21.55047506
OS 39.88239674 21.37945686
OS 39.64054302 21.13760314
OS 39.46952482 20.84139596
OS 39.38100074 20.51101562
OS 39.38100074 20.46699996
OS 40.55299484 20.46699996
OS 40.55299484 21.63899914
OE
OB 41.9789991 20.21299996 H
OS 40.80699484 20.21299996
OS 40.80699484 19.04100078
OS 40.85101558 19.04100078
OS 41.18139592 19.12952486
OS 41.4776031 19.30054306
OS 41.71945682 19.54239678
OS 41.89047502 19.83860396
OS 41.9789991 20.1689843
OS 41.9789991 20.21299996
OE
OB 40.55299484 20.21299996 H
OS 39.38100074 20.21299996
OS 39.38100074 20.1689843
OS 39.46952482 19.83860396
OS 39.64054302 19.54239678
OS 39.88239674 19.30054306
OS 40.17860392 19.12952486
OS 40.50898426 19.04100078
OS 40.55299484 19.04100078
OS 40.55299484 20.21299996
OE
OB 4.9748186 18.89999776 H
OS 4.6851824 18.89999776
OS 4.40541664 18.82503474
OS 4.15458656 18.68021664
OS 3.94978382 18.4754139
OS 3.80496572 18.22458382
OS 3.7300027 17.94481806
OS 3.7300027 17.65518186
OS 3.80496572 17.3754161
OS 3.94978382 17.12458602
OS 4.15458656 16.91978328
OS 4.40541664 16.77496518
OS 4.6851824 16.70000216
OS 4.9748186 16.70000216
OS 5.25458436 16.77496518
OS 5.50541444 16.91978328
OS 5.71021718 17.12458602
OS 5.85503528 17.3754161
OS 5.9299983 17.65518186
OS 5.9299983 17.94481806
OS 5.85503528 18.22458382
OS 5.71021718 18.4754139
OS 5.50541444 18.68021664
OS 5.25458436 18.82503474
OS 4.9748186 18.89999776
OE
OB 5.2899056 44.57499848 H
OS 4.9620932 44.57499848
OS 4.64544664 44.49015486
OS 4.36155084 44.32624866
OS 4.12975044 44.09444826
OS 3.96584424 43.81055246
OS 3.88100062 43.4939059
OS 3.88100062 43.1660935
OS 3.96584424 42.84944694
OS 4.12975044 42.56555114
OS 4.36155084 42.33375074
OS 4.64544664 42.16984454
OS 4.9620932 42.08500092
OS 5.2899056 42.08500092
OS 5.60655216 42.16984454
OS 5.76316094 42.26026092
OS 6.40075682 41.62266504
OS 6.49055344 41.53286334
OS 6.56646642 41.43729838
OS 6.65705552 41.31924172
OS 6.76080182 41.06877994
OS 6.79536614 40.80623792
OS 6.79412408 40.79999968
OS 6.79412408 39.85210216
OS 6.79122086 39.85210216
OS 6.82629318 39.40645408
OS 6.93064908 38.97178134
OS 7.10171808 38.55878242
OS 7.33528886 38.17763002
OS 7.62560832 37.83770944
OS 7.62766064 37.83976176
OS 8.45930998 37.00811496
OS 8.54731082 36.92010904
OS 8.62719128 36.82619508
OS 8.7813007 36.63841288
OS 8.95402324 36.31527154
OS 9.06038574 35.96464232
OS 9.09557744 35.6073202
OS 9.09412202 35.59999992
OS 9.09412202 18.342102
OS 9.09676616 18.3288051
OS 9.05507206 17.90547346
OS 8.92771392 17.4856267
OS 8.72089188 17.09869326
OS 8.52134694 16.85554668
OS 8.4397596 16.76233884
OS 8.43975452 16.76232868
OS 5.3610129 13.68358706
OS 5.25458436 13.74503474
OS 4.9748186 13.81999776
OS 4.6851824 13.81999776
OS 4.40541664 13.74503474
OS 4.15458656 13.60021664
OS 3.94978382 13.3954139
OS 3.80496572 13.14458382
OS 3.7300027 12.86481806
OS 3.7300027 12.57518186
OS 3.80496572 12.2954161
OS 3.94978382 12.04458602
OS 4.15458656 11.83978328
OS 4.40541664 11.69496518
OS 4.6851824 11.62000216
OS 4.9748186 11.62000216
OS 5.25458436 11.69496518
OS 5.50541444 11.83978328
OS 5.71021718 12.04458602
OS 5.85503528 12.2954161
OS 5.9299983 12.57518186
OS 5.9299983 12.86481806
OS 5.85503528 13.14458382
OS 5.7935876 13.25101236
OS 8.78253514 16.2399599
OS 8.87439424 16.32770928
OS 8.8743917 16.32771182
OS 9.16471116 16.66762986
OS 9.39828194 17.04878226
OS 9.56935094 17.46178118
OS 9.67370684 17.89645392
OS 9.70877916 18.342102
OS 9.70587594 18.342102
OS 9.70587594 35.59999992
OS 9.71196432 35.59999992
OS 9.66421994 36.0847513
OS 9.52282322 36.55087686
OS 9.29320722 36.98045944
OS 8.9841959 37.35698904
OS 8.98419844 37.35699158
OS 8.89008636 37.44248798
OS 8.06023788 38.272339
OS 8.04896536 38.2798701
OS 7.77910814 38.60869342
OS 7.5722861 38.99562686
OS 7.44492796 39.41547362
OS 7.40323386 39.83880526
OS 7.405878 39.85210216
OS 7.405878 40.79999968
OS 7.40794556 40.79999968
OS 7.3762362 41.12194722
OS 7.28232732 41.43151988
OS 7.12982826 41.71682538
OS 6.92460134 41.966896
OS 6.92460388 41.96689854
OS 6.8333366 42.05523974
OS 6.19573818 42.69283816
OS 6.28615456 42.84944694
OS 6.37099818 43.1660935
OS 6.37099818 43.4939059
OS 6.28615456 43.81055246
OS 6.12224836 44.09444826
OS 5.89044796 44.32624866
OS 5.60655216 44.49015486
OS 5.2899056 44.57499848
OE
OB 38.00192806 13.87399816 H
OS 37.97699034 13.87399816
OS 37.97699034 12.8469898
OS 39.0039987 12.8469898
OS 39.0039987 12.87192752
OS 38.92535522 13.16542706
OS 38.77342766 13.42857106
OS 38.5585716 13.64342712
OS 38.2954276 13.79535468
OS 38.00192806 13.87399816
OE
OB 37.72299034 13.87399816 H
OS 37.69807294 13.87399816
OS 37.4045734 13.79535468
OS 37.1414294 13.64342712
OS 36.92657334 13.42857106
OS 36.77464578 13.16542706
OS 36.6960023 12.87192752
OS 36.6960023 12.8469898
OS 37.72299034 12.8469898
OS 37.72299034 13.87399816
OE
OB 39.0039987 12.5929898 H
OS 37.97699034 12.5929898
OS 37.97699034 11.56600176
OS 38.00192806 11.56600176
OS 38.2954276 11.64464524
OS 38.5585716 11.7965728
OS 38.77342766 12.01142886
OS 38.92535522 12.27457286
OS 39.0039987 12.5680724
OS 39.0039987 12.5929898
OE
OB 37.72299034 12.5929898 H
OS 36.6960023 12.5929898
OS 36.6960023 12.5680724
OS 36.77464578 12.27457286
OS 36.92657334 12.01142886
OS 37.1414294 11.7965728
OS 37.4045734 11.64464524
OS 37.69807294 11.56600176
OS 37.72299034 11.56600176
OS 37.72299034 12.5929898
OE
OB 8.3379056 44.57499848 H
OS 8.0100932 44.57499848
OS 7.69344664 44.49015486
OS 7.40955084 44.32624866
OS 7.17775044 44.09444826
OS 7.01384424 43.81055246
OS 6.92900062 43.4939059
OS 6.92900062 43.1660935
OS 7.01384424 42.84944694
OS 7.17775044 42.56555114
OS 7.40955084 42.33375074
OS 7.69344664 42.16984454
OS 7.86812244 42.12303996
OS 7.86812244 40.28310206
OS 7.86521922 40.28310206
OS 7.90029154 39.83745398
OS 8.00464744 39.40278124
OS 8.17571644 38.98978232
OS 8.40928722 38.60862992
OS 8.69960668 38.26870934
OS 8.701659 38.27076166
OS 9.3343857 37.63803242
OS 9.42310028 37.5493153
OS 9.42325268 37.54916544
OS 9.42369718 37.54871586
OS 9.4241239 37.54830438
OS 9.42415438 37.54825612
OS 9.42419756 37.54823326
OS 9.50707268 37.4555766
OS 9.74078316 37.17079942
OS 9.97306616 36.73622828
OS 10.11610626 36.26468998
OS 10.15226062 35.89761426
OS 10.15914148 35.77346414
OS 10.15912116 35.77336254
OS 10.15912878 35.77332952
OS 10.1591237 35.77330158
OS 10.1591237 14.32710368
OS 10.16176784 14.31380678
OS 10.12007374 13.89047514
OS 9.9927156 13.47062838
OS 9.78589356 13.08369494
OS 9.58762878 12.84210792
OS 9.50475874 12.74734306
OS 9.50475874 12.74734052
OS 9.41667408 12.65924824
OS 5.3610129 8.60358706
OS 5.25458436 8.66503474
OS 4.9748186 8.73999776
OS 4.6851824 8.73999776
OS 4.40541664 8.66503474
OS 4.15458656 8.52021664
OS 3.94978382 8.3154139
OS 3.80496572 8.06458382
OS 3.7300027 7.78481806
OS 3.7300027 7.49518186
OS 3.80496572 7.2154161
OS 3.94978382 6.96458602
OS 4.15458656 6.75978328
OS 4.40541664 6.61496518
OS 4.6851824 6.54000216
OS 4.9748186 6.54000216
OS 5.25458436 6.61496518
OS 5.50541444 6.75978328
OS 5.71021718 6.96458602
OS 5.85503528 7.2154161
OS 5.9299983 7.49518186
OS 5.9299983 7.78481806
OS 5.85503528 8.06458382
OS 5.7935876 8.17101236
OS 9.84753682 12.22496158
OS 9.93939592 12.31271096
OS 9.93939338 12.3127135
OS 10.22971284 12.65263154
OS 10.46328362 13.03378394
OS 10.63435262 13.44678286
OS 10.73870852 13.8814556
OS 10.77378084 14.32710368
OS 10.77087762 14.32710368
OS 10.77087762 35.64774176
OS 10.774553 35.77325586
OS 10.77463428 35.77430742
OS 10.765028 35.89628584
OS 10.73616852 36.2629831
OS 10.62173644 36.73962934
OS 10.43414982 37.19250372
OS 10.17802892 37.61045818
OS 9.9404932 37.88857294
OS 9.85967802 37.98320064
OS 9.85933258 37.98349528
OS 9.76689944 38.07067062
OS 9.22403794 38.61353212
OS 9.13424386 38.70333382
OS 9.05265144 38.79654674
OS 8.8531065 39.03969332
OS 8.64628446 39.42662676
OS 8.51892632 39.84647352
OS 8.47723222 40.26980516
OS 8.47987636 40.28310206
OS 8.47987636 42.12303996
OS 8.65455216 42.16984454
OS 8.93844796 42.33375074
OS 9.17024836 42.56555114
OS 9.33415456 42.84944694
OS 9.41899818 43.1660935
OS 9.41899818 43.4939059
OS 9.33415456 43.81055246
OS 9.17024836 44.09444826
OS 8.93844796 44.32624866
OS 8.65455216 44.49015486
OS 8.3379056 44.57499848
OE
OB 37.9948186 8.73999776 H
OS 37.7051824 8.73999776
OS 37.42541664 8.66503474
OS 37.17458656 8.52021664
OS 36.96978382 8.3154139
OS 36.82496572 8.06458382
OS 36.7500027 7.78481806
OS 36.7500027 7.49518186
OS 36.82496572 7.2154161
OS 36.96978382 6.96458602
OS 37.17458656 6.75978328
OS 37.42541664 6.61496518
OS 37.7051824 6.54000216
OS 37.9948186 6.54000216
OS 38.27458436 6.61496518
OS 38.52541444 6.75978328
OS 38.73021718 6.96458602
OS 38.87503528 7.2154161
OS 38.9499983 7.49518186
OS 38.9499983 7.78481806
OS 38.87503528 8.06458382
OS 38.73021718 8.3154139
OS 38.52541444 8.52021664
OS 38.27458436 8.66503474
OS 37.9948186 8.73999776
OE
OB 4.60190596 4.04999952 H
OS 4.19809168 4.04999952
OS 3.8020371 3.97121888
OS 3.42895936 3.81668528
OS 3.09320184 3.59233978
OS 2.80766012 3.30679806
OS 2.58331462 2.97104054
OS 2.42878102 2.5979628
OS 2.35000038 2.20190822
OS 2.35000038 1.79809394
OS 2.42878102 1.40203936
OS 2.58331462 1.02896162
OS 2.80766012 0.6932041
OS 3.09320184 0.40766238
OS 3.42895936 0.18331688
OS 3.8020371 0.02878328
OS 4.19809168 -0.04999736
OS 4.60190596 -0.04999736
OS 4.99796054 0.02878328
OS 5.37103828 0.18331688
OS 5.7067958 0.40766238
OS 5.99233752 0.6932041
OS 6.21668302 1.02896162
OS 6.37121662 1.40203936
OS 6.44999726 1.79809394
OS 6.44999726 2.20190822
OS 6.37121662 2.5979628
OS 6.21668302 2.97104054
OS 5.99233752 3.30679806
OS 5.7067958 3.59233978
OS 5.37103828 3.81668528
OS 4.99796054 3.97121888
OS 4.60190596 4.04999952
OE
OB 40.8039062 1.24499878 H
OS 40.4760938 1.24499878
OS 40.15944724 1.16015516
OS 39.87555144 0.99624896
OS 39.64375104 0.76444856
OS 39.47984484 0.48055276
OS 39.39500122 0.1639062
OS 39.39500122 -0.1639062
OS 39.47984484 -0.48055276
OS 39.64375104 -0.76444856
OS 39.87555144 -0.99624896
OS 40.15944724 -1.16015516
OS 40.4760938 -1.24499878
OS 40.8039062 -1.24499878
OS 41.12055276 -1.16015516
OS 41.40444856 -0.99624896
OS 41.63624896 -0.76444856
OS 41.80015516 -0.48055276
OS 41.88499878 -0.1639062
OS 41.88499878 0.1639062
OS 41.80015516 0.48055276
OS 41.63624896 0.76444856
OS 41.40444856 0.99624896
OS 41.12055276 1.16015516
OS 40.8039062 1.24499878
OE
OB 0.1639062 1.24499878 H
OS -0.1639062 1.24499878
OS -0.48055276 1.16015516
OS -0.76444856 0.99624896
OS -0.99624896 0.76444856
OS -1.16015516 0.48055276
OS -1.24499878 0.1639062
OS -1.24499878 -0.1639062
OS -1.16015516 -0.48055276
OS -0.99624896 -0.76444856
OS -0.76444856 -0.99624896
OS -0.48055276 -1.16015516
OS -0.1639062 -1.24499878
OS 0.1639062 -1.24499878
OS 0.48055276 -1.16015516
OS 0.76444856 -0.99624896
OS 0.99624896 -0.76444856
OS 1.16015516 -0.48055276
OS 1.24499878 -0.1639062
OS 1.24499878 0.1639062
OS 1.16015516 0.48055276
OS 0.99624896 0.76444856
OS 0.76444856 0.99624896
OS 0.48055276 1.16015516
OS 0.1639062 1.24499878
OE
OB 35.70190726 1.0499979 H
OS 35.29809298 1.0499979
OS 34.9020384 0.97121726
OS 34.52896066 0.81668366
OS 34.19320314 0.59233816
OS 33.90766142 0.30679644
OS 33.68331592 -0.02896108
OS 33.52878232 -0.40203882
OS 33.45000168 -0.7980934
OS 33.45000168 -1.20190768
OS 33.52878232 -1.59796226
OS 33.68331592 -1.97104
OS 33.90766142 -2.30679752
OS 34.19320314 -2.59233924
OS 34.52896066 -2.81668474
OS 34.9020384 -2.97121834
OS 35.29809298 -3.04999898
OS 35.70190726 -3.04999898
OS 36.09796184 -2.97121834
OS 36.47103958 -2.81668474
OS 36.8067971 -2.59233924
OS 37.09233882 -2.30679752
OS 37.31668432 -1.97104
OS 37.47121792 -1.59796226
OS 37.54999856 -1.20190768
OS 37.54999856 -0.7980934
OS 37.47121792 -0.40203882
OS 37.31668432 -0.02896108
OS 37.09233882 0.30679644
OS 36.8067971 0.59233816
OS 36.47103958 0.81668366
OS 36.09796184 0.97121726
OS 35.70190726 1.0499979
OE
OB 20.66429954 1.58999936 H
OS 20.21569998 1.58999936
OS 19.77262238 1.51982424
OS 19.34597858 1.38119866
OS 18.94627402 1.17753892
OS 18.58334866 0.91385898
OS 18.26614076 0.59665108
OS 18.00246082 0.23372572
OS 17.79880108 -0.16597884
OS 17.6601755 -0.59262264
OS 17.59000038 -1.03570024
OS 17.59000038 -1.4842998
OS 17.6601755 -1.9273774
OS 17.79880108 -2.3540212
OS 18.00246082 -2.75372576
OS 18.26614076 -3.11665112
OS 18.58334866 -3.43385902
OS 18.94627402 -3.69753896
OS 19.34597858 -3.9011987
OS 19.77262238 -4.03982428
OS 20.21569998 -4.1099994
OS 20.66429954 -4.1099994
OS 21.10737714 -4.03982428
OS 21.53402094 -3.9011987
OS 21.9337255 -3.69753896
OS 22.29665086 -3.43385902
OS 22.61385876 -3.11665112
OS 22.8775387 -2.75372576
OS 23.08119844 -2.3540212
OS 23.21982402 -1.9273774
OS 23.28999914 -1.4842998
OS 23.28999914 -1.03570024
OS 23.21982402 -0.59262264
OS 23.08119844 -0.16597884
OS 22.8775387 0.23372572
OS 22.61385876 0.59665108
OS 22.29665086 0.91385898
OS 21.9337255 1.17753892
OS 21.53402094 1.38119866
OS 21.10737714 1.51982424
OS 20.66429954 1.58999936
OE
SE
S P 0
OB -2.97936666 -38.48662356 I
OS -2.97197018 -38.48754812
OS -2.96272458 -38.48939724
OS -2.95255442 -38.49124636
OS -2.94053514 -38.49402004
OS -2.92944042 -38.49679372
OS -2.91649658 -38.50141652
OS -2.9044773 -38.50603932
OS -2.89153346 -38.51251124
OS -2.87858962 -38.51990772
OS -2.86564578 -38.52822876
OS -2.8536265 -38.53839892
OS -2.84253178 -38.54949364
OS -2.84160722 -38.5504182
OS -2.8397581 -38.55226732
OS -2.83698442 -38.55596556
OS -2.83328618 -38.56151292
OS -2.82866338 -38.56798484
OS -2.82404058 -38.57538132
OS -2.81849322 -38.58462692
OS -2.81294586 -38.59572164
OS -2.8073985 -38.60774092
OS -2.80185114 -38.62068476
OS -2.79722834 -38.63547772
OS -2.79260554 -38.65119524
OS -2.7889073 -38.66876188
OS -2.78613362 -38.68725308
OS -2.7842845 -38.70666884
OS -2.78335994 -38.72793372
OS -2.78335994 -38.72885828
OS -2.78335994 -38.73255652
OS -2.78335994 -38.73902844
OS -2.7842845 -38.74827404
OS -3.1309945 -38.74827404
OS -3.1309945 -38.7491986
OS -3.1309945 -38.75197228
OS -3.13006994 -38.75567052
OS -3.13006994 -38.76121788
OS -3.12914538 -38.7676898
OS -3.12729626 -38.77508628
OS -3.12452258 -38.79172836
OS -3.11897522 -38.81021956
OS -3.11157874 -38.83055988
OS -3.10140858 -38.84905108
OS -3.08846474 -38.86569316
OS -3.08754018 -38.86569316
OS -3.08661562 -38.86754228
OS -3.08106826 -38.87216508
OS -3.07274722 -38.878637
OS -3.0616525 -38.88510892
OS -3.04685954 -38.8925054
OS -3.03021746 -38.89897732
OS -3.01172626 -38.90360012
OS -3.0015561 -38.90452468
OS -2.99046138 -38.90544924
OS -2.9830649 -38.90544924
OS -2.97474386 -38.90452468
OS -2.9645737 -38.90267556
OS -2.95347898 -38.89990188
OS -2.94053514 -38.89620364
OS -2.92851586 -38.89065628
OS -2.91649658 -38.8832598
OS -2.91557202 -38.88233524
OS -2.91094922 -38.878637
OS -2.90540186 -38.87308964
OS -2.89892994 -38.86569316
OS -2.89153346 -38.855523
OS -2.88321242 -38.84257916
OS -2.87489138 -38.8277862
OS -2.8674949 -38.81021956
OS -2.78613362 -38.82038972
OS -2.78613362 -38.82131428
OS -2.78705818 -38.8231634
OS -2.78798274 -38.82686164
OS -2.78983186 -38.832409
OS -2.79260554 -38.83795636
OS -2.79537922 -38.84535284
OS -2.8027757 -38.86107036
OS -2.8120213 -38.878637
OS -2.82496514 -38.8971282
OS -2.8397581 -38.91469484
OS -2.8582493 -38.93133692
OS -2.85917386 -38.93133692
OS -2.86102298 -38.93318604
OS -2.86379666 -38.93503516
OS -2.8674949 -38.93780884
OS -2.87304226 -38.94058252
OS -2.87858962 -38.9433562
OS -2.8859861 -38.94705444
OS -2.89430714 -38.95075268
OS -2.90355274 -38.95445092
OS -2.91279834 -38.95814916
OS -2.93591234 -38.96369652
OS -2.96180002 -38.96831932
OS -2.99046138 -38.97016844
OS -3.00063154 -38.97016844
OS -3.00710346 -38.96924388
OS -3.0154245 -38.96831932
OS -3.02559466 -38.9664702
OS -3.03668938 -38.96462108
OS -3.04870866 -38.96277196
OS -3.07459634 -38.95537548
OS -3.08846474 -38.94982812
OS -3.10140858 -38.94428076
OS -3.11527698 -38.93688428
OS -3.12822082 -38.92856324
OS -3.1402401 -38.91931764
OS -3.15225938 -38.90822292
OS -3.15318394 -38.90729836
OS -3.15503306 -38.90544924
OS -3.15780674 -38.901751
OS -3.16150498 -38.89620364
OS -3.16612778 -38.88973172
OS -3.17075058 -38.88233524
OS -3.17629794 -38.87308964
OS -3.1818453 -38.86291948
OS -3.18739266 -38.8509002
OS -3.19294002 -38.83795636
OS -3.19756282 -38.8231634
OS -3.20218562 -38.80744588
OS -3.20588386 -38.7908038
OS -3.20865754 -38.7723126
OS -3.21050666 -38.75289684
OS -3.21143122 -38.73255652
OS -3.21143122 -38.73163196
OS -3.21143122 -38.72700916
OS -3.21143122 -38.7214618
OS -3.21050666 -38.71314076
OS -3.2095821 -38.7029706
OS -3.20865754 -38.69187588
OS -3.20680842 -38.67893204
OS -3.20403474 -38.6659882
OS -3.19663826 -38.63640228
OS -3.19201546 -38.62160932
OS -3.1864681 -38.6058918
OS -3.17907162 -38.59109884
OS -3.17075058 -38.57723044
OS -3.16150498 -38.56336204
OS -3.15133482 -38.5504182
OS -3.15041026 -38.54949364
OS -3.14856114 -38.54764452
OS -3.1448629 -38.54487084
OS -3.1402401 -38.54024804
OS -3.13469274 -38.53562524
OS -3.12729626 -38.53007788
OS -3.11897522 -38.52360596
OS -3.10880506 -38.5180586
OS -3.0986349 -38.51158668
OS -3.08661562 -38.50603932
OS -3.07367178 -38.50049196
OS -3.05980338 -38.49586916
OS -3.04501042 -38.49124636
OS -3.0292929 -38.48847268
OS -3.01265082 -38.48662356
OS -2.99508418 -38.485699
OS -2.98583858 -38.485699
OS -2.97936666 -38.48662356
OE
OB -2.5022937 -38.48662356 I
OS -2.49212354 -38.48847268
OS -2.48010426 -38.49217092
OS -2.46716042 -38.49679372
OS -2.45236746 -38.50326564
OS -2.43664994 -38.51158668
OS -2.4653113 -38.58370236
OS -2.46623586 -38.5827778
OS -2.4699341 -38.58092868
OS -2.47548146 -38.578155
OS -2.48287794 -38.57538132
OS -2.49119898 -38.57260764
OS -2.50136914 -38.56983396
OS -2.5115393 -38.56798484
OS -2.52170946 -38.56706028
OS -2.52633226 -38.56706028
OS -2.53095506 -38.56798484
OS -2.53742698 -38.5689094
OS -2.5438989 -38.57075852
OS -2.55221994 -38.5735322
OS -2.56054098 -38.57723044
OS -2.56793746 -38.5827778
OS -2.56886202 -38.58370236
OS -2.5716357 -38.58555148
OS -2.57440938 -38.58924972
OS -2.57903218 -38.59387252
OS -2.58365498 -38.60034444
OS -2.58827778 -38.60774092
OS -2.59290058 -38.61606196
OS -2.59659882 -38.62623212
OS -2.59752338 -38.62808124
OS -2.59844794 -38.6336286
OS -2.60029706 -38.64194964
OS -2.60307074 -38.65304436
OS -2.60584442 -38.66691276
OS -2.60769354 -38.68263028
OS -2.6086181 -38.69927236
OS -2.60954266 -38.71776356
OS -2.60954266 -38.95999828
OS -2.68813026 -38.95999828
OS -2.68813026 -38.49586916
OS -2.61693914 -38.49586916
OS -2.61693914 -38.56613572
OS -2.61601458 -38.56521116
OS -2.61231634 -38.55873924
OS -2.60769354 -38.5504182
OS -2.60029706 -38.54024804
OS -2.59290058 -38.53007788
OS -2.58457954 -38.51898316
OS -2.5762585 -38.50973756
OS -2.56793746 -38.50234108
OS -2.5670129 -38.50141652
OS -2.56423922 -38.4995674
OS -2.55869186 -38.49679372
OS -2.5531445 -38.49402004
OS -2.54574802 -38.49124636
OS -2.53650242 -38.48847268
OS -2.52725682 -38.48662356
OS -2.51708666 -38.485699
OS -2.51061474 -38.485699
OS -2.5022937 -38.48662356
OE
OB -3.4499677 -38.48662356 I
OS -3.43979754 -38.48754812
OS -3.42777826 -38.48939724
OS -3.41483442 -38.49217092
OS -3.40096602 -38.49586916
OS -3.38802218 -38.50141652
OS -3.38617306 -38.50234108
OS -3.38247482 -38.5041902
OS -3.3760029 -38.50696388
OS -3.36860642 -38.51158668
OS -3.35936082 -38.51713404
OS -3.35103978 -38.52453052
OS -3.34271874 -38.531927
OS -3.33532226 -38.5411726
OS -3.3343977 -38.54209716
OS -3.33254858 -38.5457954
OS -3.3297749 -38.5504182
OS -3.3251521 -38.55689012
OS -3.32145386 -38.56613572
OS -3.31775562 -38.57538132
OS -3.31313282 -38.58647604
OS -3.31035914 -38.59849532
OS -3.31035914 -38.59941988
OS -3.30943458 -38.60311812
OS -3.30851002 -38.60866548
OS -3.30758546 -38.61606196
OS -3.30758546 -38.62715668
OS -3.3066609 -38.64010052
OS -3.30573634 -38.65581804
OS -3.30573634 -38.6752338
OS -3.30573634 -38.95999828
OS -3.38432394 -38.95999828
OS -3.38432394 -38.67893204
OS -3.38432394 -38.67800748
OS -3.38432394 -38.67708292
OS -3.38432394 -38.670611
OS -3.38432394 -38.66228996
OS -3.3852485 -38.6521198
OS -3.38617306 -38.64010052
OS -3.38802218 -38.62808124
OS -3.39079586 -38.61698652
OS -3.39356954 -38.60681636
OS -3.39356954 -38.6058918
OS -3.39541866 -38.60311812
OS -3.39819234 -38.59849532
OS -3.40096602 -38.59294796
OS -3.40558882 -38.5874006
OS -3.41113618 -38.58092868
OS -3.41853266 -38.57445676
OS -3.4268537 -38.5689094
OS -3.42777826 -38.56798484
OS -3.43055194 -38.56613572
OS -3.4360993 -38.5642866
OS -3.44257122 -38.56151292
OS -3.4499677 -38.55873924
OS -3.4592133 -38.55596556
OS -3.47030802 -38.555041
OS -3.48140274 -38.55411644
OS -3.48602554 -38.55411644
OS -3.48972378 -38.555041
OS -3.49896938 -38.55596556
OS -3.51098866 -38.55781468
OS -3.5239325 -38.56243748
OS -3.53872546 -38.56798484
OS -3.55351842 -38.57538132
OS -3.56738682 -38.58647604
OS -3.56923594 -38.58832516
OS -3.57293418 -38.59294796
OS -3.57570786 -38.5966462
OS -3.57848154 -38.601269
OS -3.58217978 -38.60681636
OS -3.58495346 -38.61328828
OS -3.5886517 -38.62068476
OS -3.59234994 -38.62993036
OS -3.59512362 -38.64010052
OS -3.5978973 -38.65119524
OS -3.59974642 -38.66321452
OS -3.60159554 -38.67615836
OS -3.60344466 -38.69187588
OS -3.60344466 -38.7075934
OS -3.60344466 -38.95999828
OS -3.68203226 -38.95999828
OS -3.68203226 -38.49586916
OS -3.6117657 -38.49586916
OS -3.6117657 -38.56243748
OS -3.61084114 -38.56151292
OS -3.60899202 -38.55873924
OS -3.60621834 -38.555041
OS -3.6025201 -38.5504182
OS -3.59697274 -38.54487084
OS -3.59050082 -38.53839892
OS -3.58310434 -38.53100244
OS -3.57385874 -38.52360596
OS -3.56461314 -38.51713404
OS -3.55351842 -38.50973756
OS -3.54149914 -38.50326564
OS -3.5285553 -38.49771828
OS -3.51376234 -38.49309548
OS -3.49896938 -38.48939724
OS -3.4823273 -38.48662356
OS -3.46476066 -38.485699
OS -3.45736418 -38.485699
OS -3.4499677 -38.48662356
OE
OB -0.0660781 -38.48662356 I
OS -0.05590794 -38.48847268
OS -0.04388866 -38.49217092
OS -0.03094482 -38.49679372
OS -0.01615186 -38.50326564
OS -0.00043434 -38.51158668
OS -0.0290957 -38.58370236
OS -0.03002026 -38.5827778
OS -0.0337185 -38.58092868
OS -0.03926586 -38.578155
OS -0.04666234 -38.57538132
OS -0.05498338 -38.57260764
OS -0.06515354 -38.56983396
OS -0.0753237 -38.56798484
OS -0.08549386 -38.56706028
OS -0.09011666 -38.56706028
OS -0.09473946 -38.56798484
OS -0.10121138 -38.5689094
OS -0.1076833 -38.57075852
OS -0.11600434 -38.5735322
OS -0.12432538 -38.57723044
OS -0.13172186 -38.5827778
OS -0.13264642 -38.58370236
OS -0.1354201 -38.58555148
OS -0.13819378 -38.58924972
OS -0.14281658 -38.59387252
OS -0.14743938 -38.60034444
OS -0.15206218 -38.60774092
OS -0.15668498 -38.61606196
OS -0.16038322 -38.62623212
OS -0.16130778 -38.62808124
OS -0.16223234 -38.6336286
OS -0.16408146 -38.64194964
OS -0.16685514 -38.65304436
OS -0.16962882 -38.66691276
OS -0.17147794 -38.68263028
OS -0.1724025 -38.69927236
OS -0.17332706 -38.71776356
OS -0.17332706 -38.95999828
OS -0.25191466 -38.95999828
OS -0.25191466 -38.49586916
OS -0.18072354 -38.49586916
OS -0.18072354 -38.56613572
OS -0.17979898 -38.56521116
OS -0.17610074 -38.55873924
OS -0.17147794 -38.5504182
OS -0.16408146 -38.54024804
OS -0.15668498 -38.53007788
OS -0.14836394 -38.51898316
OS -0.1400429 -38.50973756
OS -0.13172186 -38.50234108
OS -0.1307973 -38.50141652
OS -0.12802362 -38.4995674
OS -0.12247626 -38.49679372
OS -0.1169289 -38.49402004
OS -0.10953242 -38.49124636
OS -0.10028682 -38.48847268
OS -0.09104122 -38.48662356
OS -0.08087106 -38.485699
OS -0.07439914 -38.485699
OS -0.0660781 -38.48662356
OE
OB -1.94201034 -39.1375138 I
OS -2.46253762 -39.1375138
OS -2.46253762 -39.08111564
OS -1.94201034 -39.08111564
OS -1.94201034 -39.1375138
OE
OB -1.81534562 -38.95999828 I
OS -1.89393322 -38.95999828
OS -1.89393322 -38.32020276
OS -1.81534562 -38.32020276
OS -1.81534562 -38.95999828
OE
OB -0.99248722 -38.96739476 I
OS -0.99248722 -38.96831932
OS -0.99341178 -38.971093
OS -0.9952609 -38.97479124
OS -0.99711002 -38.97941404
OS -0.9998837 -38.98588596
OS -1.00265738 -38.99328244
OS -1.0091293 -39.00899996
OS -1.01560122 -39.0265666
OS -1.0229977 -39.04413324
OS -1.03039418 -39.05985076
OS -1.03409242 -39.06632268
OS -1.0368661 -39.0727946
OS -1.03779066 -39.07464372
OS -1.04056434 -39.07926652
OS -1.04518714 -39.08573844
OS -1.0507345 -39.09405948
OS -1.05813098 -39.10330508
OS -1.06645202 -39.11255068
OS -1.07477306 -39.12179628
OS -1.08494322 -39.12919276
OS -1.08586778 -39.13011732
OS -1.08956602 -39.13196644
OS -1.09511338 -39.13474012
OS -1.10343442 -39.13843836
OS -1.11268002 -39.1421366
OS -1.12377474 -39.14491028
OS -1.13579402 -39.1467594
OS -1.14966242 -39.14768396
OS -1.15336066 -39.14768396
OS -1.15798346 -39.1467594
OS -1.16445538 -39.1467594
OS -1.17185186 -39.14491028
OS -1.1801729 -39.14306116
OS -1.1894185 -39.14121204
OS -1.19958866 -39.1375138
OS -1.2079097 -39.06447356
OS -1.20698514 -39.06447356
OS -1.2032869 -39.06539812
OS -1.1986641 -39.06632268
OS -1.19311674 -39.0681718
OS -1.17832378 -39.07094548
OS -1.16353082 -39.07187004
OS -1.15890802 -39.07187004
OS -1.15428522 -39.07094548
OS -1.14873786 -39.07094548
OS -1.13486946 -39.0681718
OS -1.12839754 -39.06539812
OS -1.12192562 -39.06262444
OS -1.12100106 -39.06262444
OS -1.11915194 -39.06077532
OS -1.11637826 -39.0589262
OS -1.11268002 -39.05615252
OS -1.10435898 -39.04875604
OS -1.0969625 -39.03858588
OS -1.0969625 -39.03766132
OS -1.09511338 -39.0358122
OS -1.09326426 -39.03211396
OS -1.09141514 -39.0265666
OS -1.0877169 -39.01917012
OS -1.08401866 -39.0080754
OS -1.0784713 -38.99513156
OS -1.07292394 -38.97941404
OS -1.07292394 -38.97848948
OS -1.07107482 -38.97479124
OS -1.0692257 -38.96831932
OS -1.06552746 -38.95999828
OS -1.24119386 -38.49586916
OS -1.15798346 -38.49586916
OS -1.06090466 -38.76491612
OS -1.06090466 -38.76584068
OS -1.0599801 -38.76676524
OS -1.05905554 -38.76953892
OS -1.05813098 -38.77416172
OS -1.05628186 -38.77878452
OS -1.05443274 -38.78433188
OS -1.04980994 -38.79727572
OS -1.04426258 -38.81299324
OS -1.03871522 -38.83148444
OS -1.03316786 -38.8509002
OS -1.0276205 -38.87216508
OS -1.0276205 -38.87124052
OS -1.02669594 -38.8693914
OS -1.02577138 -38.86661772
OS -1.02484682 -38.86291948
OS -1.02392226 -38.85829668
OS -1.02207314 -38.85274932
OS -1.0183749 -38.83888092
OS -1.0137521 -38.8231634
OS -1.00728018 -38.8046722
OS -1.00173282 -38.786181
OS -0.99433634 -38.76676524
OS -0.89448386 -38.49586916
OS -0.81589626 -38.49586916
OS -0.99248722 -38.96739476
OE
OB -0.54315106 -38.48662356 I
OS -0.53575458 -38.48754812
OS -0.52650898 -38.48939724
OS -0.51633882 -38.49124636
OS -0.50431954 -38.49402004
OS -0.49322482 -38.49679372
OS -0.48028098 -38.50141652
OS -0.4682617 -38.50603932
OS -0.45531786 -38.51251124
OS -0.44237402 -38.51990772
OS -0.42943018 -38.52822876
OS -0.4174109 -38.53839892
OS -0.40631618 -38.54949364
OS -0.40539162 -38.5504182
OS -0.4035425 -38.55226732
OS -0.40076882 -38.55596556
OS -0.39707058 -38.56151292
OS -0.39244778 -38.56798484
OS -0.38782498 -38.57538132
OS -0.38227762 -38.58462692
OS -0.37673026 -38.59572164
OS -0.3711829 -38.60774092
OS -0.36563554 -38.62068476
OS -0.36101274 -38.63547772
OS -0.35638994 -38.65119524
OS -0.3526917 -38.66876188
OS -0.34991802 -38.68725308
OS -0.3480689 -38.70666884
OS -0.34714434 -38.72793372
OS -0.34714434 -38.72885828
OS -0.34714434 -38.73255652
OS -0.34714434 -38.73902844
OS -0.3480689 -38.74827404
OS -0.6947789 -38.74827404
OS -0.6947789 -38.7491986
OS -0.6947789 -38.75197228
OS -0.69385434 -38.75567052
OS -0.69385434 -38.76121788
OS -0.69292978 -38.7676898
OS -0.69108066 -38.77508628
OS -0.68830698 -38.79172836
OS -0.68275962 -38.81021956
OS -0.67536314 -38.83055988
OS -0.66519298 -38.84905108
OS -0.65224914 -38.86569316
OS -0.65132458 -38.86569316
OS -0.65040002 -38.86754228
OS -0.64485266 -38.87216508
OS -0.63653162 -38.878637
OS -0.6254369 -38.88510892
OS -0.61064394 -38.8925054
OS -0.59400186 -38.89897732
OS -0.57551066 -38.90360012
OS -0.5653405 -38.90452468
OS -0.55424578 -38.90544924
OS -0.5468493 -38.90544924
OS -0.53852826 -38.90452468
OS -0.5283581 -38.90267556
OS -0.51726338 -38.89990188
OS -0.50431954 -38.89620364
OS -0.49230026 -38.89065628
OS -0.48028098 -38.8832598
OS -0.47935642 -38.88233524
OS -0.47473362 -38.878637
OS -0.46918626 -38.87308964
OS -0.46271434 -38.86569316
OS -0.45531786 -38.855523
OS -0.44699682 -38.84257916
OS -0.43867578 -38.8277862
OS -0.4312793 -38.81021956
OS -0.34991802 -38.82038972
OS -0.34991802 -38.82131428
OS -0.35084258 -38.8231634
OS -0.35176714 -38.82686164
OS -0.35361626 -38.832409
OS -0.35638994 -38.83795636
OS -0.35916362 -38.84535284
OS -0.3665601 -38.86107036
OS -0.3758057 -38.878637
OS -0.38874954 -38.8971282
OS -0.4035425 -38.91469484
OS -0.4220337 -38.93133692
OS -0.42295826 -38.93133692
OS -0.42480738 -38.93318604
OS -0.42758106 -38.93503516
OS -0.4312793 -38.93780884
OS -0.43682666 -38.94058252
OS -0.44237402 -38.9433562
OS -0.4497705 -38.94705444
OS -0.45809154 -38.95075268
OS -0.46733714 -38.95445092
OS -0.47658274 -38.95814916
OS -0.49969674 -38.96369652
OS -0.52558442 -38.96831932
OS -0.55424578 -38.97016844
OS -0.56441594 -38.97016844
OS -0.57088786 -38.96924388
OS -0.5792089 -38.96831932
OS -0.58937906 -38.9664702
OS -0.60047378 -38.96462108
OS -0.61249306 -38.96277196
OS -0.63838074 -38.95537548
OS -0.65224914 -38.94982812
OS -0.66519298 -38.94428076
OS -0.67906138 -38.93688428
OS -0.69200522 -38.92856324
OS -0.7040245 -38.91931764
OS -0.71604378 -38.90822292
OS -0.71696834 -38.90729836
OS -0.71881746 -38.90544924
OS -0.72159114 -38.901751
OS -0.72528938 -38.89620364
OS -0.72991218 -38.88973172
OS -0.73453498 -38.88233524
OS -0.74008234 -38.87308964
OS -0.7456297 -38.86291948
OS -0.75117706 -38.8509002
OS -0.75672442 -38.83795636
OS -0.76134722 -38.8231634
OS -0.76597002 -38.80744588
OS -0.76966826 -38.7908038
OS -0.77244194 -38.7723126
OS -0.77429106 -38.75289684
OS -0.77521562 -38.73255652
OS -0.77521562 -38.73163196
OS -0.77521562 -38.72700916
OS -0.77521562 -38.7214618
OS -0.77429106 -38.71314076
OS -0.7733665 -38.7029706
OS -0.77244194 -38.69187588
OS -0.77059282 -38.67893204
OS -0.76781914 -38.6659882
OS -0.76042266 -38.63640228
OS -0.75579986 -38.62160932
OS -0.7502525 -38.6058918
OS -0.74285602 -38.59109884
OS -0.73453498 -38.57723044
OS -0.72528938 -38.56336204
OS -0.71511922 -38.5504182
OS -0.71419466 -38.54949364
OS -0.71234554 -38.54764452
OS -0.7086473 -38.54487084
OS -0.7040245 -38.54024804
OS -0.69847714 -38.53562524
OS -0.69108066 -38.53007788
OS -0.68275962 -38.52360596
OS -0.67258946 -38.5180586
OS -0.6624193 -38.51158668
OS -0.65040002 -38.50603932
OS -0.63745618 -38.50049196
OS -0.62358778 -38.49586916
OS -0.60879482 -38.49124636
OS -0.5930773 -38.48847268
OS -0.57643522 -38.48662356
OS -0.55886858 -38.485699
OS -0.54962298 -38.485699
OS -0.54315106 -38.48662356
OE
OB -1.47695666 -38.48662356 I
OS -1.46308826 -38.48754812
OS -1.44737074 -38.48939724
OS -1.43165322 -38.49217092
OS -1.4159357 -38.49586916
OS -1.40114274 -38.50049196
OS -1.39929362 -38.50141652
OS -1.39467082 -38.50326564
OS -1.3881989 -38.50603932
OS -1.37987786 -38.50973756
OS -1.37063226 -38.51528492
OS -1.36138666 -38.52083228
OS -1.35306562 -38.52822876
OS -1.34566914 -38.53562524
OS -1.34474458 -38.5365498
OS -1.34289546 -38.53932348
OS -1.34012178 -38.54394628
OS -1.33642354 -38.54949364
OS -1.33180074 -38.55781468
OS -1.3281025 -38.56613572
OS -1.32440426 -38.57630588
OS -1.32163058 -38.58832516
OS -1.32163058 -38.58924972
OS -1.32070602 -38.5920234
OS -1.31978146 -38.59757076
OS -1.3188569 -38.60496724
OS -1.3188569 -38.6151374
OS -1.31793234 -38.62715668
OS -1.31700778 -38.6428742
OS -1.31700778 -38.66044084
OS -1.31700778 -38.76584068
OS -1.31700778 -38.76676524
OS -1.31700778 -38.77046348
OS -1.31700778 -38.77601084
OS -1.31700778 -38.78340732
OS -1.31700778 -38.79172836
OS -1.31700778 -38.80189852
OS -1.31608322 -38.82408796
OS -1.31608322 -38.84720196
OS -1.31515866 -38.87031596
OS -1.3142341 -38.88048612
OS -1.3142341 -38.88973172
OS -1.31330954 -38.89805276
OS -1.31238498 -38.90452468
OS -1.31238498 -38.90544924
OS -1.31146042 -38.90914748
OS -1.31053586 -38.91469484
OS -1.30776218 -38.92209132
OS -1.30591306 -38.93041236
OS -1.30221482 -38.93965796
OS -1.29759202 -38.94982812
OS -1.29296922 -38.95999828
OS -1.37525506 -38.95999828
OS -1.37617962 -38.95907372
OS -1.37710418 -38.95537548
OS -1.3789533 -38.95075268
OS -1.38172698 -38.9433562
OS -1.38450066 -38.93503516
OS -1.38634978 -38.924865
OS -1.3881989 -38.91377028
OS -1.39004802 -38.901751
OS -1.39097258 -38.901751
OS -1.39189714 -38.90360012
OS -1.3974445 -38.90822292
OS -1.40576554 -38.91469484
OS -1.41686026 -38.92301588
OS -1.43072866 -38.93133692
OS -1.44459706 -38.94058252
OS -1.45939002 -38.94890356
OS -1.47510754 -38.95537548
OS -1.47695666 -38.95630004
OS -1.48250402 -38.9572246
OS -1.49082506 -38.95999828
OS -1.50099522 -38.96277196
OS -1.51393906 -38.96554564
OS -1.52873202 -38.96739476
OS -1.5453741 -38.96924388
OS -1.56201618 -38.97016844
OS -1.56941266 -38.97016844
OS -1.57496002 -38.96924388
OS -1.58143194 -38.96924388
OS -1.58882842 -38.96831932
OS -1.6054705 -38.96554564
OS -1.6239617 -38.96092284
OS -1.64430202 -38.95445092
OS -1.66279322 -38.94520532
OS -1.6794353 -38.93318604
OS -1.68128442 -38.93133692
OS -1.68590722 -38.92671412
OS -1.69237914 -38.91839308
OS -1.69977562 -38.90729836
OS -1.7071721 -38.89342996
OS -1.71364402 -38.87771244
OS -1.71826682 -38.85829668
OS -1.71919138 -38.84905108
OS -1.72011594 -38.83795636
OS -1.72011594 -38.83610724
OS -1.72011594 -38.832409
OS -1.71919138 -38.82593708
OS -1.71826682 -38.81761604
OS -1.7164177 -38.80744588
OS -1.71364402 -38.79727572
OS -1.70994578 -38.786181
OS -1.70532298 -38.77601084
OS -1.70439842 -38.77508628
OS -1.7025493 -38.77138804
OS -1.69885106 -38.76584068
OS -1.69422826 -38.75936876
OS -1.6886809 -38.75197228
OS -1.68128442 -38.7445758
OS -1.67388794 -38.73717932
OS -1.66464234 -38.7307074
OS -1.66371778 -38.72978284
OS -1.66001954 -38.72793372
OS -1.65539674 -38.72423548
OS -1.64800026 -38.72053724
OS -1.63967922 -38.716839
OS -1.62950906 -38.7122162
OS -1.6193389 -38.70851796
OS -1.60731962 -38.70481972
OS -1.60639506 -38.70481972
OS -1.60269682 -38.70389516
OS -1.59714946 -38.70204604
OS -1.58975298 -38.70112148
OS -1.58050738 -38.69927236
OS -1.5684881 -38.69742324
OS -1.5546197 -38.69464956
OS -1.53797762 -38.69280044
OS -1.53705306 -38.69280044
OS -1.53335482 -38.69187588
OS -1.52873202 -38.69187588
OS -1.5222601 -38.69095132
OS -1.51486362 -38.69002676
OS -1.50561802 -38.68817764
OS -1.49544786 -38.68725308
OS -1.48435314 -38.68540396
OS -1.4621637 -38.68078116
OS -1.43812514 -38.67615836
OS -1.41686026 -38.670611
OS -1.4066901 -38.66783732
OS -1.3974445 -38.66506364
OS -1.3974445 -38.66413908
OS -1.3974445 -38.66228996
OS -1.39651994 -38.6567426
OS -1.39651994 -38.65027068
OS -1.39651994 -38.64657244
OS -1.39651994 -38.64472332
OS -1.39651994 -38.64379876
OS -1.39651994 -38.6428742
OS -1.39651994 -38.63732684
OS -1.3974445 -38.62808124
OS -1.39929362 -38.61791108
OS -1.4020673 -38.60681636
OS -1.4066901 -38.59572164
OS -1.41223746 -38.58555148
OS -1.41963394 -38.57723044
OS -1.4205585 -38.57630588
OS -1.4251813 -38.57260764
OS -1.43257778 -38.5689094
OS -1.44182338 -38.56336204
OS -1.45476722 -38.55873924
OS -1.46956018 -38.55411644
OS -1.48805138 -38.55134276
OS -1.50931626 -38.5504182
OS -1.51856186 -38.5504182
OS -1.52780746 -38.55134276
OS -1.5407513 -38.55319188
OS -1.55369514 -38.555041
OS -1.56756354 -38.55873924
OS -1.58050738 -38.56336204
OS -1.5916021 -38.56983396
OS -1.59252666 -38.57075852
OS -1.5962249 -38.5735322
OS -1.6008477 -38.578155
OS -1.60639506 -38.58555148
OS -1.61194242 -38.59479708
OS -1.61841434 -38.60681636
OS -1.6239617 -38.62160932
OS -1.62950906 -38.6382514
OS -1.70624754 -38.62808124
OS -1.70624754 -38.62715668
OS -1.70532298 -38.62623212
OS -1.70532298 -38.62345844
OS -1.70439842 -38.6197602
OS -1.70162474 -38.61143916
OS -1.6979265 -38.59941988
OS -1.6933037 -38.5874006
OS -1.68775634 -38.57445676
OS -1.68035986 -38.56151292
OS -1.67203882 -38.54949364
OS -1.67111426 -38.54856908
OS -1.66741602 -38.54487084
OS -1.66186866 -38.53932348
OS -1.65447218 -38.531927
OS -1.64430202 -38.52453052
OS -1.63228274 -38.51713404
OS -1.61841434 -38.508813
OS -1.60269682 -38.50234108
OS -1.60177226 -38.50234108
OS -1.6008477 -38.50141652
OS -1.59807402 -38.50049196
OS -1.59437578 -38.4995674
OS -1.58513018 -38.49679372
OS -1.57218634 -38.49402004
OS -1.55739338 -38.49124636
OS -1.53890218 -38.48847268
OS -1.51948642 -38.48662356
OS -1.49729698 -38.485699
OS -1.48712682 -38.485699
OS -1.47695666 -38.48662356
OE
OB 0.11698478 -38.42745172 I
OS 0.0957199 -38.54671996
OS 0.04671822 -38.54671996
OS 0.02730246 -38.42745172
OS 0.02730246 -38.32020276
OS 0.11698478 -38.32020276
OS 0.11698478 -38.42745172
OE
OB -5.4655085 -38.31835364 I
OS -5.45348922 -38.32020276
OS -5.43962082 -38.32297644
OS -5.42482786 -38.32667468
OS -5.40911034 -38.33129748
OS -5.39431738 -38.33869396
OS -5.39339282 -38.33869396
OS -5.39246826 -38.33961852
OS -5.38784546 -38.3423922
OS -5.38044898 -38.347015
OS -5.37120338 -38.35348692
OS -5.36103322 -38.36273252
OS -5.3499385 -38.37290268
OS -5.33976834 -38.38492196
OS -5.32959818 -38.39879036
OS -5.32867362 -38.40063948
OS -5.32497538 -38.40526228
OS -5.32127714 -38.41358332
OS -5.31480522 -38.4256026
OS -5.30925786 -38.439471
OS -5.30186138 -38.45518852
OS -5.29538946 -38.47367972
OS -5.2898421 -38.49402004
OS -5.2898421 -38.4949446
OS -5.28891754 -38.49679372
OS -5.28799298 -38.4995674
OS -5.28706842 -38.5041902
OS -5.28614386 -38.50973756
OS -5.2852193 -38.51620948
OS -5.28337018 -38.52453052
OS -5.28244562 -38.53377612
OS -5.2805965 -38.54394628
OS -5.27967194 -38.555041
OS -5.27874738 -38.56798484
OS -5.27689826 -38.58092868
OS -5.2759737 -38.59572164
OS -5.2759737 -38.6105146
OS -5.27504914 -38.62715668
OS -5.27504914 -38.64472332
OS -5.27504914 -38.64564788
OS -5.27504914 -38.64934612
OS -5.27504914 -38.65581804
OS -5.27504914 -38.66321452
OS -5.2759737 -38.67338468
OS -5.2759737 -38.6844794
OS -5.27689826 -38.69649868
OS -5.27782282 -38.70944252
OS -5.2805965 -38.73902844
OS -5.2852193 -38.76953892
OS -5.29076666 -38.79912484
OS -5.2944649 -38.81299324
OS -5.2990877 -38.82686164
OS -5.2990877 -38.8277862
OS -5.30001226 -38.82963532
OS -5.30186138 -38.83333356
OS -5.3037105 -38.83795636
OS -5.30555962 -38.84442828
OS -5.30925786 -38.8509002
OS -5.31665434 -38.86661772
OS -5.32589994 -38.8832598
OS -5.33791922 -38.901751
OS -5.35178762 -38.91839308
OS -5.3684297 -38.9341106
OS -5.36935426 -38.9341106
OS -5.37027882 -38.93595972
OS -5.3730525 -38.93780884
OS -5.37675074 -38.93965796
OS -5.38137354 -38.94243164
OS -5.38599634 -38.94612988
OS -5.39986474 -38.9526018
OS -5.41650682 -38.95907372
OS -5.43592258 -38.96554564
OS -5.45903658 -38.96924388
OS -5.4839997 -38.971093
OS -5.4932453 -38.971093
OS -5.49971722 -38.97016844
OS -5.5071137 -38.96924388
OS -5.5163593 -38.96739476
OS -5.52652946 -38.96554564
OS -5.53762418 -38.96277196
OS -5.5487189 -38.95907372
OS -5.56073818 -38.95537548
OS -5.57275746 -38.94982812
OS -5.58477674 -38.9433562
OS -5.59679602 -38.93595972
OS -5.6088153 -38.92671412
OS -5.61991002 -38.91654396
OS -5.63008018 -38.90544924
OS -5.63100474 -38.90452468
OS -5.63285386 -38.901751
OS -5.63562754 -38.8971282
OS -5.64025034 -38.88973172
OS -5.64487314 -38.88141068
OS -5.64949594 -38.87031596
OS -5.65596786 -38.85737212
OS -5.66151522 -38.84257916
OS -5.66706258 -38.82593708
OS -5.67260994 -38.80652132
OS -5.6781573 -38.78525644
OS -5.6827801 -38.76121788
OS -5.6874029 -38.7353302
OS -5.69017658 -38.7075934
OS -5.6920257 -38.67708292
OS -5.69295026 -38.64472332
OS -5.69295026 -38.64379876
OS -5.69295026 -38.64010052
OS -5.69295026 -38.6336286
OS -5.69295026 -38.62623212
OS -5.6920257 -38.61606196
OS -5.6920257 -38.60496724
OS -5.69110114 -38.59294796
OS -5.69017658 -38.57907956
OS -5.6874029 -38.5504182
OS -5.6827801 -38.51990772
OS -5.67723274 -38.48939724
OS -5.6735345 -38.47552884
OS -5.66983626 -38.46166044
OS -5.66983626 -38.46073588
OS -5.6689117 -38.45888676
OS -5.66706258 -38.45518852
OS -5.66521346 -38.45056572
OS -5.66336434 -38.4440938
OS -5.6596661 -38.43762188
OS -5.65226962 -38.42190436
OS -5.64302402 -38.40526228
OS -5.63100474 -38.38769564
OS -5.61713634 -38.370129
OS -5.60049426 -38.35533604
OS -5.5995697 -38.35533604
OS -5.59864514 -38.35348692
OS -5.59587146 -38.3516378
OS -5.59217322 -38.34978868
OS -5.58755042 -38.34609044
OS -5.58200306 -38.34331676
OS -5.56813466 -38.33592028
OS -5.55149258 -38.32944836
OS -5.53207682 -38.32297644
OS -5.50896282 -38.3192782
OS -5.4839997 -38.31742908
OS -5.47567866 -38.31742908
OS -5.4655085 -38.31835364
OE
OB -5.79280274 -38.95999828 I
OS -5.87139034 -38.95999828
OS -5.87139034 -38.32020276
OS -5.79280274 -38.32020276
OS -5.79280274 -38.95999828
OE
OB -5.97031826 -38.42745172 I
OS -5.99158314 -38.54671996
OS -6.04058482 -38.54671996
OS -6.06000058 -38.42745172
OS -6.06000058 -38.32020276
OS -5.97031826 -38.32020276
OS -5.97031826 -38.42745172
OE
OB -4.96809522 -38.31835364 I
OS -4.96069874 -38.3192782
OS -4.95145314 -38.32020276
OS -4.94128298 -38.32205188
OS -4.93111282 -38.323901
OS -4.90707426 -38.33037292
OS -4.8830357 -38.33961852
OS -4.87101642 -38.34516588
OS -4.85899714 -38.3516378
OS -4.84790242 -38.35995884
OS -4.83773226 -38.36920444
OS -4.8368077 -38.370129
OS -4.83495858 -38.37105356
OS -4.83310946 -38.3747518
OS -4.82941122 -38.37845004
OS -4.82478842 -38.38307284
OS -4.82016562 -38.38954476
OS -4.81554282 -38.39601668
OS -4.80999546 -38.40433772
OS -4.80074986 -38.42190436
OS -4.79150426 -38.4440938
OS -4.78780602 -38.45518852
OS -4.7859569 -38.46813236
OS -4.78410778 -38.4810762
OS -4.78318322 -38.4949446
OS -4.78318322 -38.49679372
OS -4.78318322 -38.50141652
OS -4.78410778 -38.508813
OS -4.78503234 -38.51898316
OS -4.78688146 -38.53007788
OS -4.7905797 -38.54302172
OS -4.79427794 -38.55689012
OS -4.7998253 -38.57075852
OS -4.80074986 -38.57260764
OS -4.80259898 -38.57723044
OS -4.80629722 -38.58462692
OS -4.81184458 -38.59479708
OS -4.81924106 -38.6058918
OS -4.82848666 -38.6197602
OS -4.83958138 -38.6336286
OS -4.85252522 -38.64934612
OS -4.85437434 -38.65119524
OS -4.85899714 -38.6567426
OS -4.86361994 -38.6613654
OS -4.86824274 -38.6659882
OS -4.8737901 -38.67153556
OS -4.88118658 -38.67893204
OS -4.88858306 -38.68632852
OS -4.89782866 -38.69464956
OS -4.90707426 -38.70389516
OS -4.91816898 -38.71406532
OS -4.93018826 -38.72423548
OS -4.9431321 -38.73625476
OS -4.95792506 -38.74827404
OS -4.97271802 -38.76121788
OS -4.97364258 -38.76214244
OS -4.9754917 -38.76399156
OS -4.97918994 -38.76676524
OS -4.98381274 -38.77046348
OS -4.9893601 -38.77601084
OS -4.99583202 -38.7815582
OS -5.01062498 -38.79357748
OS -5.0263425 -38.80744588
OS -5.04113546 -38.82131428
OS -5.0540793 -38.83333356
OS -5.05962666 -38.83795636
OS -5.06424946 -38.84257916
OS -5.06517402 -38.84350372
OS -5.0679477 -38.8462774
OS -5.07164594 -38.84997564
OS -5.07626874 -38.855523
OS -5.08089154 -38.86199492
OS -5.0864389 -38.86846684
OS -5.09753362 -38.88418436
OS -4.78225866 -38.88418436
OS -4.78225866 -38.95999828
OS -5.2066317 -38.95999828
OS -5.2066317 -38.95907372
OS -5.2066317 -38.95537548
OS -5.2066317 -38.94982812
OS -5.20570714 -38.94243164
OS -5.20478258 -38.9341106
OS -5.20293346 -38.924865
OS -5.20108434 -38.9156194
OS -5.1973861 -38.90544924
OS -5.1973861 -38.90452468
OS -5.19646154 -38.90360012
OS -5.19461242 -38.89805276
OS -5.19091418 -38.88973172
OS -5.18536682 -38.878637
OS -5.17797034 -38.86569316
OS -5.16872474 -38.8509002
OS -5.15855458 -38.83610724
OS -5.14561074 -38.82038972
OS -5.14561074 -38.81946516
OS -5.14376162 -38.8185406
OS -5.13913882 -38.81299324
OS -5.13081778 -38.8046722
OS -5.1187985 -38.79265292
OS -5.1049301 -38.77878452
OS -5.08736346 -38.76214244
OS -5.06609858 -38.74365124
OS -5.04298458 -38.72423548
OS -5.04206002 -38.72331092
OS -5.03836178 -38.72053724
OS -5.03281442 -38.71591444
OS -5.0263425 -38.71036708
OS -5.01802146 -38.7029706
OS -5.0078513 -38.69464956
OS -4.99768114 -38.68540396
OS -4.98566186 -38.6752338
OS -4.96254786 -38.65304436
OS -4.93943386 -38.63085492
OS -4.92833914 -38.6197602
OS -4.91816898 -38.60866548
OS -4.90892338 -38.59849532
OS -4.9015269 -38.58832516
OS -4.9015269 -38.5874006
OS -4.89967778 -38.58647604
OS -4.89782866 -38.58370236
OS -4.89597954 -38.58000412
OS -4.88950762 -38.56983396
OS -4.88211114 -38.55781468
OS -4.87563922 -38.54302172
OS -4.8691673 -38.5273042
OS -4.86546906 -38.50973756
OS -4.86361994 -38.49309548
OS -4.86361994 -38.49217092
OS -4.86361994 -38.49124636
OS -4.8645445 -38.485699
OS -4.86546906 -38.4764534
OS -4.86824274 -38.46628324
OS -4.87194098 -38.4533394
OS -4.8784129 -38.44039556
OS -4.88673394 -38.42745172
OS -4.89782866 -38.41450788
OS -4.89967778 -38.41265876
OS -4.90430058 -38.40896052
OS -4.9107725 -38.40433772
OS -4.92094266 -38.3978658
OS -4.9338865 -38.39231844
OS -4.94867946 -38.38677108
OS -4.9662461 -38.38307284
OS -4.98566186 -38.38214828
OS -4.99120922 -38.38214828
OS -4.99490746 -38.38307284
OS -5.00600218 -38.3839974
OS -5.01894602 -38.38677108
OS -5.03281442 -38.39046932
OS -5.04853194 -38.39694124
OS -5.0633249 -38.40526228
OS -5.0771933 -38.416357
OS -5.07904242 -38.41820612
OS -5.08274066 -38.42282892
OS -5.08828802 -38.4302254
OS -5.09383538 -38.44132012
OS -5.1003073 -38.45426396
OS -5.10585466 -38.47090604
OS -5.1095529 -38.48939724
OS -5.11140202 -38.51066212
OS -5.19183874 -38.50234108
OS -5.19183874 -38.50141652
OS -5.19091418 -38.49864284
OS -5.19091418 -38.49402004
OS -5.18998962 -38.48754812
OS -5.1881405 -38.48015164
OS -5.18629138 -38.4718306
OS -5.1835177 -38.46166044
OS -5.18074402 -38.45149028
OS -5.17334754 -38.42930084
OS -5.16225282 -38.4071114
OS -5.1557809 -38.39601668
OS -5.14745986 -38.38492196
OS -5.13913882 -38.3747518
OS -5.12989322 -38.3655062
OS -5.12896866 -38.36458164
OS -5.12711954 -38.36365708
OS -5.12434586 -38.3608834
OS -5.11972306 -38.35810972
OS -5.1141757 -38.35441148
OS -5.10770378 -38.35071324
OS -5.1003073 -38.34609044
OS -5.0910617 -38.34146764
OS -5.08089154 -38.33684484
OS -5.06979682 -38.33222204
OS -5.05777754 -38.3285238
OS -5.0448337 -38.32482556
OS -5.0309653 -38.32205188
OS -5.01617234 -38.3192782
OS -5.00045482 -38.31835364
OS -4.98381274 -38.31742908
OS -4.97456714 -38.31742908
OS -4.96809522 -38.31835364
OE
OB -4.29963834 -38.40988508 I
OS -4.37822594 -38.40988508
OS -4.37822594 -38.32020276
OS -4.29963834 -38.32020276
OS -4.29963834 -38.40988508
OE
OB -4.29963834 -38.95999828 I
OS -4.37822594 -38.95999828
OS -4.37822594 -38.49586916
OS -4.29963834 -38.49586916
OS -4.29963834 -38.95999828
OE
OB -4.46421002 -38.7676898 I
OS -4.7073693 -38.7676898
OS -4.7073693 -38.6891022
OS -4.46421002 -38.6891022
OS -4.46421002 -38.7676898
OE
OB -3.94738098 -38.48662356 I
OS -3.93721082 -38.48754812
OS -3.92519154 -38.48939724
OS -3.9122477 -38.49217092
OS -3.8983793 -38.49586916
OS -3.88543546 -38.50141652
OS -3.88358634 -38.50234108
OS -3.8798881 -38.5041902
OS -3.87341618 -38.50696388
OS -3.8660197 -38.51158668
OS -3.8567741 -38.51713404
OS -3.84845306 -38.52453052
OS -3.84013202 -38.531927
OS -3.83273554 -38.5411726
OS -3.83181098 -38.54209716
OS -3.82996186 -38.5457954
OS -3.82718818 -38.5504182
OS -3.82256538 -38.55689012
OS -3.81886714 -38.56613572
OS -3.8151689 -38.57538132
OS -3.8105461 -38.58647604
OS -3.80777242 -38.59849532
OS -3.80777242 -38.59941988
OS -3.80684786 -38.60311812
OS -3.8059233 -38.60866548
OS -3.80499874 -38.61606196
OS -3.80499874 -38.62715668
OS -3.80407418 -38.64010052
OS -3.80314962 -38.65581804
OS -3.80314962 -38.6752338
OS -3.80314962 -38.95999828
OS -3.88173722 -38.95999828
OS -3.88173722 -38.67893204
OS -3.88173722 -38.67800748
OS -3.88173722 -38.67708292
OS -3.88173722 -38.670611
OS -3.88173722 -38.66228996
OS -3.88266178 -38.6521198
OS -3.88358634 -38.64010052
OS -3.88543546 -38.62808124
OS -3.88820914 -38.61698652
OS -3.89098282 -38.60681636
OS -3.89098282 -38.6058918
OS -3.89283194 -38.60311812
OS -3.89560562 -38.59849532
OS -3.8983793 -38.59294796
OS -3.9030021 -38.5874006
OS -3.90854946 -38.58092868
OS -3.91594594 -38.57445676
OS -3.92426698 -38.5689094
OS -3.92519154 -38.56798484
OS -3.92796522 -38.56613572
OS -3.93351258 -38.5642866
OS -3.9399845 -38.56151292
OS -3.94738098 -38.55873924
OS -3.95662658 -38.55596556
OS -3.9677213 -38.555041
OS -3.97881602 -38.55411644
OS -3.98343882 -38.55411644
OS -3.98713706 -38.555041
OS -3.99638266 -38.55596556
OS -4.00840194 -38.55781468
OS -4.02134578 -38.56243748
OS -4.03613874 -38.56798484
OS -4.0509317 -38.57538132
OS -4.0648001 -38.58647604
OS -4.06664922 -38.58832516
OS -4.07034746 -38.59294796
OS -4.07312114 -38.5966462
OS -4.07589482 -38.601269
OS -4.07959306 -38.60681636
OS -4.08236674 -38.61328828
OS -4.08606498 -38.62068476
OS -4.08976322 -38.62993036
OS -4.0925369 -38.64010052
OS -4.09531058 -38.65119524
OS -4.0971597 -38.66321452
OS -4.09900882 -38.67615836
OS -4.10085794 -38.69187588
OS -4.10085794 -38.7075934
OS -4.10085794 -38.95999828
OS -4.17944554 -38.95999828
OS -4.17944554 -38.49586916
OS -4.10917898 -38.49586916
OS -4.10917898 -38.56243748
OS -4.10825442 -38.56151292
OS -4.1064053 -38.55873924
OS -4.10363162 -38.555041
OS -4.09993338 -38.5504182
OS -4.09438602 -38.54487084
OS -4.0879141 -38.53839892
OS -4.08051762 -38.53100244
OS -4.07127202 -38.52360596
OS -4.06202642 -38.51713404
OS -4.0509317 -38.50973756
OS -4.03891242 -38.50326564
OS -4.02596858 -38.49771828
OS -4.01117562 -38.49309548
OS -3.99638266 -38.48939724
OS -3.97974058 -38.48662356
OS -3.96217394 -38.485699
OS -3.95477746 -38.485699
OS -3.94738098 -38.48662356
OE
OB -0.55794402 -38.5504182 H
OS -0.56349138 -38.5504182
OS -0.56718962 -38.55134276
OS -0.57735978 -38.55226732
OS -0.58937906 -38.555041
OS -0.60417202 -38.5596638
OS -0.61988954 -38.56613572
OS -0.6346825 -38.57538132
OS -0.64947546 -38.5874006
OS -0.65132458 -38.58924972
OS -0.65502282 -38.59387252
OS -0.66149474 -38.60219356
OS -0.66796666 -38.61328828
OS -0.67536314 -38.62623212
OS -0.68183506 -38.6428742
OS -0.68738242 -38.66228996
OS -0.6901561 -38.68355484
OS -0.43035474 -38.68355484
OS -0.43035474 -38.68263028
OS -0.43035474 -38.68078116
OS -0.4312793 -38.67800748
OS -0.4312793 -38.67430924
OS -0.43312842 -38.66321452
OS -0.4359021 -38.65119524
OS -0.4405249 -38.63640228
OS -0.4451477 -38.62253388
OS -0.45254418 -38.60866548
OS -0.46086522 -38.5966462
OS -0.46086522 -38.59572164
OS -0.46271434 -38.59479708
OS -0.46733714 -38.58924972
OS -0.47565818 -38.58185324
OS -0.4867529 -38.5735322
OS -0.5006213 -38.56521116
OS -0.51726338 -38.55781468
OS -0.53667914 -38.55226732
OS -0.5468493 -38.55134276
OS -0.55794402 -38.5504182
OE
OB -5.48492426 -38.38214828 H
OS -5.49047162 -38.38214828
OS -5.49416986 -38.38307284
OS -5.50434002 -38.38492196
OS -5.5163593 -38.38769564
OS -5.5302277 -38.393243
OS -5.54502066 -38.40156404
OS -5.55241714 -38.4071114
OS -5.55981362 -38.41265876
OS -5.56628554 -38.42005524
OS -5.57275746 -38.42837628
OS -5.57275746 -38.42930084
OS -5.57460658 -38.43114996
OS -5.5764557 -38.4348482
OS -5.57922938 -38.439471
OS -5.58200306 -38.44686748
OS -5.5857013 -38.45518852
OS -5.58847498 -38.46535868
OS -5.59217322 -38.47737796
OS -5.59587146 -38.49124636
OS -5.5995697 -38.50696388
OS -5.60326794 -38.52453052
OS -5.60604162 -38.54394628
OS -5.6088153 -38.56613572
OS -5.61066442 -38.59017428
OS -5.61158898 -38.61606196
OS -5.61251354 -38.64472332
OS -5.61251354 -38.64657244
OS -5.61251354 -38.65119524
OS -5.61251354 -38.65951628
OS -5.61158898 -38.670611
OS -5.61158898 -38.68263028
OS -5.61066442 -38.69742324
OS -5.60973986 -38.71314076
OS -5.60789074 -38.72978284
OS -5.60326794 -38.76584068
OS -5.60049426 -38.78340732
OS -5.59679602 -38.8000494
OS -5.59309778 -38.81576692
OS -5.58755042 -38.83055988
OS -5.58200306 -38.84350372
OS -5.57553114 -38.85459844
OS -5.57553114 -38.855523
OS -5.57368202 -38.85644756
OS -5.56905922 -38.86291948
OS -5.56073818 -38.87124052
OS -5.55056802 -38.88048612
OS -5.53669962 -38.88973172
OS -5.5209821 -38.89805276
OS -5.50341546 -38.90452468
OS -5.49416986 -38.90544924
OS -5.4839997 -38.9063738
OS -5.47845234 -38.9063738
OS -5.4747541 -38.90544924
OS -5.4655085 -38.90360012
OS -5.45256466 -38.89990188
OS -5.43869626 -38.89342996
OS -5.42297874 -38.88418436
OS -5.41558226 -38.878637
OS -5.40818578 -38.87124052
OS -5.4007893 -38.86384404
OS -5.39339282 -38.85459844
OS -5.39339282 -38.85367388
OS -5.3915437 -38.85182476
OS -5.38969458 -38.84905108
OS -5.38784546 -38.84442828
OS -5.38414722 -38.83795636
OS -5.38137354 -38.82963532
OS -5.3776753 -38.82038972
OS -5.37397706 -38.809295
OS -5.37120338 -38.7954266
OS -5.36750514 -38.78063364
OS -5.3638069 -38.763067
OS -5.36103322 -38.7445758
OS -5.3591841 -38.72238636
OS -5.35733498 -38.69927236
OS -5.35548586 -38.67338468
OS -5.35548586 -38.64472332
OS -5.35548586 -38.64379876
OS -5.35548586 -38.6428742
OS -5.35548586 -38.6382514
OS -5.35548586 -38.62993036
OS -5.35641042 -38.61883564
OS -5.35641042 -38.60681636
OS -5.35733498 -38.5920234
OS -5.35825954 -38.57630588
OS -5.36010866 -38.55873924
OS -5.36473146 -38.52360596
OS -5.36750514 -38.50603932
OS -5.37120338 -38.48939724
OS -5.37490162 -38.47367972
OS -5.38044898 -38.45888676
OS -5.38599634 -38.44594292
OS -5.39246826 -38.4348482
OS -5.39246826 -38.43392364
OS -5.39431738 -38.43299908
OS -5.3961665 -38.4302254
OS -5.39894018 -38.42652716
OS -5.40726122 -38.41820612
OS -5.41743138 -38.40803596
OS -5.43129978 -38.39879036
OS -5.4470173 -38.39046932
OS -5.45533834 -38.38677108
OS -5.46458394 -38.3839974
OS -5.4747541 -38.38307284
OS -5.48492426 -38.38214828
OE
OB -2.99415962 -38.5504182 H
OS -2.99970698 -38.5504182
OS -3.00340522 -38.55134276
OS -3.01357538 -38.55226732
OS -3.02559466 -38.555041
OS -3.04038762 -38.5596638
OS -3.05610514 -38.56613572
OS -3.0708981 -38.57538132
OS -3.08569106 -38.5874006
OS -3.08754018 -38.58924972
OS -3.09123842 -38.59387252
OS -3.09771034 -38.60219356
OS -3.10418226 -38.61328828
OS -3.11157874 -38.62623212
OS -3.11805066 -38.6428742
OS -3.12359802 -38.66228996
OS -3.1263717 -38.68355484
OS -2.86657034 -38.68355484
OS -2.86657034 -38.68263028
OS -2.86657034 -38.68078116
OS -2.8674949 -38.67800748
OS -2.8674949 -38.67430924
OS -2.86934402 -38.66321452
OS -2.8721177 -38.65119524
OS -2.8767405 -38.63640228
OS -2.8813633 -38.62253388
OS -2.88875978 -38.60866548
OS -2.89708082 -38.5966462
OS -2.89708082 -38.59572164
OS -2.89892994 -38.59479708
OS -2.90355274 -38.58924972
OS -2.91187378 -38.58185324
OS -2.9229685 -38.5735322
OS -2.9368369 -38.56521116
OS -2.95347898 -38.55781468
OS -2.97289474 -38.55226732
OS -2.9830649 -38.55134276
OS -2.99415962 -38.5504182
OE
OB -1.39651994 -38.72700916 H
OS -1.3974445 -38.72700916
OS -1.39836906 -38.72793372
OS -1.40114274 -38.72885828
OS -1.40484098 -38.72978284
OS -1.40946378 -38.73163196
OS -1.41501114 -38.73348108
OS -1.42148306 -38.7353302
OS -1.42887954 -38.73717932
OS -1.43720058 -38.739953
OS -1.44737074 -38.74180212
OS -1.4575409 -38.7445758
OS -1.46956018 -38.74734948
OS -1.48250402 -38.75012316
OS -1.49544786 -38.75289684
OS -1.51024082 -38.75474596
OS -1.52595834 -38.75751964
OS -1.52780746 -38.75751964
OS -1.53335482 -38.7584442
OS -1.54260042 -38.76029332
OS -1.55277058 -38.76214244
OS -1.5638653 -38.76399156
OS -1.57496002 -38.76676524
OS -1.58513018 -38.76953892
OS -1.59437578 -38.77323716
OS -1.59530034 -38.77323716
OS -1.59807402 -38.77508628
OS -1.60177226 -38.7769354
OS -1.6054705 -38.77970908
OS -1.61656522 -38.78710556
OS -1.62581082 -38.79820028
OS -1.62581082 -38.79912484
OS -1.62765994 -38.80097396
OS -1.6285845 -38.8046722
OS -1.63043362 -38.809295
OS -1.63228274 -38.81484236
OS -1.63413186 -38.82038972
OS -1.63505642 -38.8277862
OS -1.63598098 -38.83518268
OS -1.63598098 -38.83610724
OS -1.63598098 -38.84073004
OS -1.63505642 -38.8462774
OS -1.6332073 -38.85367388
OS -1.63043362 -38.86199492
OS -1.62581082 -38.87031596
OS -1.62026346 -38.87956156
OS -1.61286698 -38.8878826
OS -1.61194242 -38.88880716
OS -1.60824418 -38.89065628
OS -1.60269682 -38.89435452
OS -1.59530034 -38.89805276
OS -1.58513018 -38.901751
OS -1.5731109 -38.90544924
OS -1.5592425 -38.90729836
OS -1.54260042 -38.90822292
OS -1.53520394 -38.90822292
OS -1.52595834 -38.90729836
OS -1.51578818 -38.90544924
OS -1.50284434 -38.90360012
OS -1.4899005 -38.89990188
OS -1.4760321 -38.89527908
OS -1.4621637 -38.88880716
OS -1.46031458 -38.8878826
OS -1.45661634 -38.88510892
OS -1.45014442 -38.88048612
OS -1.44274794 -38.8740142
OS -1.4344269 -38.86661772
OS -1.4251813 -38.85737212
OS -1.41778482 -38.8462774
OS -1.41038834 -38.83425812
OS -1.40946378 -38.83333356
OS -1.40853922 -38.82963532
OS -1.4066901 -38.8231634
OS -1.40391642 -38.81484236
OS -1.40114274 -38.80374764
OS -1.39929362 -38.7908038
OS -1.39836906 -38.77508628
OS -1.3974445 -38.75659508
OS -1.39651994 -38.72700916
OE
SE
S P 0
OB -4.66714078 -36.5016923 I
OS -4.65465922 -36.5016923
OS -4.62553558 -36.50307914
OS -4.5950251 -36.50723966
OS -4.56174094 -36.51140018
OS -4.53123046 -36.51833438
OS -4.51597522 -36.5224949
OS -4.50349366 -36.52665542
OS -4.50210682 -36.52665542
OS -4.50071998 -36.52804226
OS -4.49239894 -36.53220278
OS -4.47991738 -36.53775014
OS -4.46466214 -36.54745802
OS -4.44802006 -36.55993958
OS -4.42999114 -36.57658166
OS -4.41334906 -36.59599742
OS -4.39670698 -36.61818686
OS -4.39670698 -36.6195737
OS -4.39532014 -36.62096054
OS -4.38977278 -36.62928158
OS -4.38422542 -36.64314998
OS -4.37590438 -36.6611789
OS -4.36897018 -36.6819815
OS -4.36203598 -36.70694462
OS -4.35787546 -36.73329458
OS -4.35648862 -36.76241822
OS -4.35648862 -36.76380506
OS -4.35648862 -36.76657874
OS -4.35648862 -36.7721261
OS -4.35787546 -36.7790603
OS -4.35787546 -36.78876818
OS -4.3592623 -36.79847606
OS -4.36480966 -36.82205234
OS -4.3731307 -36.84978914
OS -4.38422542 -36.87891278
OS -4.4008675 -36.90803642
OS -4.41196222 -36.92190482
OS -4.42305694 -36.93577322
OS -4.42444378 -36.93716006
OS -4.42583062 -36.9385469
OS -4.42999114 -36.94270742
OS -4.4355385 -36.94686794
OS -4.4424727 -36.9524153
OS -4.45079374 -36.95796266
OS -4.46188846 -36.96489686
OS -4.47298318 -36.9732179
OS -4.48685158 -36.9801521
OS -4.50210682 -36.9870863
OS -4.5187489 -36.99540734
OS -4.53677782 -37.00234154
OS -4.55758042 -37.0078889
OS -4.57838302 -37.0148231
OS -4.6019593 -37.01898362
OS -4.62692242 -37.02314414
OS -4.62414874 -37.02453098
OS -4.61860138 -37.02730466
OS -4.61028034 -37.03285202
OS -4.59918562 -37.03839938
OS -4.5742225 -37.05365462
OS -4.56174094 -37.0633625
OS -4.55064622 -37.07168354
OS -4.54787254 -37.07445722
OS -4.54093834 -37.08139142
OS -4.52984362 -37.09248614
OS -4.51597522 -37.10635454
OS -4.50071998 -37.1257703
OS -4.48269106 -37.1465729
OS -4.46466214 -37.17153602
OS -4.44524638 -37.19927282
OS -4.28021242 -37.45999874
OS -4.43831218 -37.45999874
OS -4.56451462 -37.26029378
OS -4.56451462 -37.25890694
OS -4.5672883 -37.25613326
OS -4.57006198 -37.25197274
OS -4.5742225 -37.24642538
OS -4.58393038 -37.23117014
OS -4.59641194 -37.21175438
OS -4.61166718 -37.19095178
OS -4.62692242 -37.16876234
OS -4.64217766 -37.14795974
OS -4.65604606 -37.12854398
OS -4.6574329 -37.12715714
OS -4.66159342 -37.12160978
OS -4.66852762 -37.11328874
OS -4.6782355 -37.10358086
OS -4.6990381 -37.08277826
OS -4.71013282 -37.07307038
OS -4.72122754 -37.06474934
OS -4.72261438 -37.0633625
OS -4.72538806 -37.06197566
OS -4.73093542 -37.05920198
OS -4.73925646 -37.05504146
OS -4.7475775 -37.05088094
OS -4.75728538 -37.04672042
OS -4.77947482 -37.03978622
OS -4.78086166 -37.03978622
OS -4.78363534 -37.03839938
OS -4.7891827 -37.03839938
OS -4.7961169 -37.03701254
OS -4.80582478 -37.0356257
OS -4.8169195 -37.0356257
OS -4.83217474 -37.03423886
OS -4.99582186 -37.03423886
OS -4.99582186 -37.45999874
OS -5.12341114 -37.45999874
OS -5.12341114 -36.50030546
OS -4.6782355 -36.50030546
OS -4.66714078 -36.5016923
OE
OB -1.0100437 -37.45999874 I
OS -1.13208562 -37.45999874
OS -1.13208562 -36.65701838
OS -1.4122273 -37.45999874
OS -1.52594818 -37.45999874
OS -1.80331618 -36.64314998
OS -1.80331618 -37.45999874
OS -1.9253581 -37.45999874
OS -1.9253581 -36.50030546
OS -1.73536102 -36.50030546
OS -1.50791926 -37.1812439
OS -1.50791926 -37.18263074
OS -1.50653242 -37.18540442
OS -1.50514558 -37.18956494
OS -1.5023719 -37.19649914
OS -1.49682454 -37.21314122
OS -1.48989034 -37.23394382
OS -1.48295614 -37.2575201
OS -1.4746351 -37.28109638
OS -1.4677009 -37.30328582
OS -1.46215354 -37.32270158
OS -1.4607667 -37.3199279
OS -1.45937986 -37.3129937
OS -1.45521934 -37.30051214
OS -1.44967198 -37.28387006
OS -1.44273778 -37.26168062
OS -1.4330299 -37.23533066
OS -1.42332202 -37.20482018
OS -1.41084046 -37.16876234
OS -1.18062502 -36.50030546
OS -1.0100437 -36.50030546
OS -1.0100437 -37.45999874
OE
OB -2.02382374 -37.45999874 I
OS -2.1680551 -37.45999874
OS -2.28038914 -37.16876234
OS -2.68257274 -37.16876234
OS -2.78658574 -37.45999874
OS -2.92110922 -37.45999874
OS -2.55498346 -36.50030546
OS -2.41629946 -36.50030546
OS -2.02382374 -37.45999874
OE
OB -3.02928274 -37.45999874 I
OS -3.16103254 -37.45999874
OS -3.66306862 -36.70694462
OS -3.66306862 -37.45999874
OS -3.78511054 -37.45999874
OS -3.78511054 -36.50030546
OS -3.65474758 -36.50030546
OS -3.15132466 -37.25474642
OS -3.15132466 -36.50030546
OS -3.02928274 -36.50030546
OS -3.02928274 -37.45999874
OE
OB -5.3231161 -36.61402634 I
OS -5.89033366 -36.61402634
OS -5.89033366 -36.90664958
OS -5.35917394 -36.90664958
OS -5.35917394 -37.02037046
OS -5.89033366 -37.02037046
OS -5.89033366 -37.34627786
OS -5.30092666 -37.34627786
OS -5.30092666 -37.45999874
OS -6.01792294 -37.45999874
OS -6.01792294 -36.50030546
OS -5.3231161 -36.50030546
OS -5.3231161 -36.61402634
OE
OB -0.10721086 -36.61402634 I
OS -0.67442842 -36.61402634
OS -0.67442842 -36.90664958
OS -0.1432687 -36.90664958
OS -0.1432687 -37.02037046
OS -0.67442842 -37.02037046
OS -0.67442842 -37.34627786
OS -0.08502142 -37.34627786
OS -0.08502142 -37.45999874
OS -0.8020177 -37.45999874
OS -0.8020177 -36.50030546
OS -0.10721086 -36.50030546
OS -0.10721086 -36.61402634
OE
OB -8.43241138 -37.34627786 I
OS -7.95949894 -37.34627786
OS -7.95949894 -37.45999874
OS -8.56000066 -37.45999874
OS -8.56000066 -36.50030546
OS -8.43241138 -36.50030546
OS -8.43241138 -37.34627786
OE
OB -6.51718534 -37.05365462 I
OS -6.51718534 -37.45999874
OS -6.64477462 -37.45999874
OS -6.64477462 -37.05365462
OS -7.0150609 -36.50030546
OS -6.86112166 -36.50030546
OS -6.67251142 -36.79154186
OS -6.67251142 -36.7929287
OS -6.66973774 -36.79570238
OS -6.66696406 -36.7998629
OS -6.66419038 -36.80541026
OS -6.65864302 -36.81234446
OS -6.65309566 -36.8206655
OS -6.6406141 -36.8414681
OS -6.62535886 -36.86643122
OS -6.60871678 -36.89416802
OS -6.59068786 -36.92329166
OS -6.57404578 -36.95380214
OS -6.57404578 -36.9524153
OS -6.57265894 -36.94964162
OS -6.56988526 -36.9454811
OS -6.56572474 -36.93993374
OS -6.56156422 -36.93299954
OS -6.55601686 -36.9246785
OS -6.5435353 -36.9038759
OS -6.52828006 -36.87891278
OS -6.51025114 -36.84978914
OS -6.48944854 -36.81789182
OS -6.4672591 -36.78322082
OS -6.28280938 -36.50030546
OS -6.1344175 -36.50030546
OS -6.51718534 -37.05365462
OE
OB -7.01644774 -37.45999874 I
OS -7.1606791 -37.45999874
OS -7.27301314 -37.16876234
OS -7.67519674 -37.16876234
OS -7.77920974 -37.45999874
OS -7.91373322 -37.45999874
OS -7.54760746 -36.50030546
OS -7.40892346 -36.50030546
OS -7.01644774 -37.45999874
OE
OB -7.48103914 -36.60015794 H
OS -7.48103914 -36.60154478
OS -7.48242598 -36.60431846
OS -7.48242598 -36.60986582
OS -7.48519966 -36.61541318
OS -7.4865865 -36.62512106
OS -7.48936018 -36.63482894
OS -7.49490754 -36.65840522
OS -7.50184174 -36.68614202
OS -7.51154962 -36.7166525
OS -7.5212575 -36.74993666
OS -7.53373906 -36.78460766
OS -7.63775206 -37.06474934
OS -7.3132315 -37.06474934
OS -7.41308398 -36.80124974
OS -7.41308398 -36.7998629
OS -7.41447082 -36.79570238
OS -7.4172445 -36.78876818
OS -7.42001818 -36.78044714
OS -7.4241787 -36.77073926
OS -7.42833922 -36.7582577
OS -7.43249974 -36.7443893
OS -7.4380471 -36.7305209
OS -7.44914182 -36.69862358
OS -7.46023654 -36.66533942
OS -7.47133126 -36.63205526
OS -7.48103914 -36.60015794
OE
OB -4.69349074 -36.60709214 H
OS -4.99582186 -36.60709214
OS -4.99582186 -36.9246785
OS -4.71013282 -36.9246785
OS -4.69349074 -36.92329166
OS -4.67407498 -36.92190482
OS -4.65188554 -36.92051798
OS -4.6296961 -36.9177443
OS -4.60750666 -36.91358378
OS -4.5880909 -36.90803642
OS -4.58531722 -36.90664958
OS -4.57976986 -36.9038759
OS -4.57144882 -36.89971538
OS -4.5603541 -36.89416802
OS -4.54787254 -36.88584698
OS -4.53539098 -36.8761391
OS -4.52290942 -36.86365754
OS -4.51320154 -36.84978914
OS -4.5118147 -36.8484023
OS -4.50904102 -36.84285494
OS -4.5048805 -36.8345339
OS -4.49933314 -36.82343918
OS -4.49517262 -36.81095762
OS -4.4910121 -36.79708922
OS -4.48823842 -36.78044714
OS -4.48685158 -36.76380506
OS -4.48685158 -36.76241822
OS -4.48685158 -36.76103138
OS -4.48823842 -36.75271034
OS -4.48962526 -36.74022878
OS -4.49239894 -36.7235867
OS -4.49933314 -36.70694462
OS -4.50765418 -36.68752886
OS -4.52013574 -36.66949994
OS -4.53677782 -36.65147102
OS -4.5395515 -36.65008418
OS -4.5464857 -36.64453682
OS -4.55758042 -36.63760262
OS -4.57560934 -36.62928158
OS -4.59641194 -36.62096054
OS -4.62414874 -36.61402634
OS -4.65604606 -36.60847898
OS -4.69349074 -36.60709214
OE
OB -2.48841514 -36.60015794 H
OS -2.48841514 -36.60154478
OS -2.48980198 -36.60431846
OS -2.48980198 -36.60986582
OS -2.49257566 -36.61541318
OS -2.4939625 -36.62512106
OS -2.49673618 -36.63482894
OS -2.50228354 -36.65840522
OS -2.50921774 -36.68614202
OS -2.51892562 -36.7166525
OS -2.5286335 -36.74993666
OS -2.54111506 -36.78460766
OS -2.64512806 -37.06474934
OS -2.3206075 -37.06474934
OS -2.42045998 -36.80124974
OS -2.42045998 -36.7998629
OS -2.42184682 -36.79570238
OS -2.4246205 -36.78876818
OS -2.42739418 -36.78044714
OS -2.4315547 -36.77073926
OS -2.43571522 -36.7582577
OS -2.43987574 -36.7443893
OS -2.4454231 -36.7305209
OS -2.45651782 -36.69862358
OS -2.46761254 -36.66533942
OS -2.47870726 -36.63205526
OS -2.48841514 -36.60015794
OE
SE
S P 0
OB 35.73690338 -37.45999874 I
OS 35.61486146 -37.45999874
OS 35.61486146 -36.65701838
OS 35.33471978 -37.45999874
OS 35.2209989 -37.45999874
OS 34.9436309 -36.64314998
OS 34.9436309 -37.45999874
OS 34.82158898 -37.45999874
OS 34.82158898 -36.50030546
OS 35.01158606 -36.50030546
OS 35.23902782 -37.1812439
OS 35.23902782 -37.18263074
OS 35.24041466 -37.18540442
OS 35.2418015 -37.18956494
OS 35.24457518 -37.19649914
OS 35.25012254 -37.21314122
OS 35.25705674 -37.23394382
OS 35.26399094 -37.2575201
OS 35.27231198 -37.28109638
OS 35.27924618 -37.30328582
OS 35.28479354 -37.32270158
OS 35.28618038 -37.3199279
OS 35.28756722 -37.3129937
OS 35.29172774 -37.30051214
OS 35.2972751 -37.28387006
OS 35.3042093 -37.26168062
OS 35.31391718 -37.23533066
OS 35.32362506 -37.20482018
OS 35.33610662 -37.16876234
OS 35.56632206 -36.50030546
OS 35.73690338 -36.50030546
OS 35.73690338 -37.45999874
OE
OB 34.61356298 -37.05504146 I
OS 34.61356298 -37.0564283
OS 34.61356298 -37.06197566
OS 34.61356298 -37.06890986
OS 34.61356298 -37.07861774
OS 34.61217614 -37.0910993
OS 34.61217614 -37.1049677
OS 34.6107893 -37.12160978
OS 34.60940246 -37.13825186
OS 34.60524194 -37.17569654
OS 34.59969458 -37.21452806
OS 34.59137354 -37.25197274
OS 34.58582618 -37.27000166
OS 34.58027882 -37.28664374
OS 34.58027882 -37.28803058
OS 34.57889198 -37.29080426
OS 34.5761183 -37.29496478
OS 34.57334462 -37.30051214
OS 34.56502358 -37.31576738
OS 34.55254202 -37.33518314
OS 34.53589994 -37.35737258
OS 34.51648418 -37.37956202
OS 34.49152106 -37.4031383
OS 34.46101058 -37.4239409
OS 34.45962374 -37.4239409
OS 34.45685006 -37.42671458
OS 34.45268954 -37.42810142
OS 34.44575534 -37.43226194
OS 34.4374343 -37.43642246
OS 34.42633958 -37.44058298
OS 34.41524486 -37.4447435
OS 34.40137646 -37.45029086
OS 34.38612122 -37.45583822
OS 34.36947914 -37.45999874
OS 34.35145022 -37.46415926
OS 34.33064762 -37.46831978
OS 34.30984502 -37.47109346
OS 34.28765558 -37.47386714
OS 34.23772934 -37.47664082
OS 34.22524778 -37.47664082
OS 34.2155399 -37.47525398
OS 34.20444518 -37.47525398
OS 34.19057678 -37.47386714
OS 34.17532154 -37.4724803
OS 34.1600663 -37.47109346
OS 34.1253953 -37.4655461
OS 34.08795062 -37.45722506
OS 34.05189278 -37.44613034
OS 34.01722178 -37.4308751
OS 34.01583494 -37.4308751
OS 34.01306126 -37.42810142
OS 34.00890074 -37.42532774
OS 34.00335338 -37.42255406
OS 33.98809814 -37.41145934
OS 33.97006922 -37.3962041
OS 33.94926662 -37.37678834
OS 33.92985086 -37.3545989
OS 33.9104351 -37.3268621
OS 33.89517986 -37.29635162
OS 33.89517986 -37.29496478
OS 33.89379302 -37.2921911
OS 33.89240618 -37.28664374
OS 33.8896325 -37.27970954
OS 33.88685882 -37.2713885
OS 33.88408514 -37.26029378
OS 33.87992462 -37.24781222
OS 33.87715094 -37.23255698
OS 33.87437726 -37.2159149
OS 33.87021674 -37.19788598
OS 33.86744306 -37.17847022
OS 33.86466938 -37.15766762
OS 33.8618957 -37.13409134
OS 33.86050886 -37.10912822
OS 33.85912202 -37.08277826
OS 33.85912202 -37.05504146
OS 33.85912202 -36.50030546
OS 33.9867113 -36.50030546
OS 33.9867113 -37.05504146
OS 33.9867113 -37.0564283
OS 33.9867113 -37.06058882
OS 33.9867113 -37.06752302
OS 33.9867113 -37.07584406
OS 33.98809814 -37.08555194
OS 33.98809814 -37.0980335
OS 33.98948498 -37.12438346
OS 33.99225866 -37.15489394
OS 33.99641918 -37.18540442
OS 34.00196654 -37.21452806
OS 34.00474022 -37.22700962
OS 34.00890074 -37.23949118
OS 34.01028758 -37.24226486
OS 34.01306126 -37.24919906
OS 34.01999546 -37.25890694
OS 34.0283165 -37.27277534
OS 34.03802438 -37.28664374
OS 34.05189278 -37.30189898
OS 34.06853486 -37.31715422
OS 34.08795062 -37.32963578
OS 34.0907243 -37.33102262
OS 34.0976585 -37.33518314
OS 34.11014006 -37.33934366
OS 34.12678214 -37.34489102
OS 34.1461979 -37.35182522
OS 34.17116102 -37.35598574
OS 34.19751098 -37.36014626
OS 34.22663462 -37.3615331
OS 34.24050302 -37.3615331
OS 34.24882406 -37.36014626
OS 34.26130562 -37.36014626
OS 34.27378718 -37.35875942
OS 34.30429766 -37.35321206
OS 34.33758182 -37.34627786
OS 34.36947914 -37.33518314
OS 34.39998962 -37.3199279
OS 34.41385802 -37.31022002
OS 34.42633958 -37.2991253
OS 34.42772642 -37.29773846
OS 34.42911326 -37.29635162
OS 34.43188694 -37.2921911
OS 34.43604746 -37.28664374
OS 34.44020798 -37.2783227
OS 34.44575534 -37.27000166
OS 34.4513027 -37.2575201
OS 34.45685006 -37.24503854
OS 34.46239742 -37.2297833
OS 34.46655794 -37.21175438
OS 34.4721053 -37.19095178
OS 34.47626582 -37.16876234
OS 34.48042634 -37.14379922
OS 34.48320002 -37.11744926
OS 34.4859737 -37.08693878
OS 34.4859737 -37.05504146
OS 34.4859737 -36.50030546
OS 34.61356298 -36.50030546
OS 34.61356298 -37.05504146
OE
OB 33.64416182 -37.45999874 I
OS 33.51241202 -37.45999874
OS 33.01037594 -36.70694462
OS 33.01037594 -37.45999874
OS 32.88833402 -37.45999874
OS 32.88833402 -36.50030546
OS 33.01869698 -36.50030546
OS 33.5221199 -37.25474642
OS 33.5221199 -36.50030546
OS 33.64416182 -36.50030546
OS 33.64416182 -37.45999874
OE
OB 38.19022334 -36.5016923 I
OS 38.2027049 -36.5016923
OS 38.23182854 -36.50307914
OS 38.26233902 -36.50723966
OS 38.29562318 -36.51140018
OS 38.32613366 -36.51833438
OS 38.3413889 -36.5224949
OS 38.35387046 -36.52665542
OS 38.3552573 -36.52665542
OS 38.35664414 -36.52804226
OS 38.36496518 -36.53220278
OS 38.37744674 -36.53775014
OS 38.39270198 -36.54745802
OS 38.40934406 -36.55993958
OS 38.42737298 -36.57658166
OS 38.44401506 -36.59599742
OS 38.46065714 -36.61818686
OS 38.46065714 -36.6195737
OS 38.46204398 -36.62096054
OS 38.46759134 -36.62928158
OS 38.4731387 -36.64314998
OS 38.48145974 -36.6611789
OS 38.48839394 -36.6819815
OS 38.49532814 -36.70694462
OS 38.49948866 -36.73329458
OS 38.5008755 -36.76241822
OS 38.5008755 -36.76380506
OS 38.5008755 -36.76657874
OS 38.5008755 -36.7721261
OS 38.49948866 -36.7790603
OS 38.49948866 -36.78876818
OS 38.49810182 -36.79847606
OS 38.49255446 -36.82205234
OS 38.48423342 -36.84978914
OS 38.4731387 -36.87891278
OS 38.45649662 -36.90803642
OS 38.4454019 -36.92190482
OS 38.43430718 -36.93577322
OS 38.43292034 -36.93716006
OS 38.4315335 -36.9385469
OS 38.42737298 -36.94270742
OS 38.42182562 -36.94686794
OS 38.41489142 -36.9524153
OS 38.40657038 -36.95796266
OS 38.39547566 -36.96489686
OS 38.38438094 -36.9732179
OS 38.37051254 -36.9801521
OS 38.3552573 -36.9870863
OS 38.33861522 -36.99540734
OS 38.3205863 -37.00234154
OS 38.2997837 -37.0078889
OS 38.2789811 -37.0148231
OS 38.25540482 -37.01898362
OS 38.2304417 -37.02314414
OS 38.23321538 -37.02453098
OS 38.23876274 -37.02730466
OS 38.24708378 -37.03285202
OS 38.2581785 -37.03839938
OS 38.28314162 -37.05365462
OS 38.29562318 -37.0633625
OS 38.3067179 -37.07168354
OS 38.30949158 -37.07445722
OS 38.31642578 -37.08139142
OS 38.3275205 -37.09248614
OS 38.3413889 -37.10635454
OS 38.35664414 -37.1257703
OS 38.37467306 -37.1465729
OS 38.39270198 -37.17153602
OS 38.41211774 -37.19927282
OS 38.5771517 -37.45999874
OS 38.41905194 -37.45999874
OS 38.2928495 -37.26029378
OS 38.2928495 -37.25890694
OS 38.29007582 -37.25613326
OS 38.28730214 -37.25197274
OS 38.28314162 -37.24642538
OS 38.27343374 -37.23117014
OS 38.26095218 -37.21175438
OS 38.24569694 -37.19095178
OS 38.2304417 -37.16876234
OS 38.21518646 -37.14795974
OS 38.20131806 -37.12854398
OS 38.19993122 -37.12715714
OS 38.1957707 -37.12160978
OS 38.1888365 -37.11328874
OS 38.17912862 -37.10358086
OS 38.15832602 -37.08277826
OS 38.1472313 -37.07307038
OS 38.13613658 -37.06474934
OS 38.13474974 -37.0633625
OS 38.13197606 -37.06197566
OS 38.1264287 -37.05920198
OS 38.11810766 -37.05504146
OS 38.10978662 -37.05088094
OS 38.10007874 -37.04672042
OS 38.0778893 -37.03978622
OS 38.07650246 -37.03978622
OS 38.07372878 -37.03839938
OS 38.06818142 -37.03839938
OS 38.06124722 -37.03701254
OS 38.05153934 -37.0356257
OS 38.04044462 -37.0356257
OS 38.02518938 -37.03423886
OS 37.86154226 -37.03423886
OS 37.86154226 -37.45999874
OS 37.73395298 -37.45999874
OS 37.73395298 -36.50030546
OS 38.17912862 -36.50030546
OS 38.19022334 -36.5016923
OE
OB 37.53424802 -36.61402634 I
OS 36.96703046 -36.61402634
OS 36.96703046 -36.90664958
OS 37.49819018 -36.90664958
OS 37.49819018 -37.02037046
OS 36.96703046 -37.02037046
OS 36.96703046 -37.34627786
OS 37.55643746 -37.34627786
OS 37.55643746 -37.45999874
OS 36.83944118 -37.45999874
OS 36.83944118 -36.50030546
OS 37.53424802 -36.50030546
OS 37.53424802 -36.61402634
OE
OB 36.32492354 -36.5016923 I
OS 36.33601826 -36.5016923
OS 36.36098138 -36.50446598
OS 36.38871818 -36.50723966
OS 36.41784182 -36.51278702
OS 36.44696546 -36.51972122
OS 36.47331542 -36.5294291
OS 36.47470226 -36.5294291
OS 36.4760891 -36.53081594
OS 36.48441014 -36.53497646
OS 36.4968917 -36.54191066
OS 36.5107601 -36.55161854
OS 36.52740218 -36.5641001
OS 36.5454311 -36.57935534
OS 36.56207318 -36.5987711
OS 36.57732842 -36.6195737
OS 36.57871526 -36.62234738
OS 36.58287578 -36.63066842
OS 36.58980998 -36.64176314
OS 36.59674418 -36.65840522
OS 36.60367838 -36.67782098
OS 36.61061258 -36.69862358
OS 36.6147731 -36.72219986
OS 36.61615994 -36.74577614
OS 36.61615994 -36.74854982
OS 36.61615994 -36.75548402
OS 36.6147731 -36.76796558
OS 36.61199942 -36.78322082
OS 36.6078389 -36.80124974
OS 36.6009047 -36.8206655
OS 36.59258366 -36.84008126
OS 36.58148894 -36.86088386
OS 36.5801021 -36.86365754
OS 36.57594158 -36.8692049
OS 36.56762054 -36.88029962
OS 36.55652582 -36.89139434
OS 36.54265742 -36.90526274
OS 36.52601534 -36.92051798
OS 36.50521274 -36.93438638
OS 36.48163646 -36.94825478
OS 36.4830233 -36.94825478
OS 36.48579698 -36.94964162
OS 36.4899575 -36.95102846
OS 36.49550486 -36.95380214
OS 36.51214694 -36.9593495
OS 36.5315627 -36.96905738
OS 36.5523653 -36.98153894
OS 36.57594158 -36.99679418
OS 36.59674418 -37.0148231
OS 36.61615994 -37.03701254
OS 36.61754678 -37.03978622
OS 36.62309414 -37.04810726
OS 36.63141518 -37.06058882
OS 36.63973622 -37.0772309
OS 36.64805726 -37.09942034
OS 36.6563783 -37.12299662
OS 36.66192566 -37.15073342
OS 36.6633125 -37.1812439
OS 36.6633125 -37.18263074
OS 36.6633125 -37.18401758
OS 36.6633125 -37.19233862
OS 36.66192566 -37.20620702
OS 36.65915198 -37.2228491
OS 36.6563783 -37.24226486
OS 36.65083094 -37.26306746
OS 36.64389674 -37.2852569
OS 36.63418886 -37.30744634
OS 36.63280202 -37.31022002
OS 36.6286415 -37.31715422
OS 36.62309414 -37.3268621
OS 36.6147731 -37.3407305
OS 36.60367838 -37.3545989
OS 36.59258366 -37.36985414
OS 36.57871526 -37.38510938
OS 36.56346002 -37.39759094
OS 36.56207318 -37.39897778
OS 36.55652582 -37.4031383
OS 36.54681794 -37.40868566
OS 36.53433638 -37.41423302
OS 36.51908114 -37.42255406
OS 36.50105222 -37.4308751
OS 36.48163646 -37.4378093
OS 36.45806018 -37.4447435
OS 36.4552865 -37.4447435
OS 36.44696546 -37.44751718
OS 36.43309706 -37.44890402
OS 36.41506814 -37.4516777
OS 36.3928787 -37.45445138
OS 36.36652874 -37.45722506
OS 36.3374051 -37.4586119
OS 36.30412094 -37.45999874
OS 35.93799518 -37.45999874
OS 35.93799518 -36.50030546
OS 36.31521566 -36.50030546
OS 36.32492354 -36.5016923
OE
OB 32.3849111 -36.61402634 I
OS 32.06871158 -36.61402634
OS 32.06871158 -37.45999874
OS 31.9411223 -37.45999874
OS 31.9411223 -36.61402634
OS 31.62492278 -36.61402634
OS 31.62492278 -36.50030546
OS 32.3849111 -36.50030546
OS 32.3849111 -36.61402634
OE
OB 30.62639798 -37.45999874 I
OS 30.48216662 -37.45999874
OS 30.36983258 -37.16876234
OS 29.96764898 -37.16876234
OS 29.86363598 -37.45999874
OS 29.7291125 -37.45999874
OS 30.09523826 -36.50030546
OS 30.23392226 -36.50030546
OS 30.62639798 -37.45999874
OE
OB 29.3546657 -36.5016923 I
OS 29.37824198 -36.50307914
OS 29.4032051 -36.50446598
OS 29.42678138 -36.50723966
OS 29.44758398 -36.51001334
OS 29.45035766 -36.51001334
OS 29.46006554 -36.51278702
OS 29.4725471 -36.5155607
OS 29.48918918 -36.51972122
OS 29.5072181 -36.52665542
OS 29.52663386 -36.53497646
OS 29.54743646 -36.54468434
OS 29.56546538 -36.55577906
OS 29.56823906 -36.5571659
OS 29.57378642 -36.56132642
OS 29.58210746 -36.56964746
OS 29.59320218 -36.57935534
OS 29.60568374 -36.5918369
OS 29.6181653 -36.60847898
OS 29.6320337 -36.6265079
OS 29.64312842 -36.6473105
OS 29.64451526 -36.65008418
OS 29.64728894 -36.65701838
OS 29.6528363 -36.66949994
OS 29.65838366 -36.68614202
OS 29.66254418 -36.70555778
OS 29.66809154 -36.72774722
OS 29.67086522 -36.75271034
OS 29.67225206 -36.7790603
OS 29.67225206 -36.78044714
OS 29.67225206 -36.78460766
OS 29.67225206 -36.79015502
OS 29.67086522 -36.7998629
OS 29.66947838 -36.80957078
OS 29.66809154 -36.82205234
OS 29.66531786 -36.83592074
OS 29.66254418 -36.85117598
OS 29.6528363 -36.8830733
OS 29.64728894 -36.89971538
OS 29.6389679 -36.9177443
OS 29.62926002 -36.93577322
OS 29.61955214 -36.9524153
OS 29.60707058 -36.96905738
OS 29.59320218 -36.98569946
OS 29.59181534 -36.9870863
OS 29.58904166 -36.98985998
OS 29.58488114 -36.9940205
OS 29.57794694 -36.99818102
OS 29.5696259 -37.00511522
OS 29.55853118 -37.01204942
OS 29.54466278 -37.02037046
OS 29.52940754 -37.02730466
OS 29.51137862 -37.0356257
OS 29.49057602 -37.04394674
OS 29.46838658 -37.05088094
OS 29.44203662 -37.0564283
OS 29.41429982 -37.06197566
OS 29.38378934 -37.06613618
OS 29.34911834 -37.06890986
OS 29.3130605 -37.0702967
OS 29.06758982 -37.0702967
OS 29.06758982 -37.45999874
OS 28.94000054 -37.45999874
OS 28.94000054 -36.50030546
OS 29.3338631 -36.50030546
OS 29.3546657 -36.5016923
OE
OB 31.18668134 -36.5016923 I
OS 31.1991629 -36.5016923
OS 31.22828654 -36.50307914
OS 31.25879702 -36.50723966
OS 31.29208118 -36.51140018
OS 31.32259166 -36.51833438
OS 31.3378469 -36.5224949
OS 31.35032846 -36.52665542
OS 31.3517153 -36.52665542
OS 31.35310214 -36.52804226
OS 31.36142318 -36.53220278
OS 31.37390474 -36.53775014
OS 31.38915998 -36.54745802
OS 31.40580206 -36.55993958
OS 31.42383098 -36.57658166
OS 31.44047306 -36.59599742
OS 31.45711514 -36.61818686
OS 31.45711514 -36.6195737
OS 31.45850198 -36.62096054
OS 31.46404934 -36.62928158
OS 31.4695967 -36.64314998
OS 31.47791774 -36.6611789
OS 31.48485194 -36.6819815
OS 31.49178614 -36.70694462
OS 31.49594666 -36.73329458
OS 31.4973335 -36.76241822
OS 31.4973335 -36.76380506
OS 31.4973335 -36.76657874
OS 31.4973335 -36.7721261
OS 31.49594666 -36.7790603
OS 31.49594666 -36.78876818
OS 31.49455982 -36.79847606
OS 31.48901246 -36.82205234
OS 31.48069142 -36.84978914
OS 31.4695967 -36.87891278
OS 31.45295462 -36.90803642
OS 31.4418599 -36.92190482
OS 31.43076518 -36.93577322
OS 31.42937834 -36.93716006
OS 31.4279915 -36.9385469
OS 31.42383098 -36.94270742
OS 31.41828362 -36.94686794
OS 31.41134942 -36.9524153
OS 31.40302838 -36.95796266
OS 31.39193366 -36.96489686
OS 31.38083894 -36.9732179
OS 31.36697054 -36.9801521
OS 31.3517153 -36.9870863
OS 31.33507322 -36.99540734
OS 31.3170443 -37.00234154
OS 31.2962417 -37.0078889
OS 31.2754391 -37.0148231
OS 31.25186282 -37.01898362
OS 31.2268997 -37.02314414
OS 31.22967338 -37.02453098
OS 31.23522074 -37.02730466
OS 31.24354178 -37.03285202
OS 31.2546365 -37.03839938
OS 31.27959962 -37.05365462
OS 31.29208118 -37.0633625
OS 31.3031759 -37.07168354
OS 31.30594958 -37.07445722
OS 31.31288378 -37.08139142
OS 31.3239785 -37.09248614
OS 31.3378469 -37.10635454
OS 31.35310214 -37.1257703
OS 31.37113106 -37.1465729
OS 31.38915998 -37.17153602
OS 31.40857574 -37.19927282
OS 31.5736097 -37.45999874
OS 31.41550994 -37.45999874
OS 31.2893075 -37.26029378
OS 31.2893075 -37.25890694
OS 31.28653382 -37.25613326
OS 31.28376014 -37.25197274
OS 31.27959962 -37.24642538
OS 31.26989174 -37.23117014
OS 31.25741018 -37.21175438
OS 31.24215494 -37.19095178
OS 31.2268997 -37.16876234
OS 31.21164446 -37.14795974
OS 31.19777606 -37.12854398
OS 31.19638922 -37.12715714
OS 31.1922287 -37.12160978
OS 31.1852945 -37.11328874
OS 31.17558662 -37.10358086
OS 31.15478402 -37.08277826
OS 31.1436893 -37.07307038
OS 31.13259458 -37.06474934
OS 31.13120774 -37.0633625
OS 31.12843406 -37.06197566
OS 31.1228867 -37.05920198
OS 31.11456566 -37.05504146
OS 31.10624462 -37.05088094
OS 31.09653674 -37.04672042
OS 31.0743473 -37.03978622
OS 31.07296046 -37.03978622
OS 31.07018678 -37.03839938
OS 31.06463942 -37.03839938
OS 31.05770522 -37.03701254
OS 31.04799734 -37.0356257
OS 31.03690262 -37.0356257
OS 31.02164738 -37.03423886
OS 30.85800026 -37.03423886
OS 30.85800026 -37.45999874
OS 30.73041098 -37.45999874
OS 30.73041098 -36.50030546
OS 31.17558662 -36.50030546
OS 31.18668134 -36.5016923
OE
OB 38.16387338 -36.60709214 H
OS 37.86154226 -36.60709214
OS 37.86154226 -36.9246785
OS 38.1472313 -36.9246785
OS 38.16387338 -36.92329166
OS 38.18328914 -36.92190482
OS 38.20547858 -36.92051798
OS 38.22766802 -36.9177443
OS 38.24985746 -36.91358378
OS 38.26927322 -36.90803642
OS 38.2720469 -36.90664958
OS 38.27759426 -36.9038759
OS 38.2859153 -36.89971538
OS 38.29701002 -36.89416802
OS 38.30949158 -36.88584698
OS 38.32197314 -36.8761391
OS 38.3344547 -36.86365754
OS 38.34416258 -36.84978914
OS 38.34554942 -36.8484023
OS 38.3483231 -36.84285494
OS 38.35248362 -36.8345339
OS 38.35803098 -36.82343918
OS 38.3621915 -36.81095762
OS 38.36635202 -36.79708922
OS 38.3691257 -36.78044714
OS 38.37051254 -36.76380506
OS 38.37051254 -36.76241822
OS 38.37051254 -36.76103138
OS 38.3691257 -36.75271034
OS 38.36773886 -36.74022878
OS 38.36496518 -36.7235867
OS 38.35803098 -36.70694462
OS 38.34970994 -36.68752886
OS 38.33722838 -36.66949994
OS 38.3205863 -36.65147102
OS 38.31781262 -36.65008418
OS 38.31087842 -36.64453682
OS 38.2997837 -36.63760262
OS 38.28175478 -36.62928158
OS 38.26095218 -36.62096054
OS 38.23321538 -36.61402634
OS 38.20131806 -36.60847898
OS 38.16387338 -36.60709214
OE
OB 29.34218414 -36.61402634 H
OS 29.06758982 -36.61402634
OS 29.06758982 -36.95657582
OS 29.32554206 -36.95657582
OS 29.33524994 -36.95518898
OS 29.34495782 -36.95518898
OS 29.35605254 -36.95380214
OS 29.3824025 -36.95102846
OS 29.41152614 -36.9454811
OS 29.44064978 -36.93716006
OS 29.46699974 -36.92606534
OS 29.4794813 -36.91913114
OS 29.48918918 -36.9108101
OS 29.49196286 -36.90803642
OS 29.49751022 -36.90248906
OS 29.50583126 -36.89139434
OS 29.51553914 -36.87752594
OS 29.52524702 -36.85949702
OS 29.53356806 -36.83730758
OS 29.53911542 -36.81234446
OS 29.5418891 -36.78322082
OS 29.5418891 -36.78183398
OS 29.5418891 -36.78044714
OS 29.5418891 -36.77351294
OS 29.54050226 -36.76103138
OS 29.53772858 -36.74716298
OS 29.5349549 -36.73190774
OS 29.52940754 -36.71387882
OS 29.5210865 -36.69723674
OS 29.51137862 -36.68059466
OS 29.50999178 -36.67920782
OS 29.50583126 -36.67366046
OS 29.49889706 -36.66672626
OS 29.49057602 -36.65701838
OS 29.47809446 -36.6473105
OS 29.46422606 -36.63898946
OS 29.44897082 -36.63066842
OS 29.4309419 -36.62373422
OS 29.42955506 -36.62373422
OS 29.4240077 -36.62234738
OS 29.41568666 -36.62096054
OS 29.40459194 -36.61818686
OS 29.38794986 -36.61680002
OS 29.36714726 -36.61541318
OS 29.34218414 -36.61402634
OE
OB 30.16180658 -36.60015794 H
OS 30.16180658 -36.60154478
OS 30.16041974 -36.60431846
OS 30.16041974 -36.60986582
OS 30.15764606 -36.61541318
OS 30.15625922 -36.62512106
OS 30.15348554 -36.63482894
OS 30.14793818 -36.65840522
OS 30.14100398 -36.68614202
OS 30.1312961 -36.7166525
OS 30.12158822 -36.74993666
OS 30.10910666 -36.78460766
OS 30.00509366 -37.06474934
OS 30.32961422 -37.06474934
OS 30.22976174 -36.80124974
OS 30.22976174 -36.7998629
OS 30.2283749 -36.79570238
OS 30.22560122 -36.78876818
OS 30.22282754 -36.78044714
OS 30.21866702 -36.77073926
OS 30.2145065 -36.7582577
OS 30.21034598 -36.7443893
OS 30.20479862 -36.7305209
OS 30.1937039 -36.69862358
OS 30.18260918 -36.66533942
OS 30.17151446 -36.63205526
OS 30.16180658 -36.60015794
OE
OB 31.16033138 -36.60709214 H
OS 30.85800026 -36.60709214
OS 30.85800026 -36.9246785
OS 31.1436893 -36.9246785
OS 31.16033138 -36.92329166
OS 31.17974714 -36.92190482
OS 31.20193658 -36.92051798
OS 31.22412602 -36.9177443
OS 31.24631546 -36.91358378
OS 31.26573122 -36.90803642
OS 31.2685049 -36.90664958
OS 31.27405226 -36.9038759
OS 31.2823733 -36.89971538
OS 31.29346802 -36.89416802
OS 31.30594958 -36.88584698
OS 31.31843114 -36.8761391
OS 31.3309127 -36.86365754
OS 31.34062058 -36.84978914
OS 31.34200742 -36.8484023
OS 31.3447811 -36.84285494
OS 31.34894162 -36.8345339
OS 31.35448898 -36.82343918
OS 31.3586495 -36.81095762
OS 31.36281002 -36.79708922
OS 31.3655837 -36.78044714
OS 31.36697054 -36.76380506
OS 31.36697054 -36.76241822
OS 31.36697054 -36.76103138
OS 31.3655837 -36.75271034
OS 31.36419686 -36.74022878
OS 31.36142318 -36.7235867
OS 31.35448898 -36.70694462
OS 31.34616794 -36.68752886
OS 31.33368638 -36.66949994
OS 31.3170443 -36.65147102
OS 31.31427062 -36.65008418
OS 31.30733642 -36.64453682
OS 31.2962417 -36.63760262
OS 31.27821278 -36.62928158
OS 31.25741018 -36.62096054
OS 31.22967338 -36.61402634
OS 31.19777606 -36.60847898
OS 31.16033138 -36.60709214
OE
OB 36.29302622 -36.61402634 H
OS 36.06558446 -36.61402634
OS 36.06558446 -36.90248906
OS 36.30134726 -36.90248906
OS 36.31937618 -36.90110222
OS 36.33879194 -36.89971538
OS 36.3582077 -36.89832854
OS 36.37762346 -36.89555486
OS 36.3928787 -36.89278118
OS 36.39565238 -36.89139434
OS 36.40119974 -36.8900075
OS 36.40952078 -36.88584698
OS 36.4206155 -36.88029962
OS 36.43171022 -36.87475226
OS 36.44419178 -36.86643122
OS 36.45667334 -36.8553365
OS 36.46638122 -36.84424178
OS 36.46776806 -36.84285494
OS 36.47054174 -36.83869442
OS 36.47470226 -36.83037338
OS 36.47886278 -36.8206655
OS 36.4830233 -36.80957078
OS 36.48718382 -36.79570238
OS 36.4899575 -36.7790603
OS 36.49134434 -36.76103138
OS 36.49134434 -36.7582577
OS 36.49134434 -36.75271034
OS 36.4899575 -36.7443893
OS 36.48857066 -36.73329458
OS 36.48579698 -36.71942618
OS 36.48163646 -36.70555778
OS 36.4760891 -36.69168938
OS 36.46776806 -36.67782098
OS 36.46638122 -36.67643414
OS 36.46360754 -36.67227362
OS 36.45806018 -36.66533942
OS 36.45112598 -36.65840522
OS 36.4414181 -36.65008418
OS 36.43032338 -36.64176314
OS 36.41645498 -36.6334421
OS 36.40119974 -36.62789474
OS 36.3998129 -36.62789474
OS 36.3928787 -36.62512106
OS 36.38317082 -36.62373422
OS 36.36791558 -36.62096054
OS 36.34711298 -36.61818686
OS 36.3235367 -36.61680002
OS 36.29302622 -36.61402634
OE
OB 36.31798934 -37.01620994 H
OS 36.06558446 -37.01620994
OS 36.06558446 -37.34627786
OS 36.33879194 -37.34627786
OS 36.36791558 -37.34489102
OS 36.38039714 -37.34350418
OS 36.39149186 -37.34211734
OS 36.3928787 -37.34211734
OS 36.39842606 -37.3407305
OS 36.4067471 -37.33934366
OS 36.41645498 -37.33656998
OS 36.44003126 -37.32824894
OS 36.46360754 -37.31715422
OS 36.46499438 -37.31576738
OS 36.4691549 -37.3129937
OS 36.47470226 -37.30883318
OS 36.48163646 -37.30328582
OS 36.48857066 -37.29496478
OS 36.49827854 -37.28664374
OS 36.50521274 -37.27554902
OS 36.51353378 -37.26306746
OS 36.51492062 -37.26168062
OS 36.51630746 -37.2575201
OS 36.51908114 -37.24919906
OS 36.52324166 -37.23949118
OS 36.52740218 -37.22839646
OS 36.53017586 -37.21452806
OS 36.5315627 -37.19788598
OS 36.53294954 -37.1812439
OS 36.53294954 -37.17847022
OS 36.53294954 -37.17292286
OS 36.5315627 -37.16182814
OS 36.52878902 -37.14934658
OS 36.52601534 -37.13547818
OS 36.52046798 -37.12022294
OS 36.51353378 -37.1049677
OS 36.5038259 -37.08971246
OS 36.50243906 -37.08832562
OS 36.49827854 -37.08277826
OS 36.49273118 -37.07584406
OS 36.48441014 -37.06752302
OS 36.47331542 -37.05781514
OS 36.45944702 -37.04810726
OS 36.44419178 -37.03978622
OS 36.42616286 -37.03285202
OS 36.42338918 -37.03146518
OS 36.41784182 -37.03007834
OS 36.40536026 -37.02730466
OS 36.39010502 -37.02453098
OS 36.37068926 -37.0217573
OS 36.34711298 -37.01898362
OS 36.31798934 -37.01620994
OE
SE
S P 0
OB 40.9056459 -38.32112732 I
OS 40.92136342 -38.32205188
OS 40.9380055 -38.32297644
OS 40.95372302 -38.32482556
OS 40.96759142 -38.32667468
OS 40.96944054 -38.32667468
OS 40.97591246 -38.3285238
OS 40.9842335 -38.33037292
OS 40.99532822 -38.3331466
OS 41.0073475 -38.3377694
OS 41.02029134 -38.34331676
OS 41.03415974 -38.34978868
OS 41.04617902 -38.35718516
OS 41.04802814 -38.35810972
OS 41.05172638 -38.3608834
OS 41.05727374 -38.36643076
OS 41.06467022 -38.37290268
OS 41.07299126 -38.38122372
OS 41.0813123 -38.39231844
OS 41.0905579 -38.40433772
OS 41.09795438 -38.41820612
OS 41.09887894 -38.42005524
OS 41.10072806 -38.42467804
OS 41.1044263 -38.43299908
OS 41.10812454 -38.4440938
OS 41.11089822 -38.45703764
OS 41.11459646 -38.4718306
OS 41.11644558 -38.48847268
OS 41.11737014 -38.50603932
OS 41.11737014 -38.50696388
OS 41.11737014 -38.50973756
OS 41.11737014 -38.5134358
OS 41.11644558 -38.51990772
OS 41.11552102 -38.52637964
OS 41.11459646 -38.53470068
OS 41.11274734 -38.54394628
OS 41.11089822 -38.55411644
OS 41.1044263 -38.57538132
OS 41.10072806 -38.58647604
OS 41.0951807 -38.59849532
OS 41.08870878 -38.6105146
OS 41.08223686 -38.62160932
OS 41.07391582 -38.63270404
OS 41.06467022 -38.64379876
OS 41.06374566 -38.64472332
OS 41.06189654 -38.64657244
OS 41.05912286 -38.64934612
OS 41.05450006 -38.6521198
OS 41.0489527 -38.6567426
OS 41.04155622 -38.6613654
OS 41.03231062 -38.66691276
OS 41.02214046 -38.67153556
OS 41.01012118 -38.67708292
OS 40.99625278 -38.68263028
OS 40.98145982 -38.68725308
OS 40.96389318 -38.69095132
OS 40.94540198 -38.69464956
OS 40.92506166 -38.69742324
OS 40.90194766 -38.69927236
OS 40.8779091 -38.70019692
OS 40.71426198 -38.70019692
OS 40.71426198 -38.95999828
OS 40.62920246 -38.95999828
OS 40.62920246 -38.32020276
OS 40.8917775 -38.32020276
OS 40.9056459 -38.32112732
OE
OB 40.49791494 -38.98403684 I
OS 40.49791494 -38.9849614
OS 40.49791494 -38.98773508
OS 40.49791494 -38.99235788
OS 40.49791494 -38.99790524
OS 40.49699038 -39.00530172
OS 40.49699038 -39.0126982
OS 40.49514126 -39.0311894
OS 40.49236758 -39.05060516
OS 40.48866934 -39.07094548
OS 40.48312198 -39.08851212
OS 40.47942374 -39.09683316
OS 40.4757255 -39.10330508
OS 40.4757255 -39.10422964
OS 40.47480094 -39.1051542
OS 40.47017814 -39.109777
OS 40.46278166 -39.11717348
OS 40.45353606 -39.12549452
OS 40.44059222 -39.13381556
OS 40.42395014 -39.14028748
OS 40.40453438 -39.14583484
OS 40.39343966 -39.1467594
OS 40.38142038 -39.14768396
OS 40.37587302 -39.14768396
OS 40.37032566 -39.1467594
OS 40.36200462 -39.1467594
OS 40.35275902 -39.14583484
OS 40.34258886 -39.14398572
OS 40.32039942 -39.13843836
OS 40.33519238 -39.07187004
OS 40.33611694 -39.07187004
OS 40.33889062 -39.0727946
OS 40.34351342 -39.07371916
OS 40.34813622 -39.07464372
OS 40.3601555 -39.0774174
OS 40.36570286 -39.07834196
OS 40.37494846 -39.07834196
OS 40.37957126 -39.0774174
OS 40.38511862 -39.07649284
OS 40.39066598 -39.07464372
OS 40.39621334 -39.07094548
OS 40.40268526 -39.06724724
OS 40.40730806 -39.06169988
OS 40.40823262 -39.06077532
OS 40.40915718 -39.05800164
OS 40.4110063 -39.05337884
OS 40.41377998 -39.04598236
OS 40.4156291 -39.0358122
OS 40.41655366 -39.02841572
OS 40.41747822 -39.0219438
OS 40.41840278 -39.01362276
OS 40.41840278 -39.0034526
OS 40.41932734 -38.99328244
OS 40.41932734 -38.98218772
OS 40.41932734 -38.49586916
OS 40.49791494 -38.49586916
OS 40.49791494 -38.98403684
OE
OB 41.51770462 -38.3100326 I
OS 41.52602566 -38.31095716
OS 41.53619582 -38.31188172
OS 41.54636598 -38.31280628
OS 41.55838526 -38.31557996
OS 41.58334838 -38.32112732
OS 41.61108518 -38.32944836
OS 41.62495358 -38.33499572
OS 41.63789742 -38.34146764
OS 41.65084126 -38.34978868
OS 41.6637851 -38.35810972
OS 41.66470966 -38.35903428
OS 41.66655878 -38.35995884
OS 41.67025702 -38.36273252
OS 41.67487982 -38.36735532
OS 41.67950262 -38.37197812
OS 41.68597454 -38.37845004
OS 41.69244646 -38.38584652
OS 41.69984294 -38.393243
OS 41.70723942 -38.4024886
OS 41.7146359 -38.41358332
OS 41.72295694 -38.42467804
OS 41.73035342 -38.43669732
OS 41.73682534 -38.45056572
OS 41.74422182 -38.46443412
OS 41.74976918 -38.47922708
OS 41.75531654 -38.49586916
OS 41.67210614 -38.51528492
OS 41.67210614 -38.51436036
OS 41.67118158 -38.51251124
OS 41.66933246 -38.508813
OS 41.66748334 -38.5041902
OS 41.66563422 -38.49864284
OS 41.66286054 -38.49124636
OS 41.65546406 -38.4764534
OS 41.64621846 -38.45981132
OS 41.63512374 -38.44316924
OS 41.62125534 -38.42745172
OS 41.60646238 -38.41358332
OS 41.60461326 -38.4117342
OS 41.5990659 -38.40803596
OS 41.5898203 -38.40341316
OS 41.57780102 -38.39694124
OS 41.5620835 -38.39139388
OS 41.54451686 -38.38584652
OS 41.52325198 -38.38214828
OS 41.50013798 -38.38122372
OS 41.4927415 -38.38122372
OS 41.4881187 -38.38214828
OS 41.48164678 -38.38214828
OS 41.4742503 -38.38307284
OS 41.45668366 -38.38584652
OS 41.4372679 -38.38954476
OS 41.41692758 -38.39601668
OS 41.3956627 -38.40526228
OS 41.37624694 -38.41728156
OS 41.37532238 -38.41728156
OS 41.37439782 -38.41913068
OS 41.3679259 -38.42375348
OS 41.35960486 -38.43114996
OS 41.3494347 -38.44224468
OS 41.33741542 -38.45611308
OS 41.3263207 -38.4718306
OS 41.31615054 -38.49124636
OS 41.30690494 -38.51251124
OS 41.30690494 -38.5134358
OS 41.30598038 -38.51528492
OS 41.30505582 -38.5180586
OS 41.30413126 -38.5226814
OS 41.30228214 -38.52822876
OS 41.30043302 -38.53470068
OS 41.29765934 -38.5504182
OS 41.2939611 -38.5689094
OS 41.29026286 -38.58924972
OS 41.28841374 -38.61143916
OS 41.28748918 -38.63547772
OS 41.28748918 -38.63640228
OS 41.28748918 -38.63917596
OS 41.28748918 -38.64379876
OS 41.28748918 -38.64934612
OS 41.28841374 -38.65581804
OS 41.28841374 -38.66413908
OS 41.2893383 -38.67338468
OS 41.29026286 -38.68355484
OS 41.29303654 -38.70574428
OS 41.29765934 -38.72978284
OS 41.3032067 -38.7538214
OS 41.31060318 -38.77785996
OS 41.31060318 -38.77878452
OS 41.31152774 -38.78063364
OS 41.31337686 -38.78340732
OS 41.31522598 -38.78803012
OS 41.32077334 -38.79912484
OS 41.32909438 -38.81206868
OS 41.33926454 -38.82686164
OS 41.35220838 -38.84257916
OS 41.36700134 -38.85644756
OS 41.38456798 -38.8693914
OS 41.38549254 -38.8693914
OS 41.38734166 -38.87031596
OS 41.39011534 -38.87216508
OS 41.39381358 -38.8740142
OS 41.39843638 -38.87586332
OS 41.40398374 -38.878637
OS 41.41692758 -38.88418436
OS 41.43356966 -38.88973172
OS 41.45206086 -38.89435452
OS 41.47240118 -38.89805276
OS 41.49366606 -38.89897732
OS 41.50013798 -38.89897732
OS 41.50568534 -38.89805276
OS 41.51215726 -38.89805276
OS 41.51862918 -38.8971282
OS 41.53527126 -38.89342996
OS 41.55468702 -38.88880716
OS 41.57410278 -38.88141068
OS 41.5944431 -38.87124052
OS 41.60461326 -38.86569316
OS 41.61385886 -38.85829668
OS 41.61478342 -38.85737212
OS 41.61570798 -38.85644756
OS 41.61848166 -38.85367388
OS 41.6221799 -38.8509002
OS 41.62587814 -38.8462774
OS 41.63050094 -38.84073004
OS 41.6360483 -38.83518268
OS 41.6406711 -38.8277862
OS 41.64621846 -38.81946516
OS 41.65269038 -38.81021956
OS 41.65823774 -38.80097396
OS 41.6637851 -38.78987924
OS 41.6684079 -38.77785996
OS 41.6730307 -38.76491612
OS 41.6776535 -38.75104772
OS 41.68135174 -38.73625476
OS 41.76641126 -38.75751964
OS 41.76641126 -38.7584442
OS 41.7654867 -38.76214244
OS 41.76363758 -38.7676898
OS 41.7608639 -38.77508628
OS 41.75809022 -38.78340732
OS 41.75439198 -38.79357748
OS 41.74976918 -38.8046722
OS 41.74422182 -38.81669148
OS 41.73127798 -38.84257916
OS 41.7146359 -38.86846684
OS 41.70446574 -38.88141068
OS 41.69429558 -38.89435452
OS 41.68320086 -38.90544924
OS 41.67025702 -38.91654396
OS 41.66933246 -38.91746852
OS 41.66748334 -38.91931764
OS 41.66286054 -38.92116676
OS 41.65823774 -38.924865
OS 41.65084126 -38.9294878
OS 41.64344478 -38.9341106
OS 41.63327462 -38.9387334
OS 41.62310446 -38.9433562
OS 41.61108518 -38.94890356
OS 41.59814134 -38.95352636
OS 41.58427294 -38.95814916
OS 41.56947998 -38.96277196
OS 41.55376246 -38.9664702
OS 41.53712038 -38.96831932
OS 41.51955374 -38.97016844
OS 41.50106254 -38.971093
OS 41.49089238 -38.971093
OS 41.4834959 -38.97016844
OS 41.47517486 -38.97016844
OS 41.4650047 -38.96924388
OS 41.45390998 -38.96739476
OS 41.44096614 -38.96554564
OS 41.4141539 -38.96092284
OS 41.3864171 -38.95352636
OS 41.3586803 -38.9433562
OS 41.34573646 -38.93688428
OS 41.33279262 -38.9294878
OS 41.33186806 -38.92856324
OS 41.33001894 -38.92763868
OS 41.3263207 -38.924865
OS 41.32262246 -38.92116676
OS 41.3170751 -38.91746852
OS 41.31060318 -38.91192116
OS 41.3032067 -38.90544924
OS 41.29581022 -38.89805276
OS 41.28841374 -38.88973172
OS 41.2800927 -38.88141068
OS 41.26345062 -38.8601458
OS 41.2477331 -38.83518268
OS 41.2338647 -38.80744588
OS 41.2338647 -38.80652132
OS 41.23201558 -38.80374764
OS 41.23109102 -38.79912484
OS 41.22831734 -38.79357748
OS 41.22646822 -38.786181
OS 41.22369454 -38.7769354
OS 41.2199963 -38.76676524
OS 41.21722262 -38.75567052
OS 41.21444894 -38.74365124
OS 41.2107507 -38.72978284
OS 41.2061279 -38.70112148
OS 41.20242966 -38.66876188
OS 41.20058054 -38.63547772
OS 41.20058054 -38.63455316
OS 41.20058054 -38.63085492
OS 41.20058054 -38.62530756
OS 41.2015051 -38.61883564
OS 41.2015051 -38.60959004
OS 41.20242966 -38.60034444
OS 41.20335422 -38.58832516
OS 41.20520334 -38.57630588
OS 41.20982614 -38.54949364
OS 41.21629806 -38.51990772
OS 41.22554366 -38.4903218
OS 41.2384875 -38.46166044
OS 41.23941206 -38.46073588
OS 41.24033662 -38.4579622
OS 41.24218574 -38.45426396
OS 41.24588398 -38.44964116
OS 41.24958222 -38.44316924
OS 41.25420502 -38.43577276
OS 41.2662243 -38.41913068
OS 41.28194182 -38.40063948
OS 41.30043302 -38.38214828
OS 41.3216979 -38.36365708
OS 41.34666102 -38.34793956
OS 41.34758558 -38.347015
OS 41.35035926 -38.34609044
OS 41.3540575 -38.34424132
OS 41.3586803 -38.34146764
OS 41.36607678 -38.33869396
OS 41.37347326 -38.33592028
OS 41.38271886 -38.33222204
OS 41.39288902 -38.3285238
OS 41.40398374 -38.32482556
OS 41.41600302 -38.32112732
OS 41.4418907 -38.31557996
OS 41.47147662 -38.31095716
OS 41.5019871 -38.30910804
OS 41.5112327 -38.30910804
OS 41.51770462 -38.3100326
OE
OB 42.90454462 -39.1375138 I
OS 42.38401734 -39.1375138
OS 42.38401734 -39.08111564
OS 42.90454462 -39.08111564
OS 42.90454462 -39.1375138
OE
OB 42.12514054 -38.32112732 I
OS 42.13253702 -38.32112732
OS 42.1491791 -38.32297644
OS 42.1676703 -38.32482556
OS 42.18708606 -38.3285238
OS 42.20650182 -38.3331466
OS 42.22406846 -38.33961852
OS 42.22499302 -38.33961852
OS 42.22591758 -38.34054308
OS 42.23146494 -38.34331676
OS 42.23978598 -38.34793956
OS 42.24903158 -38.35441148
OS 42.2601263 -38.36273252
OS 42.27214558 -38.37290268
OS 42.2832403 -38.38584652
OS 42.29341046 -38.39971492
OS 42.29433502 -38.40156404
OS 42.2971087 -38.4071114
OS 42.3017315 -38.41450788
OS 42.3063543 -38.4256026
OS 42.3109771 -38.43854644
OS 42.3155999 -38.45241484
OS 42.31837358 -38.46813236
OS 42.31929814 -38.48384988
OS 42.31929814 -38.485699
OS 42.31929814 -38.4903218
OS 42.31837358 -38.49864284
OS 42.31652446 -38.508813
OS 42.31375078 -38.52083228
OS 42.30912798 -38.53377612
OS 42.30358062 -38.54671996
OS 42.29618414 -38.56058836
OS 42.29525958 -38.56243748
OS 42.2924859 -38.56613572
OS 42.28693854 -38.5735322
OS 42.27954206 -38.58092868
OS 42.27029646 -38.59017428
OS 42.25920174 -38.60034444
OS 42.24533334 -38.60959004
OS 42.22961582 -38.61883564
OS 42.23054038 -38.61883564
OS 42.2323895 -38.6197602
OS 42.23516318 -38.62068476
OS 42.23886142 -38.62253388
OS 42.24995614 -38.62623212
OS 42.26289998 -38.63270404
OS 42.27676838 -38.64102508
OS 42.2924859 -38.65119524
OS 42.3063543 -38.66321452
OS 42.31929814 -38.67800748
OS 42.3202227 -38.6798566
OS 42.32392094 -38.68540396
OS 42.3294683 -38.693725
OS 42.33501566 -38.70481972
OS 42.34056302 -38.71961268
OS 42.34611038 -38.7353302
OS 42.34980862 -38.7538214
OS 42.35073318 -38.77416172
OS 42.35073318 -38.77508628
OS 42.35073318 -38.77601084
OS 42.35073318 -38.7815582
OS 42.34980862 -38.7908038
OS 42.3479595 -38.80189852
OS 42.34611038 -38.81484236
OS 42.34241214 -38.82871076
OS 42.33778934 -38.84350372
OS 42.33131742 -38.85829668
OS 42.33039286 -38.8601458
OS 42.32761918 -38.8647686
OS 42.32392094 -38.87124052
OS 42.31837358 -38.88048612
OS 42.3109771 -38.88973172
OS 42.30358062 -38.89990188
OS 42.29433502 -38.91007204
OS 42.28416486 -38.91839308
OS 42.2832403 -38.91931764
OS 42.27954206 -38.92209132
OS 42.27307014 -38.92578956
OS 42.2647491 -38.9294878
OS 42.25457894 -38.93503516
OS 42.24255966 -38.94058252
OS 42.22961582 -38.94520532
OS 42.2138983 -38.94982812
OS 42.21204918 -38.94982812
OS 42.20650182 -38.95167724
OS 42.19725622 -38.9526018
OS 42.18523694 -38.95445092
OS 42.17044398 -38.95630004
OS 42.15287734 -38.95814916
OS 42.13346158 -38.95907372
OS 42.11127214 -38.95999828
OS 41.8671883 -38.95999828
OS 41.8671883 -38.32020276
OS 42.11866862 -38.32020276
OS 42.12514054 -38.32112732
OE
OB 40.30745558 -38.48662356 I
OS 40.31762574 -38.48847268
OS 40.32964502 -38.49217092
OS 40.34258886 -38.49679372
OS 40.35738182 -38.50326564
OS 40.37309934 -38.51158668
OS 40.34443798 -38.58370236
OS 40.34351342 -38.5827778
OS 40.33981518 -38.58092868
OS 40.33426782 -38.578155
OS 40.32687134 -38.57538132
OS 40.3185503 -38.57260764
OS 40.30838014 -38.56983396
OS 40.29820998 -38.56798484
OS 40.28803982 -38.56706028
OS 40.28341702 -38.56706028
OS 40.27879422 -38.56798484
OS 40.2723223 -38.5689094
OS 40.26585038 -38.57075852
OS 40.25752934 -38.5735322
OS 40.2492083 -38.57723044
OS 40.24181182 -38.5827778
OS 40.24088726 -38.58370236
OS 40.23811358 -38.58555148
OS 40.2353399 -38.58924972
OS 40.2307171 -38.59387252
OS 40.2260943 -38.60034444
OS 40.2214715 -38.60774092
OS 40.2168487 -38.61606196
OS 40.21315046 -38.62623212
OS 40.2122259 -38.62808124
OS 40.21130134 -38.6336286
OS 40.20945222 -38.64194964
OS 40.20667854 -38.65304436
OS 40.20390486 -38.66691276
OS 40.20205574 -38.68263028
OS 40.20113118 -38.69927236
OS 40.20020662 -38.71776356
OS 40.20020662 -38.95999828
OS 40.12161902 -38.95999828
OS 40.12161902 -38.49586916
OS 40.19281014 -38.49586916
OS 40.19281014 -38.56613572
OS 40.1937347 -38.56521116
OS 40.19743294 -38.55873924
OS 40.20205574 -38.5504182
OS 40.20945222 -38.54024804
OS 40.2168487 -38.53007788
OS 40.22516974 -38.51898316
OS 40.23349078 -38.50973756
OS 40.24181182 -38.50234108
OS 40.24273638 -38.50141652
OS 40.24551006 -38.4995674
OS 40.25105742 -38.49679372
OS 40.25660478 -38.49402004
OS 40.26400126 -38.49124636
OS 40.27324686 -38.48847268
OS 40.28249246 -38.48662356
OS 40.29266262 -38.485699
OS 40.29913454 -38.485699
OS 40.30745558 -38.48662356
OE
OB 39.48829542 -38.95999828 I
OS 39.3986131 -38.95999828
OS 39.3986131 -38.87031596
OS 39.48829542 -38.87031596
OS 39.48829542 -38.95999828
OE
OB 38.6404739 -38.95999828 I
OS 38.55171614 -38.95999828
OS 38.30393406 -38.32020276
OS 38.39639006 -38.32020276
OS 38.56281086 -38.78525644
OS 38.56281086 -38.786181
OS 38.56373542 -38.78803012
OS 38.56465998 -38.7908038
OS 38.5665091 -38.79450204
OS 38.56743366 -38.8000494
OS 38.56928278 -38.80559676
OS 38.57390558 -38.81946516
OS 38.57945294 -38.83518268
OS 38.5850003 -38.85274932
OS 38.59609502 -38.88973172
OS 38.59609502 -38.88880716
OS 38.59701958 -38.88695804
OS 38.59794414 -38.88418436
OS 38.5988687 -38.88048612
OS 38.60164238 -38.87031596
OS 38.60626518 -38.85644756
OS 38.61088798 -38.84073004
OS 38.61643534 -38.8231634
OS 38.62290726 -38.8046722
OS 38.63030374 -38.78525644
OS 38.80412102 -38.32020276
OS 38.8901051 -38.32020276
OS 38.6404739 -38.95999828
OE
OB 39.27564662 -38.42745172 I
OS 39.25438174 -38.54671996
OS 39.20538006 -38.54671996
OS 39.1859643 -38.42745172
OS 39.1859643 -38.32020276
OS 39.27564662 -38.32020276
OS 39.27564662 -38.42745172
OE
OB 40.49791494 -38.4117342 I
OS 40.41932734 -38.4117342
OS 40.41932734 -38.32020276
OS 40.49791494 -38.32020276
OS 40.49791494 -38.4117342
OE
OB 39.84517558 -38.48662356 I
OS 39.8516475 -38.48754812
OS 39.8655159 -38.48939724
OS 39.88215798 -38.49309548
OS 39.89972462 -38.49864284
OS 39.91729126 -38.50696388
OS 39.9348579 -38.51713404
OS 39.93578246 -38.51713404
OS 39.93670702 -38.51898316
OS 39.94225438 -38.5226814
OS 39.95057542 -38.53007788
OS 39.96074558 -38.53932348
OS 39.9718403 -38.55134276
OS 39.98293502 -38.56613572
OS 39.99402974 -38.58370236
OS 40.00327534 -38.60311812
OS 40.00327534 -38.60404268
OS 40.0041999 -38.6058918
OS 40.00512446 -38.60866548
OS 40.00697358 -38.61236372
OS 40.0088227 -38.61791108
OS 40.01067182 -38.624383
OS 40.01529462 -38.63917596
OS 40.01991742 -38.65766716
OS 40.02361566 -38.67800748
OS 40.02638934 -38.70112148
OS 40.0273139 -38.72516004
OS 40.0273139 -38.7260846
OS 40.0273139 -38.72793372
OS 40.0273139 -38.73163196
OS 40.0273139 -38.73717932
OS 40.02638934 -38.74365124
OS 40.02638934 -38.75104772
OS 40.02454022 -38.7676898
OS 40.02084198 -38.78803012
OS 40.01621918 -38.809295
OS 40.00974726 -38.83148444
OS 40.00142622 -38.85367388
OS 40.00142622 -38.85459844
OS 40.00050166 -38.85644756
OS 39.99865254 -38.85922124
OS 39.99680342 -38.86291948
OS 39.9903315 -38.87308964
OS 39.98201046 -38.88603348
OS 39.9718403 -38.89990188
OS 39.95889646 -38.91377028
OS 39.9441035 -38.92763868
OS 39.92653686 -38.94058252
OS 39.9256123 -38.94058252
OS 39.92468774 -38.94150708
OS 39.92191406 -38.9433562
OS 39.91821582 -38.94520532
OS 39.90897022 -38.94982812
OS 39.89602638 -38.95537548
OS 39.88030886 -38.96092284
OS 39.86366678 -38.96554564
OS 39.84425102 -38.96924388
OS 39.82483526 -38.97016844
OS 39.81836334 -38.97016844
OS 39.81096686 -38.96924388
OS 39.80172126 -38.96831932
OS 39.79062654 -38.9664702
OS 39.77860726 -38.96369652
OS 39.76658798 -38.95999828
OS 39.7545687 -38.95445092
OS 39.75364414 -38.95352636
OS 39.74902134 -38.95167724
OS 39.74347398 -38.947979
OS 39.7360775 -38.94243164
OS 39.72868102 -38.93688428
OS 39.71943542 -38.9294878
OS 39.71111438 -38.92116676
OS 39.7037179 -38.91192116
OS 39.7037179 -39.1375138
OS 39.6251303 -39.1375138
OS 39.6251303 -38.49586916
OS 39.69632142 -38.49586916
OS 39.69632142 -38.55689012
OS 39.69724598 -38.555041
OS 39.70094422 -38.55134276
OS 39.70556702 -38.54487084
OS 39.7129635 -38.53747436
OS 39.72128454 -38.52822876
OS 39.73053014 -38.51990772
OS 39.74162486 -38.51158668
OS 39.75271958 -38.5041902
OS 39.7545687 -38.50326564
OS 39.75826694 -38.50141652
OS 39.76566342 -38.49864284
OS 39.77490902 -38.4949446
OS 39.78600374 -38.49124636
OS 39.79894758 -38.48847268
OS 39.81374054 -38.48662356
OS 39.83038262 -38.485699
OS 39.84055278 -38.485699
OS 39.84517558 -38.48662356
OE
OB 44.92193454 -38.40988508 I
OS 44.84334694 -38.40988508
OS 44.84334694 -38.32020276
OS 44.92193454 -38.32020276
OS 44.92193454 -38.40988508
OE
OB 45.24553054 -38.48662356 I
OS 45.25385158 -38.48754812
OS 45.26309718 -38.48939724
OS 45.27326734 -38.49124636
OS 45.28528662 -38.49309548
OS 45.31024974 -38.50141652
OS 45.32319358 -38.50603932
OS 45.33613742 -38.51251124
OS 45.34908126 -38.51898316
OS 45.3620251 -38.52822876
OS 45.37404438 -38.53747436
OS 45.38606366 -38.54856908
OS 45.38698822 -38.54949364
OS 45.38883734 -38.55134276
OS 45.39161102 -38.555041
OS 45.39530926 -38.5596638
OS 45.39993206 -38.56613572
OS 45.40547942 -38.57445676
OS 45.41102678 -38.58370236
OS 45.41657414 -38.59387252
OS 45.4221215 -38.60496724
OS 45.42766886 -38.61883564
OS 45.43321622 -38.63270404
OS 45.43783902 -38.64842156
OS 45.44153726 -38.66506364
OS 45.44431094 -38.68263028
OS 45.44616006 -38.70112148
OS 45.44708462 -38.7214618
OS 45.44708462 -38.72238636
OS 45.44708462 -38.72516004
OS 45.44708462 -38.72978284
OS 45.44708462 -38.73625476
OS 45.44616006 -38.74365124
OS 45.4452355 -38.75289684
OS 45.4452355 -38.76214244
OS 45.44338638 -38.7723126
OS 45.4406127 -38.7954266
OS 45.43506534 -38.8185406
OS 45.42859342 -38.8416546
OS 45.41934782 -38.86291948
OS 45.41934782 -38.86384404
OS 45.41842326 -38.8647686
OS 45.41657414 -38.86754228
OS 45.41472502 -38.87124052
OS 45.4082531 -38.88048612
OS 45.39993206 -38.89158084
OS 45.38883734 -38.90452468
OS 45.37496894 -38.91746852
OS 45.35925142 -38.93041236
OS 45.34076022 -38.94243164
OS 45.33983566 -38.94243164
OS 45.3389111 -38.9433562
OS 45.33613742 -38.94520532
OS 45.33151462 -38.94705444
OS 45.32689182 -38.94890356
OS 45.32134446 -38.95075268
OS 45.30747606 -38.95630004
OS 45.29175854 -38.96092284
OS 45.27234278 -38.96554564
OS 45.25200246 -38.96924388
OS 45.22981302 -38.97016844
OS 45.22056742 -38.97016844
OS 45.21317094 -38.96924388
OS 45.2048499 -38.96831932
OS 45.1956043 -38.9664702
OS 45.18450958 -38.96462108
OS 45.17341486 -38.96277196
OS 45.14845174 -38.95537548
OS 45.13458334 -38.94982812
OS 45.1216395 -38.94428076
OS 45.10869566 -38.93688428
OS 45.09575182 -38.92856324
OS 45.08373254 -38.91931764
OS 45.07171326 -38.90822292
OS 45.0707887 -38.90729836
OS 45.06893958 -38.90544924
OS 45.0661659 -38.901751
OS 45.06246766 -38.89620364
OS 45.05784486 -38.88973172
OS 45.05322206 -38.88233524
OS 45.0476747 -38.87308964
OS 45.04212734 -38.86199492
OS 45.03657998 -38.84997564
OS 45.03103262 -38.83610724
OS 45.02640982 -38.82131428
OS 45.02178702 -38.80559676
OS 45.01808878 -38.78803012
OS 45.0153151 -38.76953892
OS 45.01346598 -38.7491986
OS 45.01254142 -38.72793372
OS 45.01254142 -38.7260846
OS 45.01254142 -38.72238636
OS 45.01346598 -38.71591444
OS 45.01346598 -38.70666884
OS 45.01439054 -38.69649868
OS 45.01623966 -38.68355484
OS 45.01808878 -38.670611
OS 45.02178702 -38.65581804
OS 45.02548526 -38.64102508
OS 45.03010806 -38.62530756
OS 45.03565542 -38.60866548
OS 45.0430519 -38.59294796
OS 45.05044838 -38.578155
OS 45.06061854 -38.56336204
OS 45.0707887 -38.54949364
OS 45.08373254 -38.53747436
OS 45.0846571 -38.5365498
OS 45.08650622 -38.53562524
OS 45.09020446 -38.53285156
OS 45.09482726 -38.52915332
OS 45.10037462 -38.52545508
OS 45.1077711 -38.52083228
OS 45.11516758 -38.51620948
OS 45.12441318 -38.51158668
OS 45.13458334 -38.50696388
OS 45.14567806 -38.50234108
OS 45.17064118 -38.49402004
OS 45.19930254 -38.48754812
OS 45.2140955 -38.48662356
OS 45.22981302 -38.485699
OS 45.23905862 -38.485699
OS 45.24553054 -38.48662356
OE
OB 44.92193454 -38.95999828 I
OS 44.84334694 -38.95999828
OS 44.84334694 -38.49586916
OS 44.92193454 -38.49586916
OS 44.92193454 -38.95999828
OE
OB 46.10722046 -38.42745172 I
OS 46.08595558 -38.54671996
OS 46.0369539 -38.54671996
OS 46.01753814 -38.42745172
OS 46.01753814 -38.32020276
OS 46.10722046 -38.32020276
OS 46.10722046 -38.42745172
OE
OB 45.77160518 -38.48662356 I
OS 45.78177534 -38.48754812
OS 45.79379462 -38.48939724
OS 45.80673846 -38.49217092
OS 45.82060686 -38.49586916
OS 45.8335507 -38.50141652
OS 45.83539982 -38.50234108
OS 45.83909806 -38.5041902
OS 45.84556998 -38.50696388
OS 45.85296646 -38.51158668
OS 45.86221206 -38.51713404
OS 45.8705331 -38.52453052
OS 45.87885414 -38.531927
OS 45.88625062 -38.5411726
OS 45.88717518 -38.54209716
OS 45.8890243 -38.5457954
OS 45.89179798 -38.5504182
OS 45.89642078 -38.55689012
OS 45.90011902 -38.56613572
OS 45.90381726 -38.57538132
OS 45.90844006 -38.58647604
OS 45.91121374 -38.59849532
OS 45.91121374 -38.59941988
OS 45.9121383 -38.60311812
OS 45.91306286 -38.60866548
OS 45.91398742 -38.61606196
OS 45.91398742 -38.62715668
OS 45.91491198 -38.64010052
OS 45.91583654 -38.65581804
OS 45.91583654 -38.6752338
OS 45.91583654 -38.95999828
OS 45.83724894 -38.95999828
OS 45.83724894 -38.67893204
OS 45.83724894 -38.67800748
OS 45.83724894 -38.67708292
OS 45.83724894 -38.670611
OS 45.83724894 -38.66228996
OS 45.83632438 -38.6521198
OS 45.83539982 -38.64010052
OS 45.8335507 -38.62808124
OS 45.83077702 -38.61698652
OS 45.82800334 -38.60681636
OS 45.82800334 -38.6058918
OS 45.82615422 -38.60311812
OS 45.82338054 -38.59849532
OS 45.82060686 -38.59294796
OS 45.81598406 -38.5874006
OS 45.8104367 -38.58092868
OS 45.80304022 -38.57445676
OS 45.79471918 -38.5689094
OS 45.79379462 -38.56798484
OS 45.79102094 -38.56613572
OS 45.78547358 -38.5642866
OS 45.77900166 -38.56151292
OS 45.77160518 -38.55873924
OS 45.76235958 -38.55596556
OS 45.75126486 -38.555041
OS 45.74017014 -38.55411644
OS 45.73554734 -38.55411644
OS 45.7318491 -38.555041
OS 45.7226035 -38.55596556
OS 45.71058422 -38.55781468
OS 45.69764038 -38.56243748
OS 45.68284742 -38.56798484
OS 45.66805446 -38.57538132
OS 45.65418606 -38.58647604
OS 45.65233694 -38.58832516
OS 45.6486387 -38.59294796
OS 45.64586502 -38.5966462
OS 45.64309134 -38.601269
OS 45.6393931 -38.60681636
OS 45.63661942 -38.61328828
OS 45.63292118 -38.62068476
OS 45.62922294 -38.62993036
OS 45.62644926 -38.64010052
OS 45.62367558 -38.65119524
OS 45.62182646 -38.66321452
OS 45.61997734 -38.67615836
OS 45.61812822 -38.69187588
OS 45.61812822 -38.7075934
OS 45.61812822 -38.95999828
OS 45.53954062 -38.95999828
OS 45.53954062 -38.49586916
OS 45.60980718 -38.49586916
OS 45.60980718 -38.56243748
OS 45.61073174 -38.56151292
OS 45.61258086 -38.55873924
OS 45.61535454 -38.555041
OS 45.61905278 -38.5504182
OS 45.62460014 -38.54487084
OS 45.63107206 -38.53839892
OS 45.63846854 -38.53100244
OS 45.64771414 -38.52360596
OS 45.65695974 -38.51713404
OS 45.66805446 -38.50973756
OS 45.68007374 -38.50326564
OS 45.69301758 -38.49771828
OS 45.70781054 -38.49309548
OS 45.7226035 -38.48939724
OS 45.73924558 -38.48662356
OS 45.75681222 -38.485699
OS 45.7642087 -38.485699
OS 45.77160518 -38.48662356
OE
OB 44.2756671 -38.95999828 I
OS 44.1970795 -38.95999828
OS 44.1970795 -38.49586916
OS 44.2756671 -38.49586916
OS 44.2756671 -38.95999828
OE
OB 43.4574315 -38.48662356 I
OS 43.46482798 -38.48754812
OS 43.47407358 -38.48939724
OS 43.48424374 -38.49124636
OS 43.49626302 -38.49402004
OS 43.50735774 -38.49679372
OS 43.52030158 -38.50141652
OS 43.53232086 -38.50603932
OS 43.5452647 -38.51251124
OS 43.55820854 -38.51990772
OS 43.57115238 -38.52822876
OS 43.58317166 -38.53839892
OS 43.59426638 -38.54949364
OS 43.59519094 -38.5504182
OS 43.59704006 -38.55226732
OS 43.59981374 -38.55596556
OS 43.60351198 -38.56151292
OS 43.60813478 -38.56798484
OS 43.61275758 -38.57538132
OS 43.61830494 -38.58462692
OS 43.6238523 -38.59572164
OS 43.62939966 -38.60774092
OS 43.63494702 -38.62068476
OS 43.63956982 -38.63547772
OS 43.64419262 -38.65119524
OS 43.64789086 -38.66876188
OS 43.65066454 -38.68725308
OS 43.65251366 -38.70666884
OS 43.65343822 -38.72793372
OS 43.65343822 -38.72885828
OS 43.65343822 -38.73255652
OS 43.65343822 -38.73902844
OS 43.65251366 -38.74827404
OS 43.30580366 -38.74827404
OS 43.30580366 -38.7491986
OS 43.30580366 -38.75197228
OS 43.30672822 -38.75567052
OS 43.30672822 -38.76121788
OS 43.30765278 -38.7676898
OS 43.3095019 -38.77508628
OS 43.31227558 -38.79172836
OS 43.31782294 -38.81021956
OS 43.32521942 -38.83055988
OS 43.33538958 -38.84905108
OS 43.34833342 -38.86569316
OS 43.34925798 -38.86569316
OS 43.35018254 -38.86754228
OS 43.3557299 -38.87216508
OS 43.36405094 -38.878637
OS 43.37514566 -38.88510892
OS 43.38993862 -38.8925054
OS 43.4065807 -38.89897732
OS 43.4250719 -38.90360012
OS 43.43524206 -38.90452468
OS 43.44633678 -38.90544924
OS 43.45373326 -38.90544924
OS 43.4620543 -38.90452468
OS 43.47222446 -38.90267556
OS 43.48331918 -38.89990188
OS 43.49626302 -38.89620364
OS 43.5082823 -38.89065628
OS 43.52030158 -38.8832598
OS 43.52122614 -38.88233524
OS 43.52584894 -38.878637
OS 43.5313963 -38.87308964
OS 43.53786822 -38.86569316
OS 43.5452647 -38.855523
OS 43.55358574 -38.84257916
OS 43.56190678 -38.8277862
OS 43.56930326 -38.81021956
OS 43.65066454 -38.82038972
OS 43.65066454 -38.82131428
OS 43.64973998 -38.8231634
OS 43.64881542 -38.82686164
OS 43.6469663 -38.832409
OS 43.64419262 -38.83795636
OS 43.64141894 -38.84535284
OS 43.63402246 -38.86107036
OS 43.62477686 -38.878637
OS 43.61183302 -38.8971282
OS 43.59704006 -38.91469484
OS 43.57854886 -38.93133692
OS 43.5776243 -38.93133692
OS 43.57577518 -38.93318604
OS 43.5730015 -38.93503516
OS 43.56930326 -38.93780884
OS 43.5637559 -38.94058252
OS 43.55820854 -38.9433562
OS 43.55081206 -38.94705444
OS 43.54249102 -38.95075268
OS 43.53324542 -38.95445092
OS 43.52399982 -38.95814916
OS 43.50088582 -38.96369652
OS 43.47499814 -38.96831932
OS 43.44633678 -38.97016844
OS 43.43616662 -38.97016844
OS 43.4296947 -38.96924388
OS 43.42137366 -38.96831932
OS 43.4112035 -38.9664702
OS 43.40010878 -38.96462108
OS 43.3880895 -38.96277196
OS 43.36220182 -38.95537548
OS 43.34833342 -38.94982812
OS 43.33538958 -38.94428076
OS 43.32152118 -38.93688428
OS 43.30857734 -38.92856324
OS 43.29655806 -38.91931764
OS 43.28453878 -38.90822292
OS 43.28361422 -38.90729836
OS 43.2817651 -38.90544924
OS 43.27899142 -38.901751
OS 43.27529318 -38.89620364
OS 43.27067038 -38.88973172
OS 43.26604758 -38.88233524
OS 43.26050022 -38.87308964
OS 43.25495286 -38.86291948
OS 43.2494055 -38.8509002
OS 43.24385814 -38.83795636
OS 43.23923534 -38.8231634
OS 43.23461254 -38.80744588
OS 43.2309143 -38.7908038
OS 43.22814062 -38.7723126
OS 43.2262915 -38.75289684
OS 43.22536694 -38.73255652
OS 43.22536694 -38.73163196
OS 43.22536694 -38.72700916
OS 43.22536694 -38.7214618
OS 43.2262915 -38.71314076
OS 43.22721606 -38.7029706
OS 43.22814062 -38.69187588
OS 43.22998974 -38.67893204
OS 43.23276342 -38.6659882
OS 43.2401599 -38.63640228
OS 43.2447827 -38.62160932
OS 43.25033006 -38.6058918
OS 43.25772654 -38.59109884
OS 43.26604758 -38.57723044
OS 43.27529318 -38.56336204
OS 43.28546334 -38.5504182
OS 43.2863879 -38.54949364
OS 43.28823702 -38.54764452
OS 43.29193526 -38.54487084
OS 43.29655806 -38.54024804
OS 43.30210542 -38.53562524
OS 43.3095019 -38.53007788
OS 43.31782294 -38.52360596
OS 43.3279931 -38.5180586
OS 43.33816326 -38.51158668
OS 43.35018254 -38.50603932
OS 43.36312638 -38.50049196
OS 43.37699478 -38.49586916
OS 43.39178774 -38.49124636
OS 43.40750526 -38.48847268
OS 43.42414734 -38.48662356
OS 43.44171398 -38.485699
OS 43.45095958 -38.485699
OS 43.4574315 -38.48662356
OE
OB 43.13938286 -38.48662356 I
OS 43.14955302 -38.48847268
OS 43.1615723 -38.49217092
OS 43.17451614 -38.49679372
OS 43.1893091 -38.50326564
OS 43.20502662 -38.51158668
OS 43.17636526 -38.58370236
OS 43.1754407 -38.5827778
OS 43.17174246 -38.58092868
OS 43.1661951 -38.578155
OS 43.15879862 -38.57538132
OS 43.15047758 -38.57260764
OS 43.14030742 -38.56983396
OS 43.13013726 -38.56798484
OS 43.1199671 -38.56706028
OS 43.1153443 -38.56706028
OS 43.1107215 -38.56798484
OS 43.10424958 -38.5689094
OS 43.09777766 -38.57075852
OS 43.08945662 -38.5735322
OS 43.08113558 -38.57723044
OS 43.0737391 -38.5827778
OS 43.07281454 -38.58370236
OS 43.07004086 -38.58555148
OS 43.06726718 -38.58924972
OS 43.06264438 -38.59387252
OS 43.05802158 -38.60034444
OS 43.05339878 -38.60774092
OS 43.04877598 -38.61606196
OS 43.04507774 -38.62623212
OS 43.04415318 -38.62808124
OS 43.04322862 -38.6336286
OS 43.0413795 -38.64194964
OS 43.03860582 -38.65304436
OS 43.03583214 -38.66691276
OS 43.03398302 -38.68263028
OS 43.03305846 -38.69927236
OS 43.0321339 -38.71776356
OS 43.0321339 -38.95999828
OS 42.9535463 -38.95999828
OS 42.9535463 -38.49586916
OS 43.02473742 -38.49586916
OS 43.02473742 -38.56613572
OS 43.02566198 -38.56521116
OS 43.02936022 -38.55873924
OS 43.03398302 -38.5504182
OS 43.0413795 -38.54024804
OS 43.04877598 -38.53007788
OS 43.05709702 -38.51898316
OS 43.06541806 -38.50973756
OS 43.0737391 -38.50234108
OS 43.07466366 -38.50141652
OS 43.07743734 -38.4995674
OS 43.0829847 -38.49679372
OS 43.08853206 -38.49402004
OS 43.09592854 -38.49124636
OS 43.10517414 -38.48847268
OS 43.11441974 -38.48662356
OS 43.1245899 -38.485699
OS 43.13106182 -38.485699
OS 43.13938286 -38.48662356
OE
OB 43.95022198 -38.95999828 I
OS 43.87533262 -38.95999828
OS 43.70059078 -38.49586916
OS 43.78380118 -38.49586916
OS 43.88365366 -38.77416172
OS 43.88365366 -38.77508628
OS 43.88457822 -38.77601084
OS 43.88550278 -38.77878452
OS 43.88642734 -38.7815582
OS 43.88920102 -38.7908038
OS 43.89289926 -38.80282308
OS 43.89752206 -38.81669148
OS 43.90306942 -38.832409
OS 43.90769222 -38.84997564
OS 43.91323958 -38.86754228
OS 43.91416414 -38.86569316
OS 43.9150887 -38.86107036
OS 43.91786238 -38.85367388
OS 43.92063606 -38.84257916
OS 43.92525886 -38.83055988
OS 43.92988166 -38.81484236
OS 43.93635358 -38.79820028
OS 43.9428255 -38.77970908
OS 44.04545166 -38.49586916
OS 44.12681294 -38.49586916
OS 43.95022198 -38.95999828
OE
OB 44.2756671 -38.40988508 I
OS 44.1970795 -38.40988508
OS 44.1970795 -38.32020276
OS 44.2756671 -38.32020276
OS 44.2756671 -38.40988508
OE
OB 44.5669035 -38.48662356 I
OS 44.5807719 -38.48754812
OS 44.59556486 -38.48939724
OS 44.61128238 -38.49309548
OS 44.62792446 -38.49679372
OS 44.64364198 -38.50234108
OS 44.64456654 -38.50234108
OS 44.6454911 -38.50326564
OS 44.6501139 -38.50511476
OS 44.65751038 -38.508813
OS 44.66675598 -38.5134358
OS 44.67692614 -38.51990772
OS 44.6870963 -38.5273042
OS 44.6963419 -38.53562524
OS 44.70466294 -38.54487084
OS 44.7055875 -38.5457954
OS 44.70743662 -38.54949364
OS 44.71113486 -38.55596556
OS 44.71575766 -38.56336204
OS 44.72038046 -38.57445676
OS 44.72500326 -38.58647604
OS 44.7287015 -38.60034444
OS 44.73239974 -38.61606196
OS 44.65566126 -38.62623212
OS 44.65566126 -38.624383
OS 44.6547367 -38.62068476
OS 44.65288758 -38.61421284
OS 44.6501139 -38.6058918
OS 44.6454911 -38.59757076
OS 44.63994374 -38.58832516
OS 44.63347182 -38.57907956
OS 44.62422622 -38.57075852
OS 44.62330166 -38.56983396
OS 44.61960342 -38.56798484
OS 44.61405606 -38.5642866
OS 44.60573502 -38.56058836
OS 44.59648942 -38.55689012
OS 44.58447014 -38.55319188
OS 44.56967718 -38.55134276
OS 44.55395966 -38.5504182
OS 44.54471406 -38.5504182
OS 44.53546846 -38.55134276
OS 44.52344918 -38.55226732
OS 44.5114299 -38.555041
OS 44.49848606 -38.55781468
OS 44.48646678 -38.56243748
OS 44.47629662 -38.5689094
OS 44.47537206 -38.56983396
OS 44.47259838 -38.57168308
OS 44.46890014 -38.57538132
OS 44.4652019 -38.58092868
OS 44.4605791 -38.58647604
OS 44.45688086 -38.59387252
OS 44.45410718 -38.60219356
OS 44.45318262 -38.6105146
OS 44.45318262 -38.61143916
OS 44.45318262 -38.61328828
OS 44.45410718 -38.61606196
OS 44.45410718 -38.6197602
OS 44.45688086 -38.6290058
OS 44.46242822 -38.6382514
OS 44.46335278 -38.63917596
OS 44.46427734 -38.64010052
OS 44.46612646 -38.6428742
OS 44.4698247 -38.64564788
OS 44.47352294 -38.64842156
OS 44.4790703 -38.6521198
OS 44.48554222 -38.65489348
OS 44.4929387 -38.65859172
OS 44.49386326 -38.65859172
OS 44.49571238 -38.65951628
OS 44.49941062 -38.66044084
OS 44.50588254 -38.66321452
OS 44.51512814 -38.6659882
OS 44.52714742 -38.66876188
OS 44.5345439 -38.67153556
OS 44.54286494 -38.67338468
OS 44.55211054 -38.67615836
OS 44.5622807 -38.67893204
OS 44.56320526 -38.67893204
OS 44.56597894 -38.6798566
OS 44.57060174 -38.68078116
OS 44.5761491 -38.68263028
OS 44.58262102 -38.6844794
OS 44.59094206 -38.68632852
OS 44.6085087 -38.69187588
OS 44.62792446 -38.69742324
OS 44.64734022 -38.70389516
OS 44.66490686 -38.71036708
OS 44.67230334 -38.71314076
OS 44.67877526 -38.71591444
OS 44.68062438 -38.716839
OS 44.68432262 -38.71868812
OS 44.68986998 -38.7214618
OS 44.69819102 -38.7260846
OS 44.70651206 -38.73163196
OS 44.7148331 -38.73902844
OS 44.72315414 -38.74734948
OS 44.73055062 -38.75659508
OS 44.73147518 -38.75751964
OS 44.7333243 -38.76121788
OS 44.73702254 -38.76676524
OS 44.74072078 -38.77508628
OS 44.74349446 -38.78525644
OS 44.7471927 -38.79635116
OS 44.74904182 -38.809295
OS 44.74996638 -38.82408796
OS 44.74996638 -38.82593708
OS 44.74996638 -38.83055988
OS 44.74904182 -38.83795636
OS 44.7471927 -38.84812652
OS 44.74441902 -38.85922124
OS 44.73979622 -38.87124052
OS 44.73424886 -38.88510892
OS 44.72685238 -38.89805276
OS 44.72592782 -38.89990188
OS 44.72222958 -38.90360012
OS 44.71760678 -38.91007204
OS 44.7102103 -38.91746852
OS 44.70004014 -38.92578956
OS 44.68894542 -38.93503516
OS 44.67600158 -38.9433562
OS 44.66028406 -38.95167724
OS 44.6593595 -38.95167724
OS 44.65843494 -38.9526018
OS 44.65288758 -38.95445092
OS 44.64364198 -38.9572246
OS 44.6316227 -38.96092284
OS 44.61682974 -38.96462108
OS 44.60018766 -38.96739476
OS 44.58262102 -38.96924388
OS 44.5622807 -38.97016844
OS 44.55395966 -38.97016844
OS 44.54748774 -38.96924388
OS 44.54009126 -38.96924388
OS 44.53084566 -38.96831932
OS 44.52160006 -38.96739476
OS 44.5114299 -38.96554564
OS 44.48924046 -38.96092284
OS 44.46612646 -38.95445092
OS 44.44393702 -38.94520532
OS 44.43376686 -38.93965796
OS 44.42452126 -38.93318604
OS 44.4235967 -38.93226148
OS 44.42267214 -38.93133692
OS 44.41712478 -38.92578956
OS 44.40880374 -38.91746852
OS 44.39955814 -38.90452468
OS 44.38938798 -38.88880716
OS 44.37921782 -38.87031596
OS 44.37089678 -38.84720196
OS 44.36442486 -38.82131428
OS 44.4420879 -38.809295
OS 44.4420879 -38.81021956
OS 44.4420879 -38.81114412
OS 44.44393702 -38.81669148
OS 44.44578614 -38.82593708
OS 44.44948438 -38.83610724
OS 44.45410718 -38.84720196
OS 44.45965454 -38.85922124
OS 44.46797558 -38.87124052
OS 44.47814574 -38.88141068
OS 44.47999486 -38.88233524
OS 44.4836931 -38.88510892
OS 44.49108958 -38.88880716
OS 44.50033518 -38.89342996
OS 44.51235446 -38.89805276
OS 44.52622286 -38.901751
OS 44.54286494 -38.90452468
OS 44.5622807 -38.90544924
OS 44.5715263 -38.90544924
OS 44.5807719 -38.90452468
OS 44.59279118 -38.90267556
OS 44.60573502 -38.89990188
OS 44.61960342 -38.89620364
OS 44.6316227 -38.89158084
OS 44.64271742 -38.88418436
OS 44.64364198 -38.8832598
OS 44.64734022 -38.88048612
OS 44.65103846 -38.87586332
OS 44.65658582 -38.8693914
OS 44.66120862 -38.86199492
OS 44.66583142 -38.85274932
OS 44.6686051 -38.84350372
OS 44.66952966 -38.832409
OS 44.66952966 -38.83148444
OS 44.66952966 -38.8277862
OS 44.6686051 -38.8231634
OS 44.66675598 -38.81669148
OS 44.6639823 -38.81021956
OS 44.6593595 -38.80374764
OS 44.65381214 -38.79635116
OS 44.6454911 -38.7908038
OS 44.64456654 -38.78987924
OS 44.64179286 -38.78895468
OS 44.63717006 -38.786181
OS 44.62977358 -38.78340732
OS 44.61867886 -38.77970908
OS 44.61220694 -38.7769354
OS 44.60481046 -38.77508628
OS 44.59648942 -38.7723126
OS 44.58724382 -38.76953892
OS 44.57707366 -38.76676524
OS 44.56505438 -38.76399156
OS 44.56412982 -38.76399156
OS 44.56135614 -38.763067
OS 44.55673334 -38.76214244
OS 44.55118598 -38.76029332
OS 44.5437895 -38.7584442
OS 44.53546846 -38.75567052
OS 44.51790182 -38.75104772
OS 44.4975615 -38.7445758
OS 44.47814574 -38.73902844
OS 44.45965454 -38.73255652
OS 44.4513335 -38.72885828
OS 44.44486158 -38.7260846
OS 44.44301246 -38.72516004
OS 44.43931422 -38.72331092
OS 44.43376686 -38.71961268
OS 44.42637038 -38.71498988
OS 44.41804934 -38.70851796
OS 44.4097283 -38.70112148
OS 44.40140726 -38.69280044
OS 44.39401078 -38.68263028
OS 44.39308622 -38.68170572
OS 44.3912371 -38.67800748
OS 44.38846342 -38.67153556
OS 44.38568974 -38.66413908
OS 44.38291606 -38.65489348
OS 44.38014238 -38.64379876
OS 44.37829326 -38.63270404
OS 44.3773687 -38.6197602
OS 44.3773687 -38.61791108
OS 44.3773687 -38.61421284
OS 44.37829326 -38.60866548
OS 44.37921782 -38.60034444
OS 44.38106694 -38.5920234
OS 44.38291606 -38.58185324
OS 44.3866143 -38.57260764
OS 44.3912371 -38.56243748
OS 44.39216166 -38.56151292
OS 44.39401078 -38.55781468
OS 44.39678446 -38.55319188
OS 44.40140726 -38.54671996
OS 44.40695462 -38.54024804
OS 44.41342654 -38.531927
OS 44.42082302 -38.52453052
OS 44.43006862 -38.5180586
OS 44.43099318 -38.51713404
OS 44.43376686 -38.51620948
OS 44.4374651 -38.5134358
OS 44.44301246 -38.51066212
OS 44.45040894 -38.50696388
OS 44.45872998 -38.50326564
OS 44.46890014 -38.4995674
OS 44.47999486 -38.49586916
OS 44.48184398 -38.4949446
OS 44.48554222 -38.49402004
OS 44.49201414 -38.49217092
OS 44.50033518 -38.4903218
OS 44.51050534 -38.48847268
OS 44.52160006 -38.48754812
OS 44.5345439 -38.485699
OS 44.55673334 -38.485699
OS 44.5669035 -38.48662356
OE
OB 33.15968222 -38.32112732 I
OS 33.17539974 -38.32205188
OS 33.19204182 -38.32297644
OS 33.20775934 -38.32482556
OS 33.22162774 -38.32667468
OS 33.22347686 -38.32667468
OS 33.22994878 -38.3285238
OS 33.23826982 -38.33037292
OS 33.24936454 -38.3331466
OS 33.26138382 -38.3377694
OS 33.27432766 -38.34331676
OS 33.28819606 -38.34978868
OS 33.30021534 -38.35718516
OS 33.30206446 -38.35810972
OS 33.3057627 -38.3608834
OS 33.31131006 -38.36643076
OS 33.31870654 -38.37290268
OS 33.32702758 -38.38122372
OS 33.33534862 -38.39231844
OS 33.34459422 -38.40433772
OS 33.3519907 -38.41820612
OS 33.35291526 -38.42005524
OS 33.35476438 -38.42467804
OS 33.35846262 -38.43299908
OS 33.36216086 -38.4440938
OS 33.36493454 -38.45703764
OS 33.36863278 -38.4718306
OS 33.3704819 -38.48847268
OS 33.37140646 -38.50603932
OS 33.37140646 -38.50696388
OS 33.37140646 -38.50973756
OS 33.37140646 -38.5134358
OS 33.3704819 -38.51990772
OS 33.36955734 -38.52637964
OS 33.36863278 -38.53470068
OS 33.36678366 -38.54394628
OS 33.36493454 -38.55411644
OS 33.35846262 -38.57538132
OS 33.35476438 -38.58647604
OS 33.34921702 -38.59849532
OS 33.3427451 -38.6105146
OS 33.33627318 -38.62160932
OS 33.32795214 -38.63270404
OS 33.31870654 -38.64379876
OS 33.31778198 -38.64472332
OS 33.31593286 -38.64657244
OS 33.31315918 -38.64934612
OS 33.30853638 -38.6521198
OS 33.30298902 -38.6567426
OS 33.29559254 -38.6613654
OS 33.28634694 -38.66691276
OS 33.27617678 -38.67153556
OS 33.2641575 -38.67708292
OS 33.2502891 -38.68263028
OS 33.23549614 -38.68725308
OS 33.2179295 -38.69095132
OS 33.1994383 -38.69464956
OS 33.17909798 -38.69742324
OS 33.15598398 -38.69927236
OS 33.13194542 -38.70019692
OS 32.9682983 -38.70019692
OS 32.9682983 -38.95999828
OS 32.88323878 -38.95999828
OS 32.88323878 -38.32020276
OS 33.14581382 -38.32020276
OS 33.15968222 -38.32112732
OE
OB 32.75195126 -38.98403684 I
OS 32.75195126 -38.9849614
OS 32.75195126 -38.98773508
OS 32.75195126 -38.99235788
OS 32.75195126 -38.99790524
OS 32.7510267 -39.00530172
OS 32.7510267 -39.0126982
OS 32.74917758 -39.0311894
OS 32.7464039 -39.05060516
OS 32.74270566 -39.07094548
OS 32.7371583 -39.08851212
OS 32.73346006 -39.09683316
OS 32.72976182 -39.10330508
OS 32.72976182 -39.10422964
OS 32.72883726 -39.1051542
OS 32.72421446 -39.109777
OS 32.71681798 -39.11717348
OS 32.70757238 -39.12549452
OS 32.69462854 -39.13381556
OS 32.67798646 -39.14028748
OS 32.6585707 -39.14583484
OS 32.64747598 -39.1467594
OS 32.6354567 -39.14768396
OS 32.62990934 -39.14768396
OS 32.62436198 -39.1467594
OS 32.61604094 -39.1467594
OS 32.60679534 -39.14583484
OS 32.59662518 -39.14398572
OS 32.57443574 -39.13843836
OS 32.5892287 -39.07187004
OS 32.59015326 -39.07187004
OS 32.59292694 -39.0727946
OS 32.59754974 -39.07371916
OS 32.60217254 -39.07464372
OS 32.61419182 -39.0774174
OS 32.61973918 -39.07834196
OS 32.62898478 -39.07834196
OS 32.63360758 -39.0774174
OS 32.63915494 -39.07649284
OS 32.6447023 -39.07464372
OS 32.65024966 -39.07094548
OS 32.65672158 -39.06724724
OS 32.66134438 -39.06169988
OS 32.66226894 -39.06077532
OS 32.6631935 -39.05800164
OS 32.66504262 -39.05337884
OS 32.6678163 -39.04598236
OS 32.66966542 -39.0358122
OS 32.67058998 -39.02841572
OS 32.67151454 -39.0219438
OS 32.6724391 -39.01362276
OS 32.6724391 -39.0034526
OS 32.67336366 -38.99328244
OS 32.67336366 -38.98218772
OS 32.67336366 -38.49586916
OS 32.75195126 -38.49586916
OS 32.75195126 -38.98403684
OE
OB 33.77174094 -38.3100326 I
OS 33.78006198 -38.31095716
OS 33.79023214 -38.31188172
OS 33.8004023 -38.31280628
OS 33.81242158 -38.31557996
OS 33.8373847 -38.32112732
OS 33.8651215 -38.32944836
OS 33.8789899 -38.33499572
OS 33.89193374 -38.34146764
OS 33.90487758 -38.34978868
OS 33.91782142 -38.35810972
OS 33.91874598 -38.35903428
OS 33.9205951 -38.35995884
OS 33.92429334 -38.36273252
OS 33.92891614 -38.36735532
OS 33.93353894 -38.37197812
OS 33.94001086 -38.37845004
OS 33.94648278 -38.38584652
OS 33.95387926 -38.393243
OS 33.96127574 -38.4024886
OS 33.96867222 -38.41358332
OS 33.97699326 -38.42467804
OS 33.98438974 -38.43669732
OS 33.99086166 -38.45056572
OS 33.99825814 -38.46443412
OS 34.0038055 -38.47922708
OS 34.00935286 -38.49586916
OS 33.92614246 -38.51528492
OS 33.92614246 -38.51436036
OS 33.9252179 -38.51251124
OS 33.92336878 -38.508813
OS 33.92151966 -38.5041902
OS 33.91967054 -38.49864284
OS 33.91689686 -38.49124636
OS 33.90950038 -38.4764534
OS 33.90025478 -38.45981132
OS 33.88916006 -38.44316924
OS 33.87529166 -38.42745172
OS 33.8604987 -38.41358332
OS 33.85864958 -38.4117342
OS 33.85310222 -38.40803596
OS 33.84385662 -38.40341316
OS 33.83183734 -38.39694124
OS 33.81611982 -38.39139388
OS 33.79855318 -38.38584652
OS 33.7772883 -38.38214828
OS 33.7541743 -38.38122372
OS 33.74677782 -38.38122372
OS 33.74215502 -38.38214828
OS 33.7356831 -38.38214828
OS 33.72828662 -38.38307284
OS 33.71071998 -38.38584652
OS 33.69130422 -38.38954476
OS 33.6709639 -38.39601668
OS 33.64969902 -38.40526228
OS 33.63028326 -38.41728156
OS 33.6293587 -38.41728156
OS 33.62843414 -38.41913068
OS 33.62196222 -38.42375348
OS 33.61364118 -38.43114996
OS 33.60347102 -38.44224468
OS 33.59145174 -38.45611308
OS 33.58035702 -38.4718306
OS 33.57018686 -38.49124636
OS 33.56094126 -38.51251124
OS 33.56094126 -38.5134358
OS 33.5600167 -38.51528492
OS 33.55909214 -38.5180586
OS 33.55816758 -38.5226814
OS 33.55631846 -38.52822876
OS 33.55446934 -38.53470068
OS 33.55169566 -38.5504182
OS 33.54799742 -38.5689094
OS 33.54429918 -38.58924972
OS 33.54245006 -38.61143916
OS 33.5415255 -38.63547772
OS 33.5415255 -38.63640228
OS 33.5415255 -38.63917596
OS 33.5415255 -38.64379876
OS 33.5415255 -38.64934612
OS 33.54245006 -38.65581804
OS 33.54245006 -38.66413908
OS 33.54337462 -38.67338468
OS 33.54429918 -38.68355484
OS 33.54707286 -38.70574428
OS 33.55169566 -38.72978284
OS 33.55724302 -38.7538214
OS 33.5646395 -38.77785996
OS 33.5646395 -38.77878452
OS 33.56556406 -38.78063364
OS 33.56741318 -38.78340732
OS 33.5692623 -38.78803012
OS 33.57480966 -38.79912484
OS 33.5831307 -38.81206868
OS 33.59330086 -38.82686164
OS 33.6062447 -38.84257916
OS 33.62103766 -38.85644756
OS 33.6386043 -38.8693914
OS 33.63952886 -38.8693914
OS 33.64137798 -38.87031596
OS 33.64415166 -38.87216508
OS 33.6478499 -38.8740142
OS 33.6524727 -38.87586332
OS 33.65802006 -38.878637
OS 33.6709639 -38.88418436
OS 33.68760598 -38.88973172
OS 33.70609718 -38.89435452
OS 33.7264375 -38.89805276
OS 33.74770238 -38.89897732
OS 33.7541743 -38.89897732
OS 33.75972166 -38.89805276
OS 33.76619358 -38.89805276
OS 33.7726655 -38.8971282
OS 33.78930758 -38.89342996
OS 33.80872334 -38.88880716
OS 33.8281391 -38.88141068
OS 33.84847942 -38.87124052
OS 33.85864958 -38.86569316
OS 33.86789518 -38.85829668
OS 33.86881974 -38.85737212
OS 33.8697443 -38.85644756
OS 33.87251798 -38.85367388
OS 33.87621622 -38.8509002
OS 33.87991446 -38.8462774
OS 33.88453726 -38.84073004
OS 33.89008462 -38.83518268
OS 33.89470742 -38.8277862
OS 33.90025478 -38.81946516
OS 33.9067267 -38.81021956
OS 33.91227406 -38.80097396
OS 33.91782142 -38.78987924
OS 33.92244422 -38.77785996
OS 33.92706702 -38.76491612
OS 33.93168982 -38.75104772
OS 33.93538806 -38.73625476
OS 34.02044758 -38.75751964
OS 34.02044758 -38.7584442
OS 34.01952302 -38.76214244
OS 34.0176739 -38.7676898
OS 34.01490022 -38.77508628
OS 34.01212654 -38.78340732
OS 34.0084283 -38.79357748
OS 34.0038055 -38.8046722
OS 33.99825814 -38.81669148
OS 33.9853143 -38.84257916
OS 33.96867222 -38.86846684
OS 33.95850206 -38.88141068
OS 33.9483319 -38.89435452
OS 33.93723718 -38.90544924
OS 33.92429334 -38.91654396
OS 33.92336878 -38.91746852
OS 33.92151966 -38.91931764
OS 33.91689686 -38.92116676
OS 33.91227406 -38.924865
OS 33.90487758 -38.9294878
OS 33.8974811 -38.9341106
OS 33.88731094 -38.9387334
OS 33.87714078 -38.9433562
OS 33.8651215 -38.94890356
OS 33.85217766 -38.95352636
OS 33.83830926 -38.95814916
OS 33.8235163 -38.96277196
OS 33.80779878 -38.9664702
OS 33.7911567 -38.96831932
OS 33.77359006 -38.97016844
OS 33.75509886 -38.971093
OS 33.7449287 -38.971093
OS 33.73753222 -38.97016844
OS 33.72921118 -38.97016844
OS 33.71904102 -38.96924388
OS 33.7079463 -38.96739476
OS 33.69500246 -38.96554564
OS 33.66819022 -38.96092284
OS 33.64045342 -38.95352636
OS 33.61271662 -38.9433562
OS 33.59977278 -38.93688428
OS 33.58682894 -38.9294878
OS 33.58590438 -38.92856324
OS 33.58405526 -38.92763868
OS 33.58035702 -38.924865
OS 33.57665878 -38.92116676
OS 33.57111142 -38.91746852
OS 33.5646395 -38.91192116
OS 33.55724302 -38.90544924
OS 33.54984654 -38.89805276
OS 33.54245006 -38.88973172
OS 33.53412902 -38.88141068
OS 33.51748694 -38.8601458
OS 33.50176942 -38.83518268
OS 33.48790102 -38.80744588
OS 33.48790102 -38.80652132
OS 33.4860519 -38.80374764
OS 33.48512734 -38.79912484
OS 33.48235366 -38.79357748
OS 33.48050454 -38.786181
OS 33.47773086 -38.7769354
OS 33.47403262 -38.76676524
OS 33.47125894 -38.75567052
OS 33.46848526 -38.74365124
OS 33.46478702 -38.72978284
OS 33.46016422 -38.70112148
OS 33.45646598 -38.66876188
OS 33.45461686 -38.63547772
OS 33.45461686 -38.63455316
OS 33.45461686 -38.63085492
OS 33.45461686 -38.62530756
OS 33.45554142 -38.61883564
OS 33.45554142 -38.60959004
OS 33.45646598 -38.60034444
OS 33.45739054 -38.58832516
OS 33.45923966 -38.57630588
OS 33.46386246 -38.54949364
OS 33.47033438 -38.51990772
OS 33.47957998 -38.4903218
OS 33.49252382 -38.46166044
OS 33.49344838 -38.46073588
OS 33.49437294 -38.4579622
OS 33.49622206 -38.45426396
OS 33.4999203 -38.44964116
OS 33.50361854 -38.44316924
OS 33.50824134 -38.43577276
OS 33.52026062 -38.41913068
OS 33.53597814 -38.40063948
OS 33.55446934 -38.38214828
OS 33.57573422 -38.36365708
OS 33.60069734 -38.34793956
OS 33.6016219 -38.347015
OS 33.60439558 -38.34609044
OS 33.60809382 -38.34424132
OS 33.61271662 -38.34146764
OS 33.6201131 -38.33869396
OS 33.62750958 -38.33592028
OS 33.63675518 -38.33222204
OS 33.64692534 -38.3285238
OS 33.65802006 -38.32482556
OS 33.67003934 -38.32112732
OS 33.69592702 -38.31557996
OS 33.72551294 -38.31095716
OS 33.75602342 -38.30910804
OS 33.76526902 -38.30910804
OS 33.77174094 -38.3100326
OE
OB 35.15858094 -39.1375138 I
OS 34.63805366 -39.1375138
OS 34.63805366 -39.08111564
OS 35.15858094 -39.08111564
OS 35.15858094 -39.1375138
OE
OB 34.37917686 -38.32112732 I
OS 34.38657334 -38.32112732
OS 34.40321542 -38.32297644
OS 34.42170662 -38.32482556
OS 34.44112238 -38.3285238
OS 34.46053814 -38.3331466
OS 34.47810478 -38.33961852
OS 34.47902934 -38.33961852
OS 34.4799539 -38.34054308
OS 34.48550126 -38.34331676
OS 34.4938223 -38.34793956
OS 34.5030679 -38.35441148
OS 34.51416262 -38.36273252
OS 34.5261819 -38.37290268
OS 34.53727662 -38.38584652
OS 34.54744678 -38.39971492
OS 34.54837134 -38.40156404
OS 34.55114502 -38.4071114
OS 34.55576782 -38.41450788
OS 34.56039062 -38.4256026
OS 34.56501342 -38.43854644
OS 34.56963622 -38.45241484
OS 34.5724099 -38.46813236
OS 34.57333446 -38.48384988
OS 34.57333446 -38.485699
OS 34.57333446 -38.4903218
OS 34.5724099 -38.49864284
OS 34.57056078 -38.508813
OS 34.5677871 -38.52083228
OS 34.5631643 -38.53377612
OS 34.55761694 -38.54671996
OS 34.55022046 -38.56058836
OS 34.5492959 -38.56243748
OS 34.54652222 -38.56613572
OS 34.54097486 -38.5735322
OS 34.53357838 -38.58092868
OS 34.52433278 -38.59017428
OS 34.51323806 -38.60034444
OS 34.49936966 -38.60959004
OS 34.48365214 -38.61883564
OS 34.4845767 -38.61883564
OS 34.48642582 -38.6197602
OS 34.4891995 -38.62068476
OS 34.49289774 -38.62253388
OS 34.50399246 -38.62623212
OS 34.5169363 -38.63270404
OS 34.5308047 -38.64102508
OS 34.54652222 -38.65119524
OS 34.56039062 -38.66321452
OS 34.57333446 -38.67800748
OS 34.57425902 -38.6798566
OS 34.57795726 -38.68540396
OS 34.58350462 -38.693725
OS 34.58905198 -38.70481972
OS 34.59459934 -38.71961268
OS 34.6001467 -38.7353302
OS 34.60384494 -38.7538214
OS 34.6047695 -38.77416172
OS 34.6047695 -38.77508628
OS 34.6047695 -38.77601084
OS 34.6047695 -38.7815582
OS 34.60384494 -38.7908038
OS 34.60199582 -38.80189852
OS 34.6001467 -38.81484236
OS 34.59644846 -38.82871076
OS 34.59182566 -38.84350372
OS 34.58535374 -38.85829668
OS 34.58442918 -38.8601458
OS 34.5816555 -38.8647686
OS 34.57795726 -38.87124052
OS 34.5724099 -38.88048612
OS 34.56501342 -38.88973172
OS 34.55761694 -38.89990188
OS 34.54837134 -38.91007204
OS 34.53820118 -38.91839308
OS 34.53727662 -38.91931764
OS 34.53357838 -38.92209132
OS 34.52710646 -38.92578956
OS 34.51878542 -38.9294878
OS 34.50861526 -38.93503516
OS 34.49659598 -38.94058252
OS 34.48365214 -38.94520532
OS 34.46793462 -38.94982812
OS 34.4660855 -38.94982812
OS 34.46053814 -38.95167724
OS 34.45129254 -38.9526018
OS 34.43927326 -38.95445092
OS 34.4244803 -38.95630004
OS 34.40691366 -38.95814916
OS 34.3874979 -38.95907372
OS 34.36530846 -38.95999828
OS 34.12122462 -38.95999828
OS 34.12122462 -38.32020276
OS 34.37270494 -38.32020276
OS 34.37917686 -38.32112732
OE
OB 31.74233174 -38.95999828 I
OS 31.65264942 -38.95999828
OS 31.65264942 -38.87031596
OS 31.74233174 -38.87031596
OS 31.74233174 -38.95999828
OE
OB 31.52968294 -38.42745172 I
OS 31.50841806 -38.54671996
OS 31.45941638 -38.54671996
OS 31.44000062 -38.42745172
OS 31.44000062 -38.32020276
OS 31.52968294 -38.32020276
OS 31.52968294 -38.42745172
OE
OB 32.0992119 -38.48662356 I
OS 32.10568382 -38.48754812
OS 32.11955222 -38.48939724
OS 32.1361943 -38.49309548
OS 32.15376094 -38.49864284
OS 32.17132758 -38.50696388
OS 32.18889422 -38.51713404
OS 32.18981878 -38.51713404
OS 32.19074334 -38.51898316
OS 32.1962907 -38.5226814
OS 32.20461174 -38.53007788
OS 32.2147819 -38.53932348
OS 32.22587662 -38.55134276
OS 32.23697134 -38.56613572
OS 32.24806606 -38.58370236
OS 32.25731166 -38.60311812
OS 32.25731166 -38.60404268
OS 32.25823622 -38.6058918
OS 32.25916078 -38.60866548
OS 32.2610099 -38.61236372
OS 32.26285902 -38.61791108
OS 32.26470814 -38.624383
OS 32.26933094 -38.63917596
OS 32.27395374 -38.65766716
OS 32.27765198 -38.67800748
OS 32.28042566 -38.70112148
OS 32.28135022 -38.72516004
OS 32.28135022 -38.7260846
OS 32.28135022 -38.72793372
OS 32.28135022 -38.73163196
OS 32.28135022 -38.73717932
OS 32.28042566 -38.74365124
OS 32.28042566 -38.75104772
OS 32.27857654 -38.7676898
OS 32.2748783 -38.78803012
OS 32.2702555 -38.809295
OS 32.26378358 -38.83148444
OS 32.25546254 -38.85367388
OS 32.25546254 -38.85459844
OS 32.25453798 -38.85644756
OS 32.25268886 -38.85922124
OS 32.25083974 -38.86291948
OS 32.24436782 -38.87308964
OS 32.23604678 -38.88603348
OS 32.22587662 -38.89990188
OS 32.21293278 -38.91377028
OS 32.19813982 -38.92763868
OS 32.18057318 -38.94058252
OS 32.17964862 -38.94058252
OS 32.17872406 -38.94150708
OS 32.17595038 -38.9433562
OS 32.17225214 -38.94520532
OS 32.16300654 -38.94982812
OS 32.1500627 -38.95537548
OS 32.13434518 -38.96092284
OS 32.1177031 -38.96554564
OS 32.09828734 -38.96924388
OS 32.07887158 -38.97016844
OS 32.07239966 -38.97016844
OS 32.06500318 -38.96924388
OS 32.05575758 -38.96831932
OS 32.04466286 -38.9664702
OS 32.03264358 -38.96369652
OS 32.0206243 -38.95999828
OS 32.00860502 -38.95445092
OS 32.00768046 -38.95352636
OS 32.00305766 -38.95167724
OS 31.9975103 -38.947979
OS 31.99011382 -38.94243164
OS 31.98271734 -38.93688428
OS 31.97347174 -38.9294878
OS 31.9651507 -38.92116676
OS 31.95775422 -38.91192116
OS 31.95775422 -39.1375138
OS 31.87916662 -39.1375138
OS 31.87916662 -38.49586916
OS 31.95035774 -38.49586916
OS 31.95035774 -38.55689012
OS 31.9512823 -38.555041
OS 31.95498054 -38.55134276
OS 31.95960334 -38.54487084
OS 31.96699982 -38.53747436
OS 31.97532086 -38.52822876
OS 31.98456646 -38.51990772
OS 31.99566118 -38.51158668
OS 32.0067559 -38.5041902
OS 32.00860502 -38.50326564
OS 32.01230326 -38.50141652
OS 32.01969974 -38.49864284
OS 32.02894534 -38.4949446
OS 32.04004006 -38.49124636
OS 32.0529839 -38.48847268
OS 32.06777686 -38.48662356
OS 32.08441894 -38.485699
OS 32.0945891 -38.485699
OS 32.0992119 -38.48662356
OE
OB 32.5614919 -38.48662356 I
OS 32.57166206 -38.48847268
OS 32.58368134 -38.49217092
OS 32.59662518 -38.49679372
OS 32.61141814 -38.50326564
OS 32.62713566 -38.51158668
OS 32.5984743 -38.58370236
OS 32.59754974 -38.5827778
OS 32.5938515 -38.58092868
OS 32.58830414 -38.578155
OS 32.58090766 -38.57538132
OS 32.57258662 -38.57260764
OS 32.56241646 -38.56983396
OS 32.5522463 -38.56798484
OS 32.54207614 -38.56706028
OS 32.53745334 -38.56706028
OS 32.53283054 -38.56798484
OS 32.52635862 -38.5689094
OS 32.5198867 -38.57075852
OS 32.51156566 -38.5735322
OS 32.50324462 -38.57723044
OS 32.49584814 -38.5827778
OS 32.49492358 -38.58370236
OS 32.4921499 -38.58555148
OS 32.48937622 -38.58924972
OS 32.48475342 -38.59387252
OS 32.48013062 -38.60034444
OS 32.47550782 -38.60774092
OS 32.47088502 -38.61606196
OS 32.46718678 -38.62623212
OS 32.46626222 -38.62808124
OS 32.46533766 -38.6336286
OS 32.46348854 -38.64194964
OS 32.46071486 -38.65304436
OS 32.45794118 -38.66691276
OS 32.45609206 -38.68263028
OS 32.4551675 -38.69927236
OS 32.45424294 -38.71776356
OS 32.45424294 -38.95999828
OS 32.37565534 -38.95999828
OS 32.37565534 -38.49586916
OS 32.44684646 -38.49586916
OS 32.44684646 -38.56613572
OS 32.44777102 -38.56521116
OS 32.45146926 -38.55873924
OS 32.45609206 -38.5504182
OS 32.46348854 -38.54024804
OS 32.47088502 -38.53007788
OS 32.47920606 -38.51898316
OS 32.4875271 -38.50973756
OS 32.49584814 -38.50234108
OS 32.4967727 -38.50141652
OS 32.49954638 -38.4995674
OS 32.50509374 -38.49679372
OS 32.5106411 -38.49402004
OS 32.51803758 -38.49124636
OS 32.52728318 -38.48847268
OS 32.53652878 -38.48662356
OS 32.54669894 -38.485699
OS 32.55317086 -38.485699
OS 32.5614919 -38.48662356
OE
OB 32.75195126 -38.4117342 I
OS 32.67336366 -38.4117342
OS 32.67336366 -38.32020276
OS 32.75195126 -38.32020276
OS 32.75195126 -38.4117342
OE
OB 36.56668582 -38.95999828 I
OS 36.47885262 -38.95999828
OS 36.1441619 -38.4579622
OS 36.1441619 -38.95999828
OS 36.06280062 -38.95999828
OS 36.06280062 -38.32020276
OS 36.14970926 -38.32020276
OS 36.48532454 -38.8231634
OS 36.48532454 -38.32020276
OS 36.56668582 -38.32020276
OS 36.56668582 -38.95999828
OE
OB 35.74382742 -38.32112732 I
OS 35.75954494 -38.32205188
OS 35.77618702 -38.32297644
OS 35.79190454 -38.32482556
OS 35.80577294 -38.32667468
OS 35.80762206 -38.32667468
OS 35.81409398 -38.3285238
OS 35.82241502 -38.33037292
OS 35.83350974 -38.3331466
OS 35.84552902 -38.3377694
OS 35.85847286 -38.34331676
OS 35.87234126 -38.34978868
OS 35.88436054 -38.35718516
OS 35.88620966 -38.35810972
OS 35.8899079 -38.3608834
OS 35.89545526 -38.36643076
OS 35.90285174 -38.37290268
OS 35.91117278 -38.38122372
OS 35.91949382 -38.39231844
OS 35.92873942 -38.40433772
OS 35.9361359 -38.41820612
OS 35.93706046 -38.42005524
OS 35.93890958 -38.42467804
OS 35.94260782 -38.43299908
OS 35.94630606 -38.4440938
OS 35.94907974 -38.45703764
OS 35.95277798 -38.4718306
OS 35.9546271 -38.48847268
OS 35.95555166 -38.50603932
OS 35.95555166 -38.50696388
OS 35.95555166 -38.50973756
OS 35.95555166 -38.5134358
OS 35.9546271 -38.51990772
OS 35.95370254 -38.52637964
OS 35.95277798 -38.53470068
OS 35.95092886 -38.54394628
OS 35.94907974 -38.55411644
OS 35.94260782 -38.57538132
OS 35.93890958 -38.58647604
OS 35.93336222 -38.59849532
OS 35.9268903 -38.6105146
OS 35.92041838 -38.62160932
OS 35.91209734 -38.63270404
OS 35.90285174 -38.64379876
OS 35.90192718 -38.64472332
OS 35.90007806 -38.64657244
OS 35.89730438 -38.64934612
OS 35.89268158 -38.6521198
OS 35.88713422 -38.6567426
OS 35.87973774 -38.6613654
OS 35.87049214 -38.66691276
OS 35.86032198 -38.67153556
OS 35.8483027 -38.67708292
OS 35.8344343 -38.68263028
OS 35.81964134 -38.68725308
OS 35.8020747 -38.69095132
OS 35.7835835 -38.69464956
OS 35.76324318 -38.69742324
OS 35.74012918 -38.69927236
OS 35.71609062 -38.70019692
OS 35.5524435 -38.70019692
OS 35.5524435 -38.95999828
OS 35.46738398 -38.95999828
OS 35.46738398 -38.32020276
OS 35.72995902 -38.32020276
OS 35.74382742 -38.32112732
OE
OB 36.76916446 -38.42745172 I
OS 36.74789958 -38.54671996
OS 36.6988979 -38.54671996
OS 36.67948214 -38.42745172
OS 36.67948214 -38.32020276
OS 36.76916446 -38.32020276
OS 36.76916446 -38.42745172
OE
OB 38.2382903 -38.39601668 I
OS 37.86014526 -38.39601668
OS 37.86014526 -38.59109884
OS 38.21425174 -38.59109884
OS 38.21425174 -38.66691276
OS 37.86014526 -38.66691276
OS 37.86014526 -38.88418436
OS 38.25308326 -38.88418436
OS 38.25308326 -38.95999828
OS 37.77508574 -38.95999828
OS 37.77508574 -38.32020276
OS 38.2382903 -38.32020276
OS 38.2382903 -38.39601668
OE
OB 37.4339231 -38.32112732 I
OS 37.44224414 -38.32112732
OS 37.4616599 -38.32205188
OS 37.48200022 -38.32482556
OS 37.50418966 -38.32759924
OS 37.52452998 -38.33222204
OS 37.53470014 -38.33499572
OS 37.54302118 -38.3377694
OS 37.54394574 -38.3377694
OS 37.5448703 -38.33869396
OS 37.55041766 -38.34146764
OS 37.5587387 -38.34516588
OS 37.56890886 -38.3516378
OS 37.58000358 -38.35995884
OS 37.59202286 -38.37105356
OS 37.60311758 -38.3839974
OS 37.6142123 -38.39879036
OS 37.6142123 -38.39971492
OS 37.61513686 -38.40063948
OS 37.6188351 -38.40618684
OS 37.62253334 -38.41543244
OS 37.6280807 -38.42745172
OS 37.6327035 -38.44132012
OS 37.6373263 -38.4579622
OS 37.64009998 -38.47552884
OS 37.64102454 -38.4949446
OS 37.64102454 -38.49586916
OS 37.64102454 -38.49771828
OS 37.64102454 -38.50141652
OS 37.64009998 -38.50603932
OS 37.64009998 -38.51251124
OS 37.63917542 -38.51898316
OS 37.63547718 -38.53470068
OS 37.62992982 -38.55319188
OS 37.62253334 -38.57260764
OS 37.61143862 -38.5920234
OS 37.60404214 -38.601269
OS 37.59664566 -38.6105146
OS 37.5957211 -38.61143916
OS 37.59479654 -38.61236372
OS 37.59202286 -38.6151374
OS 37.58832462 -38.61791108
OS 37.58370182 -38.62160932
OS 37.57815446 -38.62530756
OS 37.57075798 -38.62993036
OS 37.5633615 -38.63547772
OS 37.5541159 -38.64010052
OS 37.54394574 -38.64472332
OS 37.53285102 -38.65027068
OS 37.52083174 -38.65489348
OS 37.50696334 -38.65859172
OS 37.49309494 -38.66321452
OS 37.47737742 -38.6659882
OS 37.46073534 -38.66876188
OS 37.46258446 -38.66968644
OS 37.4662827 -38.67153556
OS 37.47183006 -38.6752338
OS 37.47922654 -38.67893204
OS 37.49586862 -38.6891022
OS 37.50418966 -38.69557412
OS 37.51158614 -38.70112148
OS 37.51343526 -38.7029706
OS 37.51805806 -38.7075934
OS 37.52545454 -38.71498988
OS 37.53470014 -38.72423548
OS 37.5448703 -38.73717932
OS 37.55688958 -38.75104772
OS 37.56890886 -38.7676898
OS 37.5818527 -38.786181
OS 37.69187534 -38.95999828
OS 37.5864755 -38.95999828
OS 37.50234054 -38.82686164
OS 37.50234054 -38.82593708
OS 37.50049142 -38.82408796
OS 37.4986423 -38.82131428
OS 37.49586862 -38.81761604
OS 37.4893967 -38.80744588
OS 37.48107566 -38.79450204
OS 37.4709055 -38.78063364
OS 37.46073534 -38.76584068
OS 37.45056518 -38.75197228
OS 37.44131958 -38.73902844
OS 37.44039502 -38.73810388
OS 37.43762134 -38.73440564
OS 37.43299854 -38.72885828
OS 37.42652662 -38.72238636
OS 37.41265822 -38.70851796
OS 37.40526174 -38.70204604
OS 37.39786526 -38.69649868
OS 37.3969407 -38.69557412
OS 37.39509158 -38.69464956
OS 37.39139334 -38.69280044
OS 37.38584598 -38.69002676
OS 37.38029862 -38.68725308
OS 37.3738267 -38.6844794
OS 37.35903374 -38.6798566
OS 37.35810918 -38.6798566
OS 37.35626006 -38.67893204
OS 37.35256182 -38.67893204
OS 37.34793902 -38.67800748
OS 37.3414671 -38.67708292
OS 37.33407062 -38.67708292
OS 37.32390046 -38.67615836
OS 37.21480238 -38.67615836
OS 37.21480238 -38.95999828
OS 37.12974286 -38.95999828
OS 37.12974286 -38.32020276
OS 37.42652662 -38.32020276
OS 37.4339231 -38.32112732
OE
OB 35.31760526 -38.95999828 I
OS 35.23254574 -38.95999828
OS 35.23254574 -38.32020276
OS 35.31760526 -38.32020276
OS 35.31760526 -38.95999828
OE
OB 42.12051774 -38.66413908 H
OS 41.95224782 -38.66413908
OS 41.95224782 -38.88418436
OS 42.13438614 -38.88418436
OS 42.1538019 -38.8832598
OS 42.16212294 -38.88233524
OS 42.16951942 -38.88141068
OS 42.17044398 -38.88141068
OS 42.17414222 -38.88048612
OS 42.17968958 -38.87956156
OS 42.1861615 -38.87771244
OS 42.20187902 -38.87216508
OS 42.21759654 -38.8647686
OS 42.2185211 -38.86384404
OS 42.22129478 -38.86199492
OS 42.22499302 -38.85922124
OS 42.22961582 -38.855523
OS 42.23423862 -38.84997564
OS 42.24071054 -38.84442828
OS 42.24533334 -38.8370318
OS 42.2508807 -38.82871076
OS 42.25180526 -38.8277862
OS 42.25272982 -38.82501252
OS 42.25457894 -38.81946516
OS 42.25735262 -38.81299324
OS 42.2601263 -38.80559676
OS 42.26197542 -38.79635116
OS 42.26289998 -38.78525644
OS 42.26382454 -38.77416172
OS 42.26382454 -38.7723126
OS 42.26382454 -38.76861436
OS 42.26289998 -38.76121788
OS 42.26105086 -38.75289684
OS 42.25920174 -38.74365124
OS 42.2555035 -38.73348108
OS 42.2508807 -38.72331092
OS 42.24440878 -38.71314076
OS 42.24348422 -38.7122162
OS 42.24071054 -38.70851796
OS 42.2370123 -38.70389516
OS 42.23146494 -38.6983478
OS 42.22406846 -38.69187588
OS 42.21482286 -38.68540396
OS 42.2046527 -38.6798566
OS 42.19263342 -38.6752338
OS 42.1907843 -38.67430924
OS 42.18708606 -38.67338468
OS 42.17876502 -38.67153556
OS 42.16859486 -38.66968644
OS 42.15565102 -38.66783732
OS 42.1399335 -38.6659882
OS 42.12051774 -38.66413908
OE
OB 45.22981302 -38.5504182 H
OS 45.22426566 -38.5504182
OS 45.21964286 -38.55134276
OS 45.2094727 -38.55226732
OS 45.1956043 -38.55596556
OS 45.17988678 -38.56151292
OS 45.1632447 -38.5689094
OS 45.14752718 -38.58000412
OS 45.13920614 -38.5874006
OS 45.13180966 -38.59479708
OS 45.13180966 -38.59572164
OS 45.12996054 -38.5966462
OS 45.12811142 -38.59941988
OS 45.12533774 -38.60311812
OS 45.12256406 -38.60774092
OS 45.11979038 -38.61328828
OS 45.11609214 -38.62068476
OS 45.1123939 -38.62808124
OS 45.10869566 -38.63732684
OS 45.10499742 -38.64657244
OS 45.10222374 -38.65766716
OS 45.09945006 -38.66968644
OS 45.09667638 -38.68263028
OS 45.09482726 -38.69649868
OS 45.0939027 -38.7122162
OS 45.09297814 -38.72793372
OS 45.09297814 -38.72885828
OS 45.09297814 -38.73163196
OS 45.09297814 -38.73625476
OS 45.0939027 -38.74272668
OS 45.0939027 -38.75012316
OS 45.09482726 -38.7584442
OS 45.09760094 -38.77785996
OS 45.10222374 -38.8000494
OS 45.10962022 -38.82223884
OS 45.11886582 -38.84350372
OS 45.12533774 -38.85274932
OS 45.13180966 -38.86199492
OS 45.13273422 -38.86199492
OS 45.13365878 -38.86384404
OS 45.13920614 -38.86846684
OS 45.14752718 -38.87586332
OS 45.1586219 -38.8832598
OS 45.1724903 -38.89158084
OS 45.18913238 -38.89897732
OS 45.20854814 -38.90360012
OS 45.2187183 -38.90452468
OS 45.22981302 -38.90544924
OS 45.23536038 -38.90544924
OS 45.23998318 -38.90452468
OS 45.25015334 -38.90267556
OS 45.26402174 -38.89990188
OS 45.2788147 -38.89435452
OS 45.29545678 -38.88695804
OS 45.3111743 -38.87586332
OS 45.31949534 -38.86846684
OS 45.32689182 -38.86107036
OS 45.32781638 -38.8601458
OS 45.32874094 -38.85922124
OS 45.33059006 -38.85644756
OS 45.33336374 -38.85274932
OS 45.33613742 -38.84812652
OS 45.33983566 -38.84257916
OS 45.3435339 -38.83518268
OS 45.34723214 -38.8277862
OS 45.35093038 -38.8185406
OS 45.35370406 -38.80837044
OS 45.3574023 -38.79727572
OS 45.36017598 -38.78525644
OS 45.36294966 -38.77138804
OS 45.36479878 -38.75751964
OS 45.3666479 -38.74180212
OS 45.3666479 -38.72516004
OS 45.3666479 -38.72423548
OS 45.3666479 -38.7214618
OS 45.3666479 -38.716839
OS 45.36572334 -38.71129164
OS 45.36572334 -38.70389516
OS 45.36479878 -38.69557412
OS 45.3620251 -38.67615836
OS 45.3574023 -38.65581804
OS 45.35000582 -38.6336286
OS 45.33983566 -38.61328828
OS 45.3342883 -38.60311812
OS 45.32689182 -38.59479708
OS 45.32689182 -38.59387252
OS 45.3250427 -38.59294796
OS 45.31949534 -38.5874006
OS 45.3111743 -38.58092868
OS 45.30007958 -38.57260764
OS 45.28621118 -38.5642866
OS 45.2695691 -38.55689012
OS 45.2510779 -38.55226732
OS 45.24090774 -38.55134276
OS 45.22981302 -38.5504182
OE
OB 32.07702246 -38.54764452 H
OS 32.07239966 -38.54764452
OS 32.06870142 -38.54856908
OS 32.05945582 -38.5504182
OS 32.04743654 -38.55319188
OS 32.03356814 -38.55873924
OS 32.01877518 -38.56706028
OS 32.01045414 -38.57260764
OS 32.00305766 -38.57907956
OS 31.99566118 -38.58647604
OS 31.9882647 -38.59479708
OS 31.9882647 -38.59572164
OS 31.98641558 -38.5966462
OS 31.98456646 -38.59941988
OS 31.98271734 -38.60311812
OS 31.97994366 -38.60866548
OS 31.97624542 -38.61421284
OS 31.97254718 -38.62160932
OS 31.9697735 -38.6290058
OS 31.96607526 -38.6382514
OS 31.96237702 -38.64842156
OS 31.95960334 -38.65951628
OS 31.9559051 -38.67153556
OS 31.95405598 -38.68540396
OS 31.95220686 -38.69927236
OS 31.95035774 -38.71406532
OS 31.95035774 -38.7307074
OS 31.95035774 -38.73163196
OS 31.95035774 -38.73440564
OS 31.95035774 -38.73902844
OS 31.9512823 -38.74550036
OS 31.9512823 -38.75289684
OS 31.95220686 -38.76121788
OS 31.95498054 -38.78063364
OS 31.95960334 -38.80282308
OS 31.9651507 -38.82408796
OS 31.9743963 -38.84535284
OS 31.97994366 -38.85459844
OS 31.98641558 -38.86291948
OS 31.9882647 -38.8647686
OS 31.9928875 -38.8693914
OS 32.00028398 -38.87678788
OS 32.01045414 -38.88418436
OS 32.02339798 -38.89158084
OS 32.03819094 -38.89897732
OS 32.05483302 -38.90360012
OS 32.06407862 -38.90452468
OS 32.07332422 -38.90544924
OS 32.07887158 -38.90544924
OS 32.08256982 -38.90452468
OS 32.09181542 -38.90267556
OS 32.10475926 -38.89990188
OS 32.11862766 -38.89435452
OS 32.13342062 -38.88695804
OS 32.14821358 -38.87586332
OS 32.15561006 -38.8693914
OS 32.16300654 -38.86199492
OS 32.16300654 -38.86107036
OS 32.16485566 -38.8601458
OS 32.16670478 -38.85737212
OS 32.1685539 -38.85367388
OS 32.17225214 -38.84905108
OS 32.17502582 -38.84257916
OS 32.17872406 -38.83610724
OS 32.1824223 -38.8277862
OS 32.18519598 -38.81946516
OS 32.18889422 -38.80837044
OS 32.19259246 -38.79727572
OS 32.19536614 -38.78525644
OS 32.19721526 -38.77138804
OS 32.19906438 -38.75659508
OS 32.2009135 -38.74087756
OS 32.2009135 -38.72423548
OS 32.2009135 -38.72331092
OS 32.2009135 -38.72053724
OS 32.2009135 -38.71591444
OS 32.19998894 -38.70944252
OS 32.19998894 -38.70204604
OS 32.19906438 -38.693725
OS 32.1962907 -38.67430924
OS 32.1916679 -38.65304436
OS 32.18519598 -38.63177948
OS 32.17595038 -38.6105146
OS 32.17040302 -38.60034444
OS 32.1639311 -38.5920234
OS 32.1639311 -38.59109884
OS 32.16208198 -38.59017428
OS 32.15745918 -38.58462692
OS 32.1500627 -38.578155
OS 32.13989254 -38.56983396
OS 32.1269487 -38.56151292
OS 32.11215574 -38.55411644
OS 32.09551366 -38.54949364
OS 32.08626806 -38.54856908
OS 32.07702246 -38.54764452
OE
OB 42.10387566 -38.39601668 H
OS 41.95224782 -38.39601668
OS 41.95224782 -38.58832516
OS 42.10942302 -38.58832516
OS 42.1214423 -38.5874006
OS 42.13438614 -38.58647604
OS 42.14732998 -38.58555148
OS 42.16027382 -38.58370236
OS 42.17044398 -38.58185324
OS 42.1722931 -38.58092868
OS 42.17599134 -38.58000412
OS 42.1815387 -38.57723044
OS 42.18893518 -38.5735322
OS 42.19633166 -38.56983396
OS 42.2046527 -38.5642866
OS 42.21297374 -38.55689012
OS 42.21944566 -38.54949364
OS 42.22037022 -38.54856908
OS 42.22221934 -38.5457954
OS 42.22499302 -38.54024804
OS 42.2277667 -38.53377612
OS 42.23054038 -38.52637964
OS 42.23331406 -38.51713404
OS 42.23516318 -38.50603932
OS 42.23608774 -38.49402004
OS 42.23608774 -38.49217092
OS 42.23608774 -38.48847268
OS 42.23516318 -38.48292532
OS 42.23423862 -38.47552884
OS 42.2323895 -38.46628324
OS 42.22961582 -38.45703764
OS 42.22591758 -38.44779204
OS 42.22037022 -38.43854644
OS 42.21944566 -38.43762188
OS 42.21759654 -38.4348482
OS 42.2138983 -38.4302254
OS 42.2092755 -38.4256026
OS 42.20280358 -38.42005524
OS 42.1954071 -38.41450788
OS 42.1861615 -38.40896052
OS 42.17599134 -38.40526228
OS 42.17506678 -38.40526228
OS 42.17044398 -38.40341316
OS 42.16397206 -38.4024886
OS 42.1538019 -38.40063948
OS 42.1399335 -38.39879036
OS 42.12421598 -38.3978658
OS 42.10387566 -38.39601668
OE
OB 37.41635646 -38.39139388 H
OS 37.21480238 -38.39139388
OS 37.21480238 -38.60311812
OS 37.40526174 -38.60311812
OS 37.41635646 -38.60219356
OS 37.4293003 -38.601269
OS 37.44409326 -38.60034444
OS 37.45888622 -38.59849532
OS 37.47367918 -38.59572164
OS 37.48662302 -38.5920234
OS 37.48847214 -38.59109884
OS 37.49217038 -38.58924972
OS 37.49771774 -38.58647604
OS 37.50511422 -38.5827778
OS 37.51343526 -38.57723044
OS 37.5217563 -38.57075852
OS 37.53007734 -38.56243748
OS 37.53654926 -38.55319188
OS 37.53747382 -38.55226732
OS 37.53932294 -38.54856908
OS 37.54209662 -38.54302172
OS 37.54579486 -38.53562524
OS 37.54856854 -38.5273042
OS 37.55134222 -38.5180586
OS 37.55319134 -38.50696388
OS 37.5541159 -38.49586916
OS 37.5541159 -38.4949446
OS 37.5541159 -38.49402004
OS 37.55319134 -38.48847268
OS 37.55226678 -38.48015164
OS 37.55041766 -38.46905692
OS 37.54579486 -38.4579622
OS 37.5402475 -38.44501836
OS 37.53192646 -38.43299908
OS 37.52083174 -38.4209798
OS 37.51898262 -38.42005524
OS 37.51435982 -38.416357
OS 37.50696334 -38.4117342
OS 37.49494406 -38.40618684
OS 37.48107566 -38.40063948
OS 37.46258446 -38.39601668
OS 37.44131958 -38.39231844
OS 37.41635646 -38.39139388
OE
OB 39.82298614 -38.54764452 H
OS 39.81836334 -38.54764452
OS 39.8146651 -38.54856908
OS 39.8054195 -38.5504182
OS 39.79340022 -38.55319188
OS 39.77953182 -38.55873924
OS 39.76473886 -38.56706028
OS 39.75641782 -38.57260764
OS 39.74902134 -38.57907956
OS 39.74162486 -38.58647604
OS 39.73422838 -38.59479708
OS 39.73422838 -38.59572164
OS 39.73237926 -38.5966462
OS 39.73053014 -38.59941988
OS 39.72868102 -38.60311812
OS 39.72590734 -38.60866548
OS 39.7222091 -38.61421284
OS 39.71851086 -38.62160932
OS 39.71573718 -38.6290058
OS 39.71203894 -38.6382514
OS 39.7083407 -38.64842156
OS 39.70556702 -38.65951628
OS 39.70186878 -38.67153556
OS 39.70001966 -38.68540396
OS 39.69817054 -38.69927236
OS 39.69632142 -38.71406532
OS 39.69632142 -38.7307074
OS 39.69632142 -38.73163196
OS 39.69632142 -38.73440564
OS 39.69632142 -38.73902844
OS 39.69724598 -38.74550036
OS 39.69724598 -38.75289684
OS 39.69817054 -38.76121788
OS 39.70094422 -38.78063364
OS 39.70556702 -38.80282308
OS 39.71111438 -38.82408796
OS 39.72035998 -38.84535284
OS 39.72590734 -38.85459844
OS 39.73237926 -38.86291948
OS 39.73422838 -38.8647686
OS 39.73885118 -38.8693914
OS 39.74624766 -38.87678788
OS 39.75641782 -38.88418436
OS 39.76936166 -38.89158084
OS 39.78415462 -38.89897732
OS 39.8007967 -38.90360012
OS 39.8100423 -38.90452468
OS 39.8192879 -38.90544924
OS 39.82483526 -38.90544924
OS 39.8285335 -38.90452468
OS 39.8377791 -38.90267556
OS 39.85072294 -38.89990188
OS 39.86459134 -38.89435452
OS 39.8793843 -38.88695804
OS 39.89417726 -38.87586332
OS 39.90157374 -38.8693914
OS 39.90897022 -38.86199492
OS 39.90897022 -38.86107036
OS 39.91081934 -38.8601458
OS 39.91266846 -38.85737212
OS 39.91451758 -38.85367388
OS 39.91821582 -38.84905108
OS 39.9209895 -38.84257916
OS 39.92468774 -38.83610724
OS 39.92838598 -38.8277862
OS 39.93115966 -38.81946516
OS 39.9348579 -38.80837044
OS 39.93855614 -38.79727572
OS 39.94132982 -38.78525644
OS 39.94317894 -38.77138804
OS 39.94502806 -38.75659508
OS 39.94687718 -38.74087756
OS 39.94687718 -38.72423548
OS 39.94687718 -38.72331092
OS 39.94687718 -38.72053724
OS 39.94687718 -38.71591444
OS 39.94595262 -38.70944252
OS 39.94595262 -38.70204604
OS 39.94502806 -38.693725
OS 39.94225438 -38.67430924
OS 39.93763158 -38.65304436
OS 39.93115966 -38.63177948
OS 39.92191406 -38.6105146
OS 39.9163667 -38.60034444
OS 39.90989478 -38.5920234
OS 39.90989478 -38.59109884
OS 39.90804566 -38.59017428
OS 39.90342286 -38.58462692
OS 39.89602638 -38.578155
OS 39.88585622 -38.56983396
OS 39.87291238 -38.56151292
OS 39.85811942 -38.55411644
OS 39.84147734 -38.54949364
OS 39.83223174 -38.54856908
OS 39.82298614 -38.54764452
OE
OB 35.73550638 -38.39601668 H
OS 35.5524435 -38.39601668
OS 35.5524435 -38.624383
OS 35.72441166 -38.624383
OS 35.73088358 -38.62345844
OS 35.7373555 -38.62345844
OS 35.74475198 -38.62253388
OS 35.76231862 -38.62068476
OS 35.78173438 -38.61698652
OS 35.80115014 -38.61143916
OS 35.81871678 -38.60404268
OS 35.82703782 -38.59941988
OS 35.83350974 -38.59387252
OS 35.83535886 -38.5920234
OS 35.8390571 -38.58832516
OS 35.84460446 -38.58092868
OS 35.85107638 -38.57168308
OS 35.8575483 -38.5596638
OS 35.86309566 -38.54487084
OS 35.8667939 -38.52822876
OS 35.86864302 -38.508813
OS 35.86864302 -38.50788844
OS 35.86864302 -38.50696388
OS 35.86864302 -38.50234108
OS 35.86771846 -38.49402004
OS 35.86586934 -38.48477444
OS 35.86402022 -38.47460428
OS 35.86032198 -38.462585
OS 35.85477462 -38.45149028
OS 35.8483027 -38.44039556
OS 35.84737814 -38.439471
OS 35.84460446 -38.43577276
OS 35.83998166 -38.43114996
OS 35.8344343 -38.42467804
OS 35.82611326 -38.41820612
OS 35.81686766 -38.41265876
OS 35.8066975 -38.4071114
OS 35.79467822 -38.4024886
OS 35.79375366 -38.4024886
OS 35.79005542 -38.40156404
OS 35.78450806 -38.40063948
OS 35.77711158 -38.39879036
OS 35.76601686 -38.3978658
OS 35.75214846 -38.39694124
OS 35.73550638 -38.39601668
OE
OB 43.44263854 -38.5504182 H
OS 43.43709118 -38.5504182
OS 43.43339294 -38.55134276
OS 43.42322278 -38.55226732
OS 43.4112035 -38.555041
OS 43.39641054 -38.5596638
OS 43.38069302 -38.56613572
OS 43.36590006 -38.57538132
OS 43.3511071 -38.5874006
OS 43.34925798 -38.58924972
OS 43.34555974 -38.59387252
OS 43.33908782 -38.60219356
OS 43.3326159 -38.61328828
OS 43.32521942 -38.62623212
OS 43.3187475 -38.6428742
OS 43.31320014 -38.66228996
OS 43.31042646 -38.68355484
OS 43.57022782 -38.68355484
OS 43.57022782 -38.68263028
OS 43.57022782 -38.68078116
OS 43.56930326 -38.67800748
OS 43.56930326 -38.67430924
OS 43.56745414 -38.66321452
OS 43.56468046 -38.65119524
OS 43.56005766 -38.63640228
OS 43.55543486 -38.62253388
OS 43.54803838 -38.60866548
OS 43.53971734 -38.5966462
OS 43.53971734 -38.59572164
OS 43.53786822 -38.59479708
OS 43.53324542 -38.58924972
OS 43.52492438 -38.58185324
OS 43.51382966 -38.5735322
OS 43.49996126 -38.56521116
OS 43.48331918 -38.55781468
OS 43.46390342 -38.55226732
OS 43.45373326 -38.55134276
OS 43.44263854 -38.5504182
OE
OB 34.35791198 -38.39601668 H
OS 34.20628414 -38.39601668
OS 34.20628414 -38.58832516
OS 34.36345934 -38.58832516
OS 34.37547862 -38.5874006
OS 34.38842246 -38.58647604
OS 34.4013663 -38.58555148
OS 34.41431014 -38.58370236
OS 34.4244803 -38.58185324
OS 34.42632942 -38.58092868
OS 34.43002766 -38.58000412
OS 34.43557502 -38.57723044
OS 34.4429715 -38.5735322
OS 34.45036798 -38.56983396
OS 34.45868902 -38.5642866
OS 34.46701006 -38.55689012
OS 34.47348198 -38.54949364
OS 34.47440654 -38.54856908
OS 34.47625566 -38.5457954
OS 34.47902934 -38.54024804
OS 34.48180302 -38.53377612
OS 34.4845767 -38.52637964
OS 34.48735038 -38.51713404
OS 34.4891995 -38.50603932
OS 34.49012406 -38.49402004
OS 34.49012406 -38.49217092
OS 34.49012406 -38.48847268
OS 34.4891995 -38.48292532
OS 34.48827494 -38.47552884
OS 34.48642582 -38.46628324
OS 34.48365214 -38.45703764
OS 34.4799539 -38.44779204
OS 34.47440654 -38.43854644
OS 34.47348198 -38.43762188
OS 34.47163286 -38.4348482
OS 34.46793462 -38.4302254
OS 34.46331182 -38.4256026
OS 34.4568399 -38.42005524
OS 34.44944342 -38.41450788
OS 34.44019782 -38.40896052
OS 34.43002766 -38.40526228
OS 34.4291031 -38.40526228
OS 34.4244803 -38.40341316
OS 34.41800838 -38.4024886
OS 34.40783822 -38.40063948
OS 34.39396982 -38.39879036
OS 34.3782523 -38.3978658
OS 34.35791198 -38.39601668
OE
OB 40.89732486 -38.39601668 H
OS 40.71426198 -38.39601668
OS 40.71426198 -38.624383
OS 40.88623014 -38.624383
OS 40.89270206 -38.62345844
OS 40.89917398 -38.62345844
OS 40.90657046 -38.62253388
OS 40.9241371 -38.62068476
OS 40.94355286 -38.61698652
OS 40.96296862 -38.61143916
OS 40.98053526 -38.60404268
OS 40.9888563 -38.59941988
OS 40.99532822 -38.59387252
OS 40.99717734 -38.5920234
OS 41.00087558 -38.58832516
OS 41.00642294 -38.58092868
OS 41.01289486 -38.57168308
OS 41.01936678 -38.5596638
OS 41.02491414 -38.54487084
OS 41.02861238 -38.52822876
OS 41.0304615 -38.508813
OS 41.0304615 -38.50788844
OS 41.0304615 -38.50696388
OS 41.0304615 -38.50234108
OS 41.02953694 -38.49402004
OS 41.02768782 -38.48477444
OS 41.0258387 -38.47460428
OS 41.02214046 -38.462585
OS 41.0165931 -38.45149028
OS 41.01012118 -38.44039556
OS 41.00919662 -38.439471
OS 41.00642294 -38.43577276
OS 41.00180014 -38.43114996
OS 40.99625278 -38.42467804
OS 40.98793174 -38.41820612
OS 40.97868614 -38.41265876
OS 40.96851598 -38.4071114
OS 40.9564967 -38.4024886
OS 40.95557214 -38.4024886
OS 40.9518739 -38.40156404
OS 40.94632654 -38.40063948
OS 40.93893006 -38.39879036
OS 40.92783534 -38.3978658
OS 40.91396694 -38.39694124
OS 40.89732486 -38.39601668
OE
OB 33.15136118 -38.39601668 H
OS 32.9682983 -38.39601668
OS 32.9682983 -38.624383
OS 33.14026646 -38.624383
OS 33.14673838 -38.62345844
OS 33.1532103 -38.62345844
OS 33.16060678 -38.62253388
OS 33.17817342 -38.62068476
OS 33.19758918 -38.61698652
OS 33.21700494 -38.61143916
OS 33.23457158 -38.60404268
OS 33.24289262 -38.59941988
OS 33.24936454 -38.59387252
OS 33.25121366 -38.5920234
OS 33.2549119 -38.58832516
OS 33.26045926 -38.58092868
OS 33.26693118 -38.57168308
OS 33.2734031 -38.5596638
OS 33.27895046 -38.54487084
OS 33.2826487 -38.52822876
OS 33.28449782 -38.508813
OS 33.28449782 -38.50788844
OS 33.28449782 -38.50696388
OS 33.28449782 -38.50234108
OS 33.28357326 -38.49402004
OS 33.28172414 -38.48477444
OS 33.27987502 -38.47460428
OS 33.27617678 -38.462585
OS 33.27062942 -38.45149028
OS 33.2641575 -38.44039556
OS 33.26323294 -38.439471
OS 33.26045926 -38.43577276
OS 33.25583646 -38.43114996
OS 33.2502891 -38.42467804
OS 33.24196806 -38.41820612
OS 33.23272246 -38.41265876
OS 33.2225523 -38.4071114
OS 33.21053302 -38.4024886
OS 33.20960846 -38.4024886
OS 33.20591022 -38.40156404
OS 33.20036286 -38.40063948
OS 33.19296638 -38.39879036
OS 33.18187166 -38.3978658
OS 33.16800326 -38.39694124
OS 33.15136118 -38.39601668
OE
OB 34.37455406 -38.66413908 H
OS 34.20628414 -38.66413908
OS 34.20628414 -38.88418436
OS 34.38842246 -38.88418436
OS 34.40783822 -38.8832598
OS 34.41615926 -38.88233524
OS 34.42355574 -38.88141068
OS 34.4244803 -38.88141068
OS 34.42817854 -38.88048612
OS 34.4337259 -38.87956156
OS 34.44019782 -38.87771244
OS 34.45591534 -38.87216508
OS 34.47163286 -38.8647686
OS 34.47255742 -38.86384404
OS 34.4753311 -38.86199492
OS 34.47902934 -38.85922124
OS 34.48365214 -38.855523
OS 34.48827494 -38.84997564
OS 34.49474686 -38.84442828
OS 34.49936966 -38.8370318
OS 34.50491702 -38.82871076
OS 34.50584158 -38.8277862
OS 34.50676614 -38.82501252
OS 34.50861526 -38.81946516
OS 34.51138894 -38.81299324
OS 34.51416262 -38.80559676
OS 34.51601174 -38.79635116
OS 34.5169363 -38.78525644
OS 34.51786086 -38.77416172
OS 34.51786086 -38.7723126
OS 34.51786086 -38.76861436
OS 34.5169363 -38.76121788
OS 34.51508718 -38.75289684
OS 34.51323806 -38.74365124
OS 34.50953982 -38.73348108
OS 34.50491702 -38.72331092
OS 34.4984451 -38.71314076
OS 34.49752054 -38.7122162
OS 34.49474686 -38.70851796
OS 34.49104862 -38.70389516
OS 34.48550126 -38.6983478
OS 34.47810478 -38.69187588
OS 34.46885918 -38.68540396
OS 34.45868902 -38.6798566
OS 34.44666974 -38.6752338
OS 34.44482062 -38.67430924
OS 34.44112238 -38.67338468
OS 34.43280134 -38.67153556
OS 34.42263118 -38.66968644
OS 34.40968734 -38.66783732
OS 34.39396982 -38.6659882
OS 34.37455406 -38.66413908
OE
SE
S P 0
OB 48.49040086 -36.61402634 I
OS 48.17420134 -36.61402634
OS 48.17420134 -37.45999874
OS 48.04661206 -37.45999874
OS 48.04661206 -36.61402634
OS 47.73041254 -36.61402634
OS 47.73041254 -36.50030546
OS 48.49040086 -36.50030546
OS 48.49040086 -36.61402634
OE
OB 47.69990206 -37.45999874 I
OS 47.5556707 -37.45999874
OS 47.44333666 -37.16876234
OS 47.04115306 -37.16876234
OS 46.93714006 -37.45999874
OS 46.80261658 -37.45999874
OS 47.16874234 -36.50030546
OS 47.30742634 -36.50030546
OS 47.69990206 -37.45999874
OE
OB 49.31834434 -36.61402634 I
OS 48.75112678 -36.61402634
OS 48.75112678 -36.90664958
OS 49.2822865 -36.90664958
OS 49.2822865 -37.02037046
OS 48.75112678 -37.02037046
OS 48.75112678 -37.34627786
OS 49.34053378 -37.34627786
OS 49.34053378 -37.45999874
OS 48.6235375 -37.45999874
OS 48.6235375 -36.50030546
OS 49.31834434 -36.50030546
OS 49.31834434 -36.61402634
OE
OB 46.33386466 -36.5016923 I
OS 46.36160146 -36.50307914
OS 46.38933826 -36.50585282
OS 46.41707506 -36.51001334
OS 46.44065134 -36.51417386
OS 46.44203818 -36.51417386
OS 46.44481186 -36.5155607
OS 46.44897238 -36.5155607
OS 46.45451974 -36.51833438
OS 46.46977498 -36.5224949
OS 46.48919074 -36.5294291
OS 46.51138018 -36.53913698
OS 46.53495646 -36.55161854
OS 46.55853274 -36.56548694
OS 46.58072218 -36.58351586
OS 46.58210902 -36.5849027
OS 46.58349586 -36.58628954
OS 46.58765638 -36.59045006
OS 46.59320374 -36.59461058
OS 46.60707214 -36.60847898
OS 46.62371422 -36.62789474
OS 46.64174314 -36.65147102
OS 46.6611589 -36.67920782
OS 46.67918782 -36.71110514
OS 46.69444306 -36.74716298
OS 46.69444306 -36.74854982
OS 46.6958299 -36.7513235
OS 46.69860358 -36.75687086
OS 46.69999042 -36.7651919
OS 46.70415094 -36.77489978
OS 46.70692462 -36.7859945
OS 46.7096983 -36.79847606
OS 46.71385882 -36.8137313
OS 46.71801934 -36.82898654
OS 46.72079302 -36.84701546
OS 46.72772722 -36.88584698
OS 46.73188774 -36.92883902
OS 46.73327458 -36.97599158
OS 46.73327458 -36.97737842
OS 46.73327458 -36.9801521
OS 46.73327458 -36.9870863
OS 46.73327458 -36.9940205
OS 46.73188774 -37.00372838
OS 46.73188774 -37.0148231
OS 46.7305009 -37.04117306
OS 46.72634038 -37.07168354
OS 46.72217986 -37.10358086
OS 46.71524566 -37.13686502
OS 46.70692462 -37.17014918
OS 46.70692462 -37.17153602
OS 46.70553778 -37.1743097
OS 46.70415094 -37.17847022
OS 46.7027641 -37.18401758
OS 46.69721674 -37.19927282
OS 46.6888957 -37.21868858
OS 46.68057466 -37.24087802
OS 46.66947994 -37.26306746
OS 46.65561154 -37.28664374
OS 46.64174314 -37.30883318
OS 46.6403563 -37.31160686
OS 46.63480894 -37.31854106
OS 46.6264879 -37.32824894
OS 46.61539318 -37.3407305
OS 46.60291162 -37.3545989
OS 46.58765638 -37.3684673
OS 46.57240114 -37.38372254
OS 46.55437222 -37.3962041
OS 46.55159854 -37.39759094
OS 46.54605118 -37.40175146
OS 46.5363433 -37.40729882
OS 46.5224749 -37.41423302
OS 46.50583282 -37.42255406
OS 46.48641706 -37.42948826
OS 46.46422762 -37.4378093
OS 46.4392645 -37.4447435
OS 46.43649082 -37.4447435
OS 46.4323303 -37.44613034
OS 46.42816978 -37.44751718
OS 46.41430138 -37.44890402
OS 46.39488562 -37.4516777
OS 46.37269618 -37.45445138
OS 46.34634622 -37.45722506
OS 46.31722258 -37.4586119
OS 46.28532526 -37.45999874
OS 45.9400021 -37.45999874
OS 45.9400021 -36.50030546
OS 46.30890154 -36.50030546
OS 46.33386466 -36.5016923
OE
OB 46.28948578 -36.61402634 H
OS 46.06759138 -36.61402634
OS 46.06759138 -37.34627786
OS 46.29503314 -37.34627786
OS 46.30474102 -37.34489102
OS 46.32554362 -37.34350418
OS 46.3491199 -37.34211734
OS 46.37408302 -37.33934366
OS 46.39904614 -37.33518314
OS 46.41984874 -37.32963578
OS 46.42262242 -37.32824894
OS 46.42955662 -37.3268621
OS 46.4392645 -37.32270158
OS 46.45174606 -37.31715422
OS 46.46561446 -37.30883318
OS 46.47948286 -37.30051214
OS 46.49335126 -37.29080426
OS 46.50721966 -37.27970954
OS 46.5086065 -37.27693586
OS 46.51415386 -37.2713885
OS 46.5224749 -37.26168062
OS 46.53218278 -37.24781222
OS 46.5432775 -37.2297833
OS 46.55575906 -37.2089807
OS 46.56685378 -37.18540442
OS 46.57656166 -37.15905446
OS 46.57656166 -37.15766762
OS 46.5779485 -37.15489394
OS 46.57933534 -37.15073342
OS 46.58072218 -37.14518606
OS 46.58210902 -37.13825186
OS 46.5848827 -37.12854398
OS 46.58765638 -37.1188361
OS 46.59043006 -37.10774138
OS 46.59459058 -37.08000458
OS 46.5987511 -37.04810726
OS 46.60152478 -37.01204942
OS 46.60291162 -36.9732179
OS 46.60291162 -36.97183106
OS 46.60291162 -36.9662837
OS 46.60291162 -36.9593495
OS 46.60152478 -36.94825478
OS 46.60152478 -36.93577322
OS 46.60013794 -36.92190482
OS 46.5987511 -36.90526274
OS 46.59736426 -36.88862066
OS 46.59043006 -36.85117598
OS 46.58210902 -36.81234446
OS 46.56962746 -36.77628662
OS 46.56130642 -36.7582577
OS 46.55298538 -36.74300246
OS 46.55298538 -36.74161562
OS 46.5502117 -36.73884194
OS 46.54743802 -36.73468142
OS 46.54466434 -36.72913406
OS 46.53356962 -36.71526566
OS 46.51970122 -36.69862358
OS 46.5016723 -36.68059466
OS 46.4808697 -36.66256574
OS 46.45729342 -36.6473105
OS 46.4323303 -36.63482894
OS 46.42955662 -36.6334421
OS 46.42262242 -36.63205526
OS 46.41014086 -36.62789474
OS 46.39211194 -36.62373422
OS 46.3699225 -36.62096054
OS 46.3421857 -36.61680002
OS 46.32554362 -36.61541318
OS 46.3075147 -36.61541318
OS 46.28948578 -36.61402634
OE
OB 47.23531066 -36.60015794 H
OS 47.23531066 -36.60154478
OS 47.23392382 -36.60431846
OS 47.23392382 -36.60986582
OS 47.23115014 -36.61541318
OS 47.2297633 -36.62512106
OS 47.22698962 -36.63482894
OS 47.22144226 -36.65840522
OS 47.21450806 -36.68614202
OS 47.20480018 -36.7166525
OS 47.1950923 -36.74993666
OS 47.18261074 -36.78460766
OS 47.07859774 -37.06474934
OS 47.4031183 -37.06474934
OS 47.30326582 -36.80124974
OS 47.30326582 -36.7998629
OS 47.30187898 -36.79570238
OS 47.2991053 -36.78876818
OS 47.29633162 -36.78044714
OS 47.2921711 -36.77073926
OS 47.28801058 -36.7582577
OS 47.28385006 -36.7443893
OS 47.2783027 -36.7305209
OS 47.26720798 -36.69862358
OS 47.25611326 -36.66533942
OS 47.24501854 -36.63205526
OS 47.23531066 -36.60015794
OE
SE
S P 0
OB 53.57408132 -38.30725892 I
OS 53.5861006 -38.30910804
OS 53.60089356 -38.31188172
OS 53.61753564 -38.31650452
OS 53.63417772 -38.32205188
OS 53.6508198 -38.32944836
OS 53.65174436 -38.32944836
OS 53.65266892 -38.33037292
OS 53.65821628 -38.3331466
OS 53.66653732 -38.33869396
OS 53.67578292 -38.34516588
OS 53.68687764 -38.35441148
OS 53.69797236 -38.36458164
OS 53.70906708 -38.37660092
OS 53.71831268 -38.39046932
OS 53.71923724 -38.39231844
OS 53.72201092 -38.39694124
OS 53.72570916 -38.40526228
OS 53.73033196 -38.41543244
OS 53.73495476 -38.42745172
OS 53.738653 -38.44132012
OS 53.74142668 -38.45703764
OS 53.74235124 -38.47275516
OS 53.74235124 -38.47460428
OS 53.74235124 -38.48015164
OS 53.74142668 -38.48754812
OS 53.73957756 -38.49771828
OS 53.73680388 -38.50973756
OS 53.73218108 -38.5226814
OS 53.72663372 -38.53562524
OS 53.71923724 -38.54856908
OS 53.71831268 -38.5504182
OS 53.715539 -38.55411644
OS 53.70999164 -38.56058836
OS 53.70259516 -38.56798484
OS 53.69334956 -38.57630588
OS 53.68225484 -38.58555148
OS 53.669311 -38.59387252
OS 53.65359348 -38.60219356
OS 53.65451804 -38.60219356
OS 53.65636716 -38.60311812
OS 53.65914084 -38.60404268
OS 53.66283908 -38.60496724
OS 53.67300924 -38.60866548
OS 53.68595308 -38.61421284
OS 53.70074604 -38.62160932
OS 53.715539 -38.63085492
OS 53.7294074 -38.6428742
OS 53.74235124 -38.6567426
OS 53.7432758 -38.65859172
OS 53.74697404 -38.66413908
OS 53.7525214 -38.67338468
OS 53.75806876 -38.68540396
OS 53.76361612 -38.70019692
OS 53.76916348 -38.71776356
OS 53.77286172 -38.73810388
OS 53.77378628 -38.76029332
OS 53.77378628 -38.76121788
OS 53.77378628 -38.76399156
OS 53.77378628 -38.76861436
OS 53.77286172 -38.77416172
OS 53.77193716 -38.7815582
OS 53.77008804 -38.78987924
OS 53.76823892 -38.79912484
OS 53.7663898 -38.809295
OS 53.75899332 -38.83148444
OS 53.75344596 -38.84350372
OS 53.7478986 -38.85459844
OS 53.74050212 -38.86661772
OS 53.73218108 -38.878637
OS 53.72293548 -38.89065628
OS 53.71184076 -38.901751
OS 53.7109162 -38.90267556
OS 53.70906708 -38.90452468
OS 53.70536884 -38.90729836
OS 53.70074604 -38.9109966
OS 53.69519868 -38.9156194
OS 53.6878022 -38.9202422
OS 53.67948116 -38.92578956
OS 53.669311 -38.93041236
OS 53.65914084 -38.93595972
OS 53.64712156 -38.94150708
OS 53.63510228 -38.94612988
OS 53.62123388 -38.95075268
OS 53.60644092 -38.95445092
OS 53.5907234 -38.9572246
OS 53.57500588 -38.95907372
OS 53.55743924 -38.95999828
OS 53.5491182 -38.95999828
OS 53.54357084 -38.95907372
OS 53.53617436 -38.95814916
OS 53.52785332 -38.9572246
OS 53.51860772 -38.95537548
OS 53.50843756 -38.95352636
OS 53.48624812 -38.947979
OS 53.46313412 -38.9387334
OS 53.45111484 -38.93318604
OS 53.44002012 -38.92671412
OS 53.4289254 -38.91839308
OS 53.41783068 -38.91007204
OS 53.41690612 -38.90914748
OS 53.415057 -38.90729836
OS 53.41228332 -38.90452468
OS 53.40950964 -38.90082644
OS 53.40488684 -38.89620364
OS 53.40026404 -38.88973172
OS 53.39471668 -38.8832598
OS 53.38916932 -38.87493876
OS 53.38362196 -38.86569316
OS 53.3780746 -38.85644756
OS 53.36790444 -38.83425812
OS 53.3595834 -38.80837044
OS 53.35680972 -38.79450204
OS 53.3549606 -38.77970908
OS 53.4335482 -38.76953892
OS 53.4335482 -38.77046348
OS 53.43447276 -38.7723126
OS 53.43539732 -38.77601084
OS 53.43632188 -38.78063364
OS 53.43724644 -38.786181
OS 53.43909556 -38.79265292
OS 53.44371836 -38.80652132
OS 53.45019028 -38.8231634
OS 53.45851132 -38.83888092
OS 53.46775692 -38.85367388
OS 53.47885164 -38.86661772
OS 53.48070076 -38.86754228
OS 53.484399 -38.87124052
OS 53.49179548 -38.87586332
OS 53.50104108 -38.88048612
OS 53.5121358 -38.88603348
OS 53.5260042 -38.89065628
OS 53.54172172 -38.89435452
OS 53.5583638 -38.89527908
OS 53.56391116 -38.89527908
OS 53.5676094 -38.89435452
OS 53.57777956 -38.89342996
OS 53.5907234 -38.89065628
OS 53.60551636 -38.88603348
OS 53.62123388 -38.87956156
OS 53.6369514 -38.87031596
OS 53.65174436 -38.85737212
OS 53.65359348 -38.855523
OS 53.65821628 -38.84997564
OS 53.66376364 -38.8416546
OS 53.67116012 -38.83055988
OS 53.6785566 -38.81669148
OS 53.68410396 -38.80097396
OS 53.68872676 -38.78248276
OS 53.69057588 -38.76214244
OS 53.69057588 -38.76121788
OS 53.69057588 -38.75936876
OS 53.69057588 -38.75659508
OS 53.68965132 -38.75289684
OS 53.68872676 -38.74272668
OS 53.68595308 -38.7307074
OS 53.68225484 -38.71591444
OS 53.67578292 -38.70112148
OS 53.66653732 -38.68632852
OS 53.65451804 -38.67246012
OS 53.65266892 -38.670611
OS 53.64804612 -38.66691276
OS 53.64064964 -38.6613654
OS 53.63047948 -38.65489348
OS 53.61753564 -38.64842156
OS 53.60181812 -38.6428742
OS 53.58425148 -38.63917596
OS 53.56483572 -38.63732684
OS 53.55651468 -38.63732684
OS 53.55004276 -38.6382514
OS 53.54172172 -38.63917596
OS 53.53247612 -38.64102508
OS 53.5213814 -38.6428742
OS 53.50936212 -38.64564788
OS 53.51860772 -38.57630588
OS 53.52323052 -38.57630588
OS 53.52692876 -38.57723044
OS 53.53894804 -38.57723044
OS 53.5491182 -38.57538132
OS 53.56113748 -38.5735322
OS 53.57500588 -38.57075852
OS 53.5907234 -38.56613572
OS 53.60551636 -38.5596638
OS 53.62123388 -38.55134276
OS 53.62215844 -38.55134276
OS 53.623083 -38.5504182
OS 53.6277058 -38.54671996
OS 53.63417772 -38.54024804
OS 53.6415742 -38.531927
OS 53.64897068 -38.51990772
OS 53.6554426 -38.50603932
OS 53.6600654 -38.4903218
OS 53.66191452 -38.4810762
OS 53.66191452 -38.47090604
OS 53.66191452 -38.46998148
OS 53.66191452 -38.46905692
OS 53.66191452 -38.46350956
OS 53.6600654 -38.45611308
OS 53.65821628 -38.44594292
OS 53.65451804 -38.4348482
OS 53.64989524 -38.42282892
OS 53.64249876 -38.41080964
OS 53.6323286 -38.39971492
OS 53.63140404 -38.39879036
OS 53.62678124 -38.39509212
OS 53.62030932 -38.39046932
OS 53.61198828 -38.38492196
OS 53.60089356 -38.38029916
OS 53.58794972 -38.37567636
OS 53.57315676 -38.37197812
OS 53.55651468 -38.37105356
OS 53.5491182 -38.37105356
OS 53.54079716 -38.37290268
OS 53.52970244 -38.3747518
OS 53.51768316 -38.37845004
OS 53.50566388 -38.38307284
OS 53.49272004 -38.39046932
OS 53.48070076 -38.39971492
OS 53.4797762 -38.40063948
OS 53.47607796 -38.40526228
OS 53.4705306 -38.4117342
OS 53.46405868 -38.4209798
OS 53.45758676 -38.43299908
OS 53.45111484 -38.44779204
OS 53.44556748 -38.46535868
OS 53.44186924 -38.485699
OS 53.36328164 -38.4718306
OS 53.36328164 -38.47090604
OS 53.3642062 -38.46813236
OS 53.36513076 -38.46443412
OS 53.36605532 -38.45888676
OS 53.36790444 -38.45241484
OS 53.37067812 -38.44501836
OS 53.37622548 -38.42745172
OS 53.38547108 -38.4071114
OS 53.3965658 -38.38677108
OS 53.4104342 -38.36735532
OS 53.42800084 -38.34978868
OS 53.4289254 -38.34886412
OS 53.43077452 -38.34793956
OS 53.4335482 -38.34609044
OS 53.43724644 -38.34331676
OS 53.44186924 -38.33961852
OS 53.44834116 -38.33592028
OS 53.45481308 -38.33222204
OS 53.46313412 -38.32759924
OS 53.48162532 -38.32020276
OS 53.5028902 -38.31280628
OS 53.52785332 -38.30818348
OS 53.54079716 -38.30633436
OS 53.56391116 -38.30633436
OS 53.57408132 -38.30725892
OE
OB 54.07889108 -38.30725892 I
OS 54.09091036 -38.30910804
OS 54.10477876 -38.31188172
OS 54.11957172 -38.31557996
OS 54.13528924 -38.32020276
OS 54.1500822 -38.32759924
OS 54.15100676 -38.32759924
OS 54.15193132 -38.3285238
OS 54.15655412 -38.33129748
OS 54.1639506 -38.33592028
OS 54.1731962 -38.3423922
OS 54.18336636 -38.3516378
OS 54.19446108 -38.36180796
OS 54.20463124 -38.37382724
OS 54.2148014 -38.38769564
OS 54.21572596 -38.38954476
OS 54.2194242 -38.39416756
OS 54.22312244 -38.4024886
OS 54.22959436 -38.41450788
OS 54.23514172 -38.42837628
OS 54.2425382 -38.4440938
OS 54.24901012 -38.462585
OS 54.25455748 -38.48292532
OS 54.25455748 -38.48384988
OS 54.25548204 -38.485699
OS 54.2564066 -38.48847268
OS 54.25733116 -38.49309548
OS 54.25825572 -38.49864284
OS 54.25918028 -38.50511476
OS 54.2610294 -38.5134358
OS 54.26195396 -38.5226814
OS 54.26380308 -38.53285156
OS 54.26472764 -38.54394628
OS 54.2656522 -38.55689012
OS 54.26750132 -38.56983396
OS 54.26842588 -38.58462692
OS 54.26842588 -38.59941988
OS 54.26935044 -38.61606196
OS 54.26935044 -38.6336286
OS 54.26935044 -38.63455316
OS 54.26935044 -38.6382514
OS 54.26935044 -38.64472332
OS 54.26935044 -38.6521198
OS 54.26842588 -38.66228996
OS 54.26842588 -38.67338468
OS 54.26750132 -38.68540396
OS 54.26657676 -38.6983478
OS 54.26380308 -38.72793372
OS 54.25918028 -38.7584442
OS 54.25363292 -38.78803012
OS 54.24993468 -38.80189852
OS 54.24531188 -38.81576692
OS 54.24531188 -38.81669148
OS 54.24438732 -38.8185406
OS 54.2425382 -38.82223884
OS 54.24068908 -38.82686164
OS 54.23883996 -38.83333356
OS 54.23514172 -38.83980548
OS 54.22774524 -38.855523
OS 54.21849964 -38.87216508
OS 54.20648036 -38.89065628
OS 54.19261196 -38.90729836
OS 54.17596988 -38.92301588
OS 54.17504532 -38.92301588
OS 54.17412076 -38.924865
OS 54.17134708 -38.92671412
OS 54.16764884 -38.92856324
OS 54.16302604 -38.93133692
OS 54.15840324 -38.93503516
OS 54.14453484 -38.94150708
OS 54.12789276 -38.947979
OS 54.108477 -38.95445092
OS 54.085363 -38.95814916
OS 54.06039988 -38.95999828
OS 54.05115428 -38.95999828
OS 54.04468236 -38.95907372
OS 54.03728588 -38.95814916
OS 54.02804028 -38.95630004
OS 54.01787012 -38.95445092
OS 54.0067754 -38.95167724
OS 53.99568068 -38.947979
OS 53.9836614 -38.94428076
OS 53.97164212 -38.9387334
OS 53.95962284 -38.93226148
OS 53.94760356 -38.924865
OS 53.93558428 -38.9156194
OS 53.92448956 -38.90544924
OS 53.9143194 -38.89435452
OS 53.91339484 -38.89342996
OS 53.91154572 -38.89065628
OS 53.90877204 -38.88603348
OS 53.90414924 -38.878637
OS 53.89952644 -38.87031596
OS 53.89490364 -38.85922124
OS 53.88843172 -38.8462774
OS 53.88288436 -38.83148444
OS 53.877337 -38.81484236
OS 53.87178964 -38.7954266
OS 53.86624228 -38.77416172
OS 53.86161948 -38.75012316
OS 53.85699668 -38.72423548
OS 53.854223 -38.69649868
OS 53.85237388 -38.6659882
OS 53.85144932 -38.6336286
OS 53.85144932 -38.63270404
OS 53.85144932 -38.6290058
OS 53.85144932 -38.62253388
OS 53.85144932 -38.6151374
OS 53.85237388 -38.60496724
OS 53.85237388 -38.59387252
OS 53.85329844 -38.58185324
OS 53.854223 -38.56798484
OS 53.85699668 -38.53932348
OS 53.86161948 -38.508813
OS 53.86716684 -38.47830252
OS 53.87086508 -38.46443412
OS 53.87456332 -38.45056572
OS 53.87456332 -38.44964116
OS 53.87548788 -38.44779204
OS 53.877337 -38.4440938
OS 53.87918612 -38.439471
OS 53.88103524 -38.43299908
OS 53.88473348 -38.42652716
OS 53.89212996 -38.41080964
OS 53.90137556 -38.39416756
OS 53.91339484 -38.37660092
OS 53.92726324 -38.35903428
OS 53.94390532 -38.34424132
OS 53.94482988 -38.34424132
OS 53.94575444 -38.3423922
OS 53.94852812 -38.34054308
OS 53.95222636 -38.33869396
OS 53.95684916 -38.33499572
OS 53.96239652 -38.33222204
OS 53.97626492 -38.32482556
OS 53.992907 -38.31835364
OS 54.01232276 -38.31188172
OS 54.03543676 -38.30818348
OS 54.06039988 -38.30633436
OS 54.06872092 -38.30633436
OS 54.07889108 -38.30725892
OE
OB 53.23846604 -38.94890356 I
OS 53.14878372 -38.94890356
OS 53.14878372 -38.85922124
OS 53.23846604 -38.85922124
OS 53.23846604 -38.94890356
OE
OB 53.00177868 -38.39231844 I
OS 52.74567556 -38.39231844
OS 52.71146684 -38.56521116
OS 52.7123914 -38.5642866
OS 52.71424052 -38.56336204
OS 52.7170142 -38.56151292
OS 52.721637 -38.55873924
OS 52.72718436 -38.55596556
OS 52.73365628 -38.55226732
OS 52.74844924 -38.54487084
OS 52.76694044 -38.53747436
OS 52.78728076 -38.53100244
OS 52.8094702 -38.52637964
OS 52.82056492 -38.52453052
OS 52.84090524 -38.52453052
OS 52.8464526 -38.52545508
OS 52.85384908 -38.52637964
OS 52.86217012 -38.5273042
OS 52.87141572 -38.52915332
OS 52.88158588 -38.531927
OS 52.90377532 -38.53839892
OS 52.9157946 -38.54302172
OS 52.92781388 -38.54949364
OS 52.93983316 -38.55596556
OS 52.95185244 -38.56336204
OS 52.96294716 -38.57260764
OS 52.97404188 -38.5827778
OS 52.97496644 -38.58370236
OS 52.97681556 -38.58555148
OS 52.97958924 -38.58832516
OS 52.98328748 -38.59294796
OS 52.98791028 -38.59941988
OS 52.99253308 -38.6058918
OS 52.99808044 -38.61421284
OS 53.0036278 -38.62345844
OS 53.0082506 -38.6336286
OS 53.01379796 -38.64472332
OS 53.01842076 -38.65766716
OS 53.02304356 -38.670611
OS 53.0267418 -38.6844794
OS 53.02951548 -38.70019692
OS 53.0313646 -38.71591444
OS 53.03228916 -38.73255652
OS 53.03228916 -38.73348108
OS 53.03228916 -38.73625476
OS 53.03228916 -38.74087756
OS 53.0313646 -38.74734948
OS 53.03044004 -38.75474596
OS 53.02951548 -38.763067
OS 53.02766636 -38.77323716
OS 53.02581724 -38.78340732
OS 53.02026988 -38.80744588
OS 53.01102428 -38.832409
OS 53.00547692 -38.84535284
OS 52.99808044 -38.85737212
OS 52.99068396 -38.87031596
OS 52.98143836 -38.88233524
OS 52.9805138 -38.8832598
OS 52.97866468 -38.88603348
OS 52.97496644 -38.88973172
OS 52.97034364 -38.89435452
OS 52.96387172 -38.89990188
OS 52.95647524 -38.90729836
OS 52.94722964 -38.91377028
OS 52.93705948 -38.92116676
OS 52.92596476 -38.92856324
OS 52.91302092 -38.93503516
OS 52.89915252 -38.94150708
OS 52.88435956 -38.947979
OS 52.86864204 -38.9526018
OS 52.8510754 -38.95630004
OS 52.8325842 -38.95907372
OS 52.81316844 -38.95999828
OS 52.8048474 -38.95999828
OS 52.79837548 -38.95907372
OS 52.790979 -38.95814916
OS 52.78265796 -38.9572246
OS 52.7724878 -38.95630004
OS 52.76231764 -38.95352636
OS 52.73920364 -38.947979
OS 52.71608964 -38.93965796
OS 52.70407036 -38.9341106
OS 52.69205108 -38.92763868
OS 52.68095636 -38.9202422
OS 52.66986164 -38.91192116
OS 52.66893708 -38.9109966
OS 52.66708796 -38.91007204
OS 52.66523884 -38.9063738
OS 52.6615406 -38.90267556
OS 52.6569178 -38.89805276
OS 52.652295 -38.8925054
OS 52.64674764 -38.88510892
OS 52.64212484 -38.87678788
OS 52.63657748 -38.86846684
OS 52.63103012 -38.85829668
OS 52.62085996 -38.83610724
OS 52.61253892 -38.81021956
OS 52.60976524 -38.79635116
OS 52.60791612 -38.7815582
OS 52.69020196 -38.77508628
OS 52.69020196 -38.77601084
OS 52.69020196 -38.77785996
OS 52.69112652 -38.78063364
OS 52.69205108 -38.78525644
OS 52.69482476 -38.7954266
OS 52.698523 -38.809295
OS 52.70407036 -38.8231634
OS 52.71146684 -38.83888092
OS 52.72071244 -38.85274932
OS 52.73180716 -38.86569316
OS 52.73365628 -38.86661772
OS 52.73735452 -38.87031596
OS 52.744751 -38.87493876
OS 52.75492116 -38.88048612
OS 52.76601588 -38.88603348
OS 52.77988428 -38.89065628
OS 52.7956018 -38.89435452
OS 52.81316844 -38.89527908
OS 52.8187158 -38.89527908
OS 52.82241404 -38.89435452
OS 52.83350876 -38.89342996
OS 52.8464526 -38.88973172
OS 52.86217012 -38.88510892
OS 52.87788764 -38.87771244
OS 52.89452972 -38.86661772
OS 52.9019262 -38.8601458
OS 52.90932268 -38.85274932
OS 52.91024724 -38.85182476
OS 52.9111718 -38.8509002
OS 52.91302092 -38.84812652
OS 52.9157946 -38.84535284
OS 52.92226652 -38.83518268
OS 52.929663 -38.82223884
OS 52.93613492 -38.80652132
OS 52.94260684 -38.78710556
OS 52.94722964 -38.76399156
OS 52.94907876 -38.75197228
OS 52.94907876 -38.73902844
OS 52.94907876 -38.73810388
OS 52.94907876 -38.73625476
OS 52.94907876 -38.73255652
OS 52.9481542 -38.72793372
OS 52.9481542 -38.72238636
OS 52.94722964 -38.71591444
OS 52.94445596 -38.70112148
OS 52.93983316 -38.68355484
OS 52.93336124 -38.6659882
OS 52.92411564 -38.64934612
OS 52.9111718 -38.6336286
OS 52.9111718 -38.63270404
OS 52.90932268 -38.63177948
OS 52.90469988 -38.62715668
OS 52.89637884 -38.62068476
OS 52.88528412 -38.61328828
OS 52.87049116 -38.60681636
OS 52.85384908 -38.60034444
OS 52.83443332 -38.59572164
OS 52.8233386 -38.59387252
OS 52.80577196 -38.59387252
OS 52.79837548 -38.59479708
OS 52.78912988 -38.59572164
OS 52.77803516 -38.59849532
OS 52.76694044 -38.601269
OS 52.75492116 -38.6058918
OS 52.74290188 -38.61143916
OS 52.74197732 -38.61236372
OS 52.73827908 -38.61421284
OS 52.73273172 -38.61883564
OS 52.72533524 -38.62345844
OS 52.71793876 -38.62993036
OS 52.71054228 -38.6382514
OS 52.70222124 -38.64657244
OS 52.69574932 -38.6567426
OS 52.62178452 -38.64657244
OS 52.68373004 -38.31742908
OS 53.00177868 -38.31742908
OS 53.00177868 -38.39231844
OE
OB 53.23846604 -38.57445676 I
OS 53.14878372 -38.57445676
OS 53.14878372 -38.48477444
OS 53.23846604 -38.48477444
OS 53.23846604 -38.57445676
OE
OB 54.48199924 -38.57445676 I
OS 54.39231692 -38.57445676
OS 54.39231692 -38.48477444
OS 54.48199924 -38.48477444
OS 54.48199924 -38.57445676
OE
OB 56.14990548 -38.3100326 I
OS 56.165623 -38.31095716
OS 56.18226508 -38.31188172
OS 56.1979826 -38.31373084
OS 56.211851 -38.31557996
OS 56.21370012 -38.31557996
OS 56.22017204 -38.31742908
OS 56.22849308 -38.3192782
OS 56.2395878 -38.32205188
OS 56.25160708 -38.32667468
OS 56.26455092 -38.33222204
OS 56.27841932 -38.33869396
OS 56.2904386 -38.34609044
OS 56.29228772 -38.347015
OS 56.29598596 -38.34978868
OS 56.30153332 -38.35533604
OS 56.3089298 -38.36180796
OS 56.31725084 -38.370129
OS 56.32557188 -38.38122372
OS 56.33481748 -38.393243
OS 56.34221396 -38.4071114
OS 56.34313852 -38.40896052
OS 56.34498764 -38.41358332
OS 56.34868588 -38.42190436
OS 56.35238412 -38.43299908
OS 56.3551578 -38.44594292
OS 56.35885604 -38.46073588
OS 56.36070516 -38.47737796
OS 56.36162972 -38.4949446
OS 56.36162972 -38.49586916
OS 56.36162972 -38.49864284
OS 56.36162972 -38.50234108
OS 56.36070516 -38.508813
OS 56.3597806 -38.51528492
OS 56.35885604 -38.52360596
OS 56.35700692 -38.53285156
OS 56.3551578 -38.54302172
OS 56.34868588 -38.5642866
OS 56.34498764 -38.57538132
OS 56.33944028 -38.5874006
OS 56.33296836 -38.59941988
OS 56.32649644 -38.6105146
OS 56.3181754 -38.62160932
OS 56.3089298 -38.63270404
OS 56.30800524 -38.6336286
OS 56.30615612 -38.63547772
OS 56.30338244 -38.6382514
OS 56.29875964 -38.64102508
OS 56.29321228 -38.64564788
OS 56.2858158 -38.65027068
OS 56.2765702 -38.65581804
OS 56.26640004 -38.66044084
OS 56.25438076 -38.6659882
OS 56.24051236 -38.67153556
OS 56.2257194 -38.67615836
OS 56.20815276 -38.6798566
OS 56.18966156 -38.68355484
OS 56.16932124 -38.68632852
OS 56.14620724 -38.68817764
OS 56.12216868 -38.6891022
OS 55.95852156 -38.6891022
OS 55.95852156 -38.94890356
OS 55.87346204 -38.94890356
OS 55.87346204 -38.30910804
OS 56.13603708 -38.30910804
OS 56.14990548 -38.3100326
OE
OB 57.07723916 -38.94890356 I
OS 56.99587788 -38.94890356
OS 56.99587788 -38.41358332
OS 56.80911676 -38.94890356
OS 56.73330284 -38.94890356
OS 56.54839084 -38.40433772
OS 56.54839084 -38.94890356
OS 56.46702956 -38.94890356
OS 56.46702956 -38.30910804
OS 56.59369428 -38.30910804
OS 56.74532212 -38.763067
OS 56.74532212 -38.76399156
OS 56.74624668 -38.76584068
OS 56.74717124 -38.76861436
OS 56.74902036 -38.77323716
OS 56.7527186 -38.78433188
OS 56.7573414 -38.79820028
OS 56.7619642 -38.8139178
OS 56.76751156 -38.82963532
OS 56.77213436 -38.84442828
OS 56.7758326 -38.85737212
OS 56.77675716 -38.855523
OS 56.77768172 -38.8509002
OS 56.7804554 -38.84257916
OS 56.78415364 -38.83148444
OS 56.78877644 -38.81669148
OS 56.79524836 -38.79912484
OS 56.80172028 -38.77878452
OS 56.81004132 -38.75474596
OS 56.96351828 -38.30910804
OS 57.07723916 -38.30910804
OS 57.07723916 -38.94890356
OE
OB 55.3150278 -38.30725892 I
OS 55.32704708 -38.30910804
OS 55.34184004 -38.31188172
OS 55.35848212 -38.31650452
OS 55.3751242 -38.32205188
OS 55.39176628 -38.32944836
OS 55.39269084 -38.32944836
OS 55.3936154 -38.33037292
OS 55.39916276 -38.3331466
OS 55.4074838 -38.33869396
OS 55.4167294 -38.34516588
OS 55.42782412 -38.35441148
OS 55.43891884 -38.36458164
OS 55.45001356 -38.37660092
OS 55.45925916 -38.39046932
OS 55.46018372 -38.39231844
OS 55.4629574 -38.39694124
OS 55.46665564 -38.40526228
OS 55.47127844 -38.41543244
OS 55.47590124 -38.42745172
OS 55.47959948 -38.44132012
OS 55.48237316 -38.45703764
OS 55.48329772 -38.47275516
OS 55.48329772 -38.47460428
OS 55.48329772 -38.48015164
OS 55.48237316 -38.48754812
OS 55.48052404 -38.49771828
OS 55.47775036 -38.50973756
OS 55.47312756 -38.5226814
OS 55.4675802 -38.53562524
OS 55.46018372 -38.54856908
OS 55.45925916 -38.5504182
OS 55.45648548 -38.55411644
OS 55.45093812 -38.56058836
OS 55.44354164 -38.56798484
OS 55.43429604 -38.57630588
OS 55.42320132 -38.58555148
OS 55.41025748 -38.59387252
OS 55.39453996 -38.60219356
OS 55.39546452 -38.60219356
OS 55.39731364 -38.60311812
OS 55.40008732 -38.60404268
OS 55.40378556 -38.60496724
OS 55.41395572 -38.60866548
OS 55.42689956 -38.61421284
OS 55.44169252 -38.62160932
OS 55.45648548 -38.63085492
OS 55.47035388 -38.6428742
OS 55.48329772 -38.6567426
OS 55.48422228 -38.65859172
OS 55.48792052 -38.66413908
OS 55.49346788 -38.67338468
OS 55.49901524 -38.68540396
OS 55.5045626 -38.70019692
OS 55.51010996 -38.71776356
OS 55.5138082 -38.73810388
OS 55.51473276 -38.76029332
OS 55.51473276 -38.76121788
OS 55.51473276 -38.76399156
OS 55.51473276 -38.76861436
OS 55.5138082 -38.77416172
OS 55.51288364 -38.7815582
OS 55.51103452 -38.78987924
OS 55.5091854 -38.79912484
OS 55.50733628 -38.809295
OS 55.4999398 -38.83148444
OS 55.49439244 -38.84350372
OS 55.48884508 -38.85459844
OS 55.4814486 -38.86661772
OS 55.47312756 -38.878637
OS 55.46388196 -38.89065628
OS 55.45278724 -38.901751
OS 55.45186268 -38.90267556
OS 55.45001356 -38.90452468
OS 55.44631532 -38.90729836
OS 55.44169252 -38.9109966
OS 55.43614516 -38.9156194
OS 55.42874868 -38.9202422
OS 55.42042764 -38.92578956
OS 55.41025748 -38.93041236
OS 55.40008732 -38.93595972
OS 55.38806804 -38.94150708
OS 55.37604876 -38.94612988
OS 55.36218036 -38.95075268
OS 55.3473874 -38.95445092
OS 55.33166988 -38.9572246
OS 55.31595236 -38.95907372
OS 55.29838572 -38.95999828
OS 55.29006468 -38.95999828
OS 55.28451732 -38.95907372
OS 55.27712084 -38.95814916
OS 55.2687998 -38.9572246
OS 55.2595542 -38.95537548
OS 55.24938404 -38.95352636
OS 55.2271946 -38.947979
OS 55.2040806 -38.9387334
OS 55.19206132 -38.93318604
OS 55.1809666 -38.92671412
OS 55.16987188 -38.91839308
OS 55.15877716 -38.91007204
OS 55.1578526 -38.90914748
OS 55.15600348 -38.90729836
OS 55.1532298 -38.90452468
OS 55.15045612 -38.90082644
OS 55.14583332 -38.89620364
OS 55.14121052 -38.88973172
OS 55.13566316 -38.8832598
OS 55.1301158 -38.87493876
OS 55.12456844 -38.86569316
OS 55.11902108 -38.85644756
OS 55.10885092 -38.83425812
OS 55.10052988 -38.80837044
OS 55.0977562 -38.79450204
OS 55.09590708 -38.77970908
OS 55.17449468 -38.76953892
OS 55.17449468 -38.77046348
OS 55.17541924 -38.7723126
OS 55.1763438 -38.77601084
OS 55.17726836 -38.78063364
OS 55.17819292 -38.786181
OS 55.18004204 -38.79265292
OS 55.18466484 -38.80652132
OS 55.19113676 -38.8231634
OS 55.1994578 -38.83888092
OS 55.2087034 -38.85367388
OS 55.21979812 -38.86661772
OS 55.22164724 -38.86754228
OS 55.22534548 -38.87124052
OS 55.23274196 -38.87586332
OS 55.24198756 -38.88048612
OS 55.25308228 -38.88603348
OS 55.26695068 -38.89065628
OS 55.2826682 -38.89435452
OS 55.29931028 -38.89527908
OS 55.30485764 -38.89527908
OS 55.30855588 -38.89435452
OS 55.31872604 -38.89342996
OS 55.33166988 -38.89065628
OS 55.34646284 -38.88603348
OS 55.36218036 -38.87956156
OS 55.37789788 -38.87031596
OS 55.39269084 -38.85737212
OS 55.39453996 -38.855523
OS 55.39916276 -38.84997564
OS 55.40471012 -38.8416546
OS 55.4121066 -38.83055988
OS 55.41950308 -38.81669148
OS 55.42505044 -38.80097396
OS 55.42967324 -38.78248276
OS 55.43152236 -38.76214244
OS 55.43152236 -38.76121788
OS 55.43152236 -38.75936876
OS 55.43152236 -38.75659508
OS 55.4305978 -38.75289684
OS 55.42967324 -38.74272668
OS 55.42689956 -38.7307074
OS 55.42320132 -38.71591444
OS 55.4167294 -38.70112148
OS 55.4074838 -38.68632852
OS 55.39546452 -38.67246012
OS 55.3936154 -38.670611
OS 55.3889926 -38.66691276
OS 55.38159612 -38.6613654
OS 55.37142596 -38.65489348
OS 55.35848212 -38.64842156
OS 55.3427646 -38.6428742
OS 55.32519796 -38.63917596
OS 55.3057822 -38.63732684
OS 55.29746116 -38.63732684
OS 55.29098924 -38.6382514
OS 55.2826682 -38.63917596
OS 55.2734226 -38.64102508
OS 55.26232788 -38.6428742
OS 55.2503086 -38.64564788
OS 55.2595542 -38.57630588
OS 55.264177 -38.57630588
OS 55.26787524 -38.57723044
OS 55.27989452 -38.57723044
OS 55.29006468 -38.57538132
OS 55.30208396 -38.5735322
OS 55.31595236 -38.57075852
OS 55.33166988 -38.56613572
OS 55.34646284 -38.5596638
OS 55.36218036 -38.55134276
OS 55.36310492 -38.55134276
OS 55.36402948 -38.5504182
OS 55.36865228 -38.54671996
OS 55.3751242 -38.54024804
OS 55.38252068 -38.531927
OS 55.38991716 -38.51990772
OS 55.39638908 -38.50603932
OS 55.40101188 -38.4903218
OS 55.402861 -38.4810762
OS 55.402861 -38.47090604
OS 55.402861 -38.46998148
OS 55.402861 -38.46905692
OS 55.402861 -38.46350956
OS 55.40101188 -38.45611308
OS 55.39916276 -38.44594292
OS 55.39546452 -38.4348482
OS 55.39084172 -38.42282892
OS 55.38344524 -38.41080964
OS 55.37327508 -38.39971492
OS 55.37235052 -38.39879036
OS 55.36772772 -38.39509212
OS 55.3612558 -38.39046932
OS 55.35293476 -38.38492196
OS 55.34184004 -38.38029916
OS 55.3288962 -38.37567636
OS 55.31410324 -38.37197812
OS 55.29746116 -38.37105356
OS 55.29006468 -38.37105356
OS 55.28174364 -38.37290268
OS 55.27064892 -38.3747518
OS 55.25862964 -38.37845004
OS 55.24661036 -38.38307284
OS 55.23366652 -38.39046932
OS 55.22164724 -38.39971492
OS 55.22072268 -38.40063948
OS 55.21702444 -38.40526228
OS 55.21147708 -38.4117342
OS 55.20500516 -38.4209798
OS 55.19853324 -38.43299908
OS 55.19206132 -38.44779204
OS 55.18651396 -38.46535868
OS 55.18281572 -38.485699
OS 55.10422812 -38.4718306
OS 55.10422812 -38.47090604
OS 55.10515268 -38.46813236
OS 55.10607724 -38.46443412
OS 55.1070018 -38.45888676
OS 55.10885092 -38.45241484
OS 55.1116246 -38.44501836
OS 55.11717196 -38.42745172
OS 55.12641756 -38.4071114
OS 55.13751228 -38.38677108
OS 55.15138068 -38.36735532
OS 55.16894732 -38.34978868
OS 55.16987188 -38.34886412
OS 55.171721 -38.34793956
OS 55.17449468 -38.34609044
OS 55.17819292 -38.34331676
OS 55.18281572 -38.33961852
OS 55.18928764 -38.33592028
OS 55.19575956 -38.33222204
OS 55.2040806 -38.32759924
OS 55.2225718 -38.32020276
OS 55.24383668 -38.31280628
OS 55.2687998 -38.30818348
OS 55.28174364 -38.30633436
OS 55.30485764 -38.30633436
OS 55.3150278 -38.30725892
OE
OB 54.48199924 -38.94890356 I
OS 54.39231692 -38.94890356
OS 54.39231692 -38.85922124
OS 54.48199924 -38.85922124
OS 54.48199924 -38.94890356
OE
OB 54.9914318 -38.39231844 I
OS 54.73532868 -38.39231844
OS 54.70111996 -38.56521116
OS 54.70204452 -38.5642866
OS 54.70389364 -38.56336204
OS 54.70666732 -38.56151292
OS 54.71129012 -38.55873924
OS 54.71683748 -38.55596556
OS 54.7233094 -38.55226732
OS 54.73810236 -38.54487084
OS 54.75659356 -38.53747436
OS 54.77693388 -38.53100244
OS 54.79912332 -38.52637964
OS 54.81021804 -38.52453052
OS 54.83055836 -38.52453052
OS 54.83610572 -38.52545508
OS 54.8435022 -38.52637964
OS 54.85182324 -38.5273042
OS 54.86106884 -38.52915332
OS 54.871239 -38.531927
OS 54.89342844 -38.53839892
OS 54.90544772 -38.54302172
OS 54.917467 -38.54949364
OS 54.92948628 -38.55596556
OS 54.94150556 -38.56336204
OS 54.95260028 -38.57260764
OS 54.963695 -38.5827778
OS 54.96461956 -38.58370236
OS 54.96646868 -38.58555148
OS 54.96924236 -38.58832516
OS 54.9729406 -38.59294796
OS 54.9775634 -38.59941988
OS 54.9821862 -38.6058918
OS 54.98773356 -38.61421284
OS 54.99328092 -38.62345844
OS 54.99790372 -38.6336286
OS 55.00345108 -38.64472332
OS 55.00807388 -38.65766716
OS 55.01269668 -38.670611
OS 55.01639492 -38.6844794
OS 55.0191686 -38.70019692
OS 55.02101772 -38.71591444
OS 55.02194228 -38.73255652
OS 55.02194228 -38.73348108
OS 55.02194228 -38.73625476
OS 55.02194228 -38.74087756
OS 55.02101772 -38.74734948
OS 55.02009316 -38.75474596
OS 55.0191686 -38.763067
OS 55.01731948 -38.77323716
OS 55.01547036 -38.78340732
OS 55.009923 -38.80744588
OS 55.0006774 -38.832409
OS 54.99513004 -38.84535284
OS 54.98773356 -38.85737212
OS 54.98033708 -38.87031596
OS 54.97109148 -38.88233524
OS 54.97016692 -38.8832598
OS 54.9683178 -38.88603348
OS 54.96461956 -38.88973172
OS 54.95999676 -38.89435452
OS 54.95352484 -38.89990188
OS 54.94612836 -38.90729836
OS 54.93688276 -38.91377028
OS 54.9267126 -38.92116676
OS 54.91561788 -38.92856324
OS 54.90267404 -38.93503516
OS 54.88880564 -38.94150708
OS 54.87401268 -38.947979
OS 54.85829516 -38.9526018
OS 54.84072852 -38.95630004
OS 54.82223732 -38.95907372
OS 54.80282156 -38.95999828
OS 54.79450052 -38.95999828
OS 54.7880286 -38.95907372
OS 54.78063212 -38.95814916
OS 54.77231108 -38.9572246
OS 54.76214092 -38.95630004
OS 54.75197076 -38.95352636
OS 54.72885676 -38.947979
OS 54.70574276 -38.93965796
OS 54.69372348 -38.9341106
OS 54.6817042 -38.92763868
OS 54.67060948 -38.9202422
OS 54.65951476 -38.91192116
OS 54.6585902 -38.9109966
OS 54.65674108 -38.91007204
OS 54.65489196 -38.9063738
OS 54.65119372 -38.90267556
OS 54.64657092 -38.89805276
OS 54.64194812 -38.8925054
OS 54.63640076 -38.88510892
OS 54.63177796 -38.87678788
OS 54.6262306 -38.86846684
OS 54.62068324 -38.85829668
OS 54.61051308 -38.83610724
OS 54.60219204 -38.81021956
OS 54.59941836 -38.79635116
OS 54.59756924 -38.7815582
OS 54.67985508 -38.77508628
OS 54.67985508 -38.77601084
OS 54.67985508 -38.77785996
OS 54.68077964 -38.78063364
OS 54.6817042 -38.78525644
OS 54.68447788 -38.7954266
OS 54.68817612 -38.809295
OS 54.69372348 -38.8231634
OS 54.70111996 -38.83888092
OS 54.71036556 -38.85274932
OS 54.72146028 -38.86569316
OS 54.7233094 -38.86661772
OS 54.72700764 -38.87031596
OS 54.73440412 -38.87493876
OS 54.74457428 -38.88048612
OS 54.755669 -38.88603348
OS 54.7695374 -38.89065628
OS 54.78525492 -38.89435452
OS 54.80282156 -38.89527908
OS 54.80836892 -38.89527908
OS 54.81206716 -38.89435452
OS 54.82316188 -38.89342996
OS 54.83610572 -38.88973172
OS 54.85182324 -38.88510892
OS 54.86754076 -38.87771244
OS 54.88418284 -38.86661772
OS 54.89157932 -38.8601458
OS 54.8989758 -38.85274932
OS 54.89990036 -38.85182476
OS 54.90082492 -38.8509002
OS 54.90267404 -38.84812652
OS 54.90544772 -38.84535284
OS 54.91191964 -38.83518268
OS 54.91931612 -38.82223884
OS 54.92578804 -38.80652132
OS 54.93225996 -38.78710556
OS 54.93688276 -38.76399156
OS 54.93873188 -38.75197228
OS 54.93873188 -38.73902844
OS 54.93873188 -38.73810388
OS 54.93873188 -38.73625476
OS 54.93873188 -38.73255652
OS 54.93780732 -38.72793372
OS 54.93780732 -38.72238636
OS 54.93688276 -38.71591444
OS 54.93410908 -38.70112148
OS 54.92948628 -38.68355484
OS 54.92301436 -38.6659882
OS 54.91376876 -38.64934612
OS 54.90082492 -38.6336286
OS 54.90082492 -38.63270404
OS 54.8989758 -38.63177948
OS 54.894353 -38.62715668
OS 54.88603196 -38.62068476
OS 54.87493724 -38.61328828
OS 54.86014428 -38.60681636
OS 54.8435022 -38.60034444
OS 54.82408644 -38.59572164
OS 54.81299172 -38.59387252
OS 54.79542508 -38.59387252
OS 54.7880286 -38.59479708
OS 54.778783 -38.59572164
OS 54.76768828 -38.59849532
OS 54.75659356 -38.601269
OS 54.74457428 -38.6058918
OS 54.732555 -38.61143916
OS 54.73163044 -38.61236372
OS 54.7279322 -38.61421284
OS 54.72238484 -38.61883564
OS 54.71498836 -38.62345844
OS 54.70759188 -38.62993036
OS 54.7001954 -38.6382514
OS 54.69187436 -38.64657244
OS 54.68540244 -38.6567426
OS 54.61143764 -38.64657244
OS 54.67338316 -38.31742908
OS 54.9914318 -38.31742908
OS 54.9914318 -38.39231844
OE
OB 49.95350436 -38.72331092 I
OS 50.040413 -38.72331092
OS 50.040413 -38.7954266
OS 49.95350436 -38.7954266
OS 49.95350436 -38.94890356
OS 49.87491676 -38.94890356
OS 49.87491676 -38.7954266
OS 49.5966242 -38.7954266
OS 49.5966242 -38.72331092
OS 49.88970972 -38.30910804
OS 49.95350436 -38.30910804
OS 49.95350436 -38.72331092
OE
OB 50.1467374 -38.95999828 I
OS 50.08386732 -38.95999828
OS 50.26970388 -38.29801332
OS 50.33257396 -38.29801332
OS 50.1467374 -38.95999828
OE
OB 49.35346492 -38.30725892 I
OS 49.3608614 -38.30818348
OS 49.370107 -38.30910804
OS 49.38027716 -38.31095716
OS 49.39044732 -38.31280628
OS 49.41448588 -38.3192782
OS 49.43852444 -38.3285238
OS 49.45054372 -38.33407116
OS 49.462563 -38.34054308
OS 49.47365772 -38.34886412
OS 49.48382788 -38.35810972
OS 49.48475244 -38.35903428
OS 49.48660156 -38.35995884
OS 49.48845068 -38.36365708
OS 49.49214892 -38.36735532
OS 49.49677172 -38.37197812
OS 49.50139452 -38.37845004
OS 49.50601732 -38.38492196
OS 49.51156468 -38.393243
OS 49.52081028 -38.41080964
OS 49.53005588 -38.43299908
OS 49.53375412 -38.4440938
OS 49.53560324 -38.45703764
OS 49.53745236 -38.46998148
OS 49.53837692 -38.48384988
OS 49.53837692 -38.485699
OS 49.53837692 -38.4903218
OS 49.53745236 -38.49771828
OS 49.5365278 -38.50788844
OS 49.53467868 -38.51898316
OS 49.53098044 -38.531927
OS 49.5272822 -38.5457954
OS 49.52173484 -38.5596638
OS 49.52081028 -38.56151292
OS 49.51896116 -38.56613572
OS 49.51526292 -38.5735322
OS 49.50971556 -38.58370236
OS 49.50231908 -38.59479708
OS 49.49307348 -38.60866548
OS 49.48197876 -38.62253388
OS 49.46903492 -38.6382514
OS 49.4671858 -38.64010052
OS 49.462563 -38.64564788
OS 49.4579402 -38.65027068
OS 49.4533174 -38.65489348
OS 49.44777004 -38.66044084
OS 49.44037356 -38.66783732
OS 49.43297708 -38.6752338
OS 49.42373148 -38.68355484
OS 49.41448588 -38.69280044
OS 49.40339116 -38.7029706
OS 49.39137188 -38.71314076
OS 49.37842804 -38.72516004
OS 49.36363508 -38.73717932
OS 49.34884212 -38.75012316
OS 49.34791756 -38.75104772
OS 49.34606844 -38.75289684
OS 49.3423702 -38.75567052
OS 49.3377474 -38.75936876
OS 49.33220004 -38.76491612
OS 49.32572812 -38.77046348
OS 49.31093516 -38.78248276
OS 49.29521764 -38.79635116
OS 49.28042468 -38.81021956
OS 49.26748084 -38.82223884
OS 49.26193348 -38.82686164
OS 49.25731068 -38.83148444
OS 49.25638612 -38.832409
OS 49.25361244 -38.83518268
OS 49.2499142 -38.83888092
OS 49.2452914 -38.84442828
OS 49.2406686 -38.8509002
OS 49.23512124 -38.85737212
OS 49.22402652 -38.87308964
OS 49.53930148 -38.87308964
OS 49.53930148 -38.94890356
OS 49.11492844 -38.94890356
OS 49.11492844 -38.947979
OS 49.11492844 -38.94428076
OS 49.11492844 -38.9387334
OS 49.115853 -38.93133692
OS 49.11677756 -38.92301588
OS 49.11862668 -38.91377028
OS 49.1204758 -38.90452468
OS 49.12417404 -38.89435452
OS 49.12417404 -38.89342996
OS 49.1250986 -38.8925054
OS 49.12694772 -38.88695804
OS 49.13064596 -38.878637
OS 49.13619332 -38.86754228
OS 49.1435898 -38.85459844
OS 49.1528354 -38.83980548
OS 49.16300556 -38.82501252
OS 49.1759494 -38.809295
OS 49.1759494 -38.80837044
OS 49.17779852 -38.80744588
OS 49.18242132 -38.80189852
OS 49.19074236 -38.79357748
OS 49.20276164 -38.7815582
OS 49.21663004 -38.7676898
OS 49.23419668 -38.75104772
OS 49.25546156 -38.73255652
OS 49.27857556 -38.71314076
OS 49.27950012 -38.7122162
OS 49.28319836 -38.70944252
OS 49.28874572 -38.70481972
OS 49.29521764 -38.69927236
OS 49.30353868 -38.69187588
OS 49.31370884 -38.68355484
OS 49.323879 -38.67430924
OS 49.33589828 -38.66413908
OS 49.35901228 -38.64194964
OS 49.38212628 -38.6197602
OS 49.393221 -38.60866548
OS 49.40339116 -38.59757076
OS 49.41263676 -38.5874006
OS 49.42003324 -38.57723044
OS 49.42003324 -38.57630588
OS 49.42188236 -38.57538132
OS 49.42373148 -38.57260764
OS 49.4255806 -38.5689094
OS 49.43205252 -38.55873924
OS 49.439449 -38.54671996
OS 49.44592092 -38.531927
OS 49.45239284 -38.51620948
OS 49.45609108 -38.49864284
OS 49.4579402 -38.48200076
OS 49.4579402 -38.4810762
OS 49.4579402 -38.48015164
OS 49.45701564 -38.47460428
OS 49.45609108 -38.46535868
OS 49.4533174 -38.45518852
OS 49.44961916 -38.44224468
OS 49.44314724 -38.42930084
OS 49.4348262 -38.416357
OS 49.42373148 -38.40341316
OS 49.42188236 -38.40156404
OS 49.41725956 -38.3978658
OS 49.41078764 -38.393243
OS 49.40061748 -38.38677108
OS 49.38767364 -38.38122372
OS 49.37288068 -38.37567636
OS 49.35531404 -38.37197812
OS 49.33589828 -38.37105356
OS 49.33035092 -38.37105356
OS 49.32665268 -38.37197812
OS 49.31555796 -38.37290268
OS 49.30261412 -38.37567636
OS 49.28874572 -38.3793746
OS 49.2730282 -38.38584652
OS 49.25823524 -38.39416756
OS 49.24436684 -38.40526228
OS 49.24251772 -38.4071114
OS 49.23881948 -38.4117342
OS 49.23327212 -38.41913068
OS 49.22772476 -38.4302254
OS 49.22125284 -38.44316924
OS 49.21570548 -38.45981132
OS 49.21200724 -38.47830252
OS 49.21015812 -38.4995674
OS 49.1297214 -38.49124636
OS 49.1297214 -38.4903218
OS 49.13064596 -38.48754812
OS 49.13064596 -38.48292532
OS 49.13157052 -38.4764534
OS 49.13341964 -38.46905692
OS 49.13526876 -38.46073588
OS 49.13804244 -38.45056572
OS 49.14081612 -38.44039556
OS 49.1482126 -38.41820612
OS 49.15930732 -38.39601668
OS 49.16577924 -38.38492196
OS 49.17410028 -38.37382724
OS 49.18242132 -38.36365708
OS 49.19166692 -38.35441148
OS 49.19259148 -38.35348692
OS 49.1944406 -38.35256236
OS 49.19721428 -38.34978868
OS 49.20183708 -38.347015
OS 49.20738444 -38.34331676
OS 49.21385636 -38.33961852
OS 49.22125284 -38.33499572
OS 49.23049844 -38.33037292
OS 49.2406686 -38.32575012
OS 49.25176332 -38.32112732
OS 49.2637826 -38.31742908
OS 49.27672644 -38.31373084
OS 49.29059484 -38.31095716
OS 49.3053878 -38.30818348
OS 49.32110532 -38.30725892
OS 49.3377474 -38.30633436
OS 49.346993 -38.30633436
OS 49.35346492 -38.30725892
OE
OB 48.67576244 -38.94890356 I
OS 48.59717484 -38.94890356
OS 48.59717484 -38.4487166
OS 48.59625028 -38.44964116
OS 48.59162748 -38.4533394
OS 48.58608012 -38.45888676
OS 48.57683452 -38.46535868
OS 48.56666436 -38.47367972
OS 48.55372052 -38.48292532
OS 48.53892756 -38.49309548
OS 48.52228548 -38.50326564
OS 48.52136092 -38.50326564
OS 48.52043636 -38.5041902
OS 48.514889 -38.50788844
OS 48.5056434 -38.51251124
OS 48.49454868 -38.5180586
OS 48.48160484 -38.52453052
OS 48.46773644 -38.53100244
OS 48.45386804 -38.53747436
OS 48.43999964 -38.54302172
OS 48.43999964 -38.4672078
OS 48.4409242 -38.4672078
OS 48.44277332 -38.46535868
OS 48.44647156 -38.46443412
OS 48.45109436 -38.46166044
OS 48.45664172 -38.45888676
OS 48.46311364 -38.45518852
OS 48.47883116 -38.44594292
OS 48.49732236 -38.43577276
OS 48.51581356 -38.42282892
OS 48.53522932 -38.40803596
OS 48.55464508 -38.39231844
OS 48.55556964 -38.39139388
OS 48.5564942 -38.39046932
OS 48.55926788 -38.38769564
OS 48.56296612 -38.38492196
OS 48.57128716 -38.37567636
OS 48.58238188 -38.36458164
OS 48.5934766 -38.3516378
OS 48.60549588 -38.33684484
OS 48.61566604 -38.32205188
OS 48.62491164 -38.30633436
OS 48.67576244 -38.30633436
OS 48.67576244 -38.94890356
OE
OB 48.9032042 -38.95999828 I
OS 48.84033412 -38.95999828
OS 49.02617068 -38.29801332
OS 49.08904076 -38.29801332
OS 48.9032042 -38.95999828
OE
OB 50.59699812 -38.30725892 I
OS 50.6043946 -38.30818348
OS 50.6136402 -38.30910804
OS 50.62381036 -38.31095716
OS 50.63398052 -38.31280628
OS 50.65801908 -38.3192782
OS 50.68205764 -38.3285238
OS 50.69407692 -38.33407116
OS 50.7060962 -38.34054308
OS 50.71719092 -38.34886412
OS 50.72736108 -38.35810972
OS 50.72828564 -38.35903428
OS 50.73013476 -38.35995884
OS 50.73198388 -38.36365708
OS 50.73568212 -38.36735532
OS 50.74030492 -38.37197812
OS 50.74492772 -38.37845004
OS 50.74955052 -38.38492196
OS 50.75509788 -38.393243
OS 50.76434348 -38.41080964
OS 50.77358908 -38.43299908
OS 50.77728732 -38.4440938
OS 50.77913644 -38.45703764
OS 50.78098556 -38.46998148
OS 50.78191012 -38.48384988
OS 50.78191012 -38.485699
OS 50.78191012 -38.4903218
OS 50.78098556 -38.49771828
OS 50.780061 -38.50788844
OS 50.77821188 -38.51898316
OS 50.77451364 -38.531927
OS 50.7708154 -38.5457954
OS 50.76526804 -38.5596638
OS 50.76434348 -38.56151292
OS 50.76249436 -38.56613572
OS 50.75879612 -38.5735322
OS 50.75324876 -38.58370236
OS 50.74585228 -38.59479708
OS 50.73660668 -38.60866548
OS 50.72551196 -38.62253388
OS 50.71256812 -38.6382514
OS 50.710719 -38.64010052
OS 50.7060962 -38.64564788
OS 50.7014734 -38.65027068
OS 50.6968506 -38.65489348
OS 50.69130324 -38.66044084
OS 50.68390676 -38.66783732
OS 50.67651028 -38.6752338
OS 50.66726468 -38.68355484
OS 50.65801908 -38.69280044
OS 50.64692436 -38.7029706
OS 50.63490508 -38.71314076
OS 50.62196124 -38.72516004
OS 50.60716828 -38.73717932
OS 50.59237532 -38.75012316
OS 50.59145076 -38.75104772
OS 50.58960164 -38.75289684
OS 50.5859034 -38.75567052
OS 50.5812806 -38.75936876
OS 50.57573324 -38.76491612
OS 50.56926132 -38.77046348
OS 50.55446836 -38.78248276
OS 50.53875084 -38.79635116
OS 50.52395788 -38.81021956
OS 50.51101404 -38.82223884
OS 50.50546668 -38.82686164
OS 50.50084388 -38.83148444
OS 50.49991932 -38.832409
OS 50.49714564 -38.83518268
OS 50.4934474 -38.83888092
OS 50.4888246 -38.84442828
OS 50.4842018 -38.8509002
OS 50.47865444 -38.85737212
OS 50.46755972 -38.87308964
OS 50.78283468 -38.87308964
OS 50.78283468 -38.94890356
OS 50.35846164 -38.94890356
OS 50.35846164 -38.947979
OS 50.35846164 -38.94428076
OS 50.35846164 -38.9387334
OS 50.3593862 -38.93133692
OS 50.36031076 -38.92301588
OS 50.36215988 -38.91377028
OS 50.364009 -38.90452468
OS 50.36770724 -38.89435452
OS 50.36770724 -38.89342996
OS 50.3686318 -38.8925054
OS 50.37048092 -38.88695804
OS 50.37417916 -38.878637
OS 50.37972652 -38.86754228
OS 50.387123 -38.85459844
OS 50.3963686 -38.83980548
OS 50.40653876 -38.82501252
OS 50.4194826 -38.809295
OS 50.4194826 -38.80837044
OS 50.42133172 -38.80744588
OS 50.42595452 -38.80189852
OS 50.43427556 -38.79357748
OS 50.44629484 -38.7815582
OS 50.46016324 -38.7676898
OS 50.47772988 -38.75104772
OS 50.49899476 -38.73255652
OS 50.52210876 -38.71314076
OS 50.52303332 -38.7122162
OS 50.52673156 -38.70944252
OS 50.53227892 -38.70481972
OS 50.53875084 -38.69927236
OS 50.54707188 -38.69187588
OS 50.55724204 -38.68355484
OS 50.5674122 -38.67430924
OS 50.57943148 -38.66413908
OS 50.60254548 -38.64194964
OS 50.62565948 -38.6197602
OS 50.6367542 -38.60866548
OS 50.64692436 -38.59757076
OS 50.65616996 -38.5874006
OS 50.66356644 -38.57723044
OS 50.66356644 -38.57630588
OS 50.66541556 -38.57538132
OS 50.66726468 -38.57260764
OS 50.6691138 -38.5689094
OS 50.67558572 -38.55873924
OS 50.6829822 -38.54671996
OS 50.68945412 -38.531927
OS 50.69592604 -38.51620948
OS 50.69962428 -38.49864284
OS 50.7014734 -38.48200076
OS 50.7014734 -38.4810762
OS 50.7014734 -38.48015164
OS 50.70054884 -38.47460428
OS 50.69962428 -38.46535868
OS 50.6968506 -38.45518852
OS 50.69315236 -38.44224468
OS 50.68668044 -38.42930084
OS 50.6783594 -38.416357
OS 50.66726468 -38.40341316
OS 50.66541556 -38.40156404
OS 50.66079276 -38.3978658
OS 50.65432084 -38.393243
OS 50.64415068 -38.38677108
OS 50.63120684 -38.38122372
OS 50.61641388 -38.37567636
OS 50.59884724 -38.37197812
OS 50.57943148 -38.37105356
OS 50.57388412 -38.37105356
OS 50.57018588 -38.37197812
OS 50.55909116 -38.37290268
OS 50.54614732 -38.37567636
OS 50.53227892 -38.3793746
OS 50.5165614 -38.38584652
OS 50.50176844 -38.39416756
OS 50.48790004 -38.40526228
OS 50.48605092 -38.4071114
OS 50.48235268 -38.4117342
OS 50.47680532 -38.41913068
OS 50.47125796 -38.4302254
OS 50.46478604 -38.44316924
OS 50.45923868 -38.45981132
OS 50.45554044 -38.47830252
OS 50.45369132 -38.4995674
OS 50.3732546 -38.49124636
OS 50.3732546 -38.4903218
OS 50.37417916 -38.48754812
OS 50.37417916 -38.48292532
OS 50.37510372 -38.4764534
OS 50.37695284 -38.46905692
OS 50.37880196 -38.46073588
OS 50.38157564 -38.45056572
OS 50.38434932 -38.44039556
OS 50.3917458 -38.41820612
OS 50.40284052 -38.39601668
OS 50.40931244 -38.38492196
OS 50.41763348 -38.37382724
OS 50.42595452 -38.36365708
OS 50.43520012 -38.35441148
OS 50.43612468 -38.35348692
OS 50.4379738 -38.35256236
OS 50.44074748 -38.34978868
OS 50.44537028 -38.347015
OS 50.45091764 -38.34331676
OS 50.45738956 -38.33961852
OS 50.46478604 -38.33499572
OS 50.47403164 -38.33037292
OS 50.4842018 -38.32575012
OS 50.49529652 -38.32112732
OS 50.5073158 -38.31742908
OS 50.52025964 -38.31373084
OS 50.53412804 -38.31095716
OS 50.548921 -38.30818348
OS 50.56463852 -38.30725892
OS 50.5812806 -38.30633436
OS 50.5905262 -38.30633436
OS 50.59699812 -38.30725892
OE
OB 51.0944114 -38.30725892 I
OS 51.10643068 -38.30910804
OS 51.12029908 -38.31188172
OS 51.13509204 -38.31557996
OS 51.15080956 -38.32020276
OS 51.16560252 -38.32759924
OS 51.16652708 -38.32759924
OS 51.16745164 -38.3285238
OS 51.17207444 -38.33129748
OS 51.17947092 -38.33592028
OS 51.18871652 -38.3423922
OS 51.19888668 -38.3516378
OS 51.2099814 -38.36180796
OS 51.22015156 -38.37382724
OS 51.23032172 -38.38769564
OS 51.23124628 -38.38954476
OS 51.23494452 -38.39416756
OS 51.23864276 -38.4024886
OS 51.24511468 -38.41450788
OS 51.25066204 -38.42837628
OS 51.25805852 -38.4440938
OS 51.26453044 -38.462585
OS 51.2700778 -38.48292532
OS 51.2700778 -38.48384988
OS 51.27100236 -38.485699
OS 51.27192692 -38.48847268
OS 51.27285148 -38.49309548
OS 51.27377604 -38.49864284
OS 51.2747006 -38.50511476
OS 51.27654972 -38.5134358
OS 51.27747428 -38.5226814
OS 51.2793234 -38.53285156
OS 51.28024796 -38.54394628
OS 51.28117252 -38.55689012
OS 51.28302164 -38.56983396
OS 51.2839462 -38.58462692
OS 51.2839462 -38.59941988
OS 51.28487076 -38.61606196
OS 51.28487076 -38.6336286
OS 51.28487076 -38.63455316
OS 51.28487076 -38.6382514
OS 51.28487076 -38.64472332
OS 51.28487076 -38.6521198
OS 51.2839462 -38.66228996
OS 51.2839462 -38.67338468
OS 51.28302164 -38.68540396
OS 51.28209708 -38.6983478
OS 51.2793234 -38.72793372
OS 51.2747006 -38.7584442
OS 51.26915324 -38.78803012
OS 51.265455 -38.80189852
OS 51.2608322 -38.81576692
OS 51.2608322 -38.81669148
OS 51.25990764 -38.8185406
OS 51.25805852 -38.82223884
OS 51.2562094 -38.82686164
OS 51.25436028 -38.83333356
OS 51.25066204 -38.83980548
OS 51.24326556 -38.855523
OS 51.23401996 -38.87216508
OS 51.22200068 -38.89065628
OS 51.20813228 -38.90729836
OS 51.1914902 -38.92301588
OS 51.19056564 -38.92301588
OS 51.18964108 -38.924865
OS 51.1868674 -38.92671412
OS 51.18316916 -38.92856324
OS 51.17854636 -38.93133692
OS 51.17392356 -38.93503516
OS 51.16005516 -38.94150708
OS 51.14341308 -38.947979
OS 51.12399732 -38.95445092
OS 51.10088332 -38.95814916
OS 51.0759202 -38.95999828
OS 51.0666746 -38.95999828
OS 51.06020268 -38.95907372
OS 51.0528062 -38.95814916
OS 51.0435606 -38.95630004
OS 51.03339044 -38.95445092
OS 51.02229572 -38.95167724
OS 51.011201 -38.947979
OS 50.99918172 -38.94428076
OS 50.98716244 -38.9387334
OS 50.97514316 -38.93226148
OS 50.96312388 -38.924865
OS 50.9511046 -38.9156194
OS 50.94000988 -38.90544924
OS 50.92983972 -38.89435452
OS 50.92891516 -38.89342996
OS 50.92706604 -38.89065628
OS 50.92429236 -38.88603348
OS 50.91966956 -38.878637
OS 50.91504676 -38.87031596
OS 50.91042396 -38.85922124
OS 50.90395204 -38.8462774
OS 50.89840468 -38.83148444
OS 50.89285732 -38.81484236
OS 50.88730996 -38.7954266
OS 50.8817626 -38.77416172
OS 50.8771398 -38.75012316
OS 50.872517 -38.72423548
OS 50.86974332 -38.69649868
OS 50.8678942 -38.6659882
OS 50.86696964 -38.6336286
OS 50.86696964 -38.63270404
OS 50.86696964 -38.6290058
OS 50.86696964 -38.62253388
OS 50.86696964 -38.6151374
OS 50.8678942 -38.60496724
OS 50.8678942 -38.59387252
OS 50.86881876 -38.58185324
OS 50.86974332 -38.56798484
OS 50.872517 -38.53932348
OS 50.8771398 -38.508813
OS 50.88268716 -38.47830252
OS 50.8863854 -38.46443412
OS 50.89008364 -38.45056572
OS 50.89008364 -38.44964116
OS 50.8910082 -38.44779204
OS 50.89285732 -38.4440938
OS 50.89470644 -38.439471
OS 50.89655556 -38.43299908
OS 50.9002538 -38.42652716
OS 50.90765028 -38.41080964
OS 50.91689588 -38.39416756
OS 50.92891516 -38.37660092
OS 50.94278356 -38.35903428
OS 50.95942564 -38.34424132
OS 50.9603502 -38.34424132
OS 50.96127476 -38.3423922
OS 50.96404844 -38.34054308
OS 50.96774668 -38.33869396
OS 50.97236948 -38.33499572
OS 50.97791684 -38.33222204
OS 50.99178524 -38.32482556
OS 51.00842732 -38.31835364
OS 51.02784308 -38.31188172
OS 51.05095708 -38.30818348
OS 51.0759202 -38.30633436
OS 51.08424124 -38.30633436
OS 51.0944114 -38.30725892
OE
OB 51.59182468 -38.30725892 I
OS 51.59922116 -38.30818348
OS 51.60846676 -38.30910804
OS 51.61863692 -38.31095716
OS 51.62880708 -38.31280628
OS 51.65284564 -38.3192782
OS 51.6768842 -38.3285238
OS 51.68890348 -38.33407116
OS 51.70092276 -38.34054308
OS 51.71201748 -38.34886412
OS 51.72218764 -38.35810972
OS 51.7231122 -38.35903428
OS 51.72496132 -38.35995884
OS 51.72681044 -38.36365708
OS 51.73050868 -38.36735532
OS 51.73513148 -38.37197812
OS 51.73975428 -38.37845004
OS 51.74437708 -38.38492196
OS 51.74992444 -38.393243
OS 51.75917004 -38.41080964
OS 51.76841564 -38.43299908
OS 51.77211388 -38.4440938
OS 51.773963 -38.45703764
OS 51.77581212 -38.46998148
OS 51.77673668 -38.48384988
OS 51.77673668 -38.485699
OS 51.77673668 -38.4903218
OS 51.77581212 -38.49771828
OS 51.77488756 -38.50788844
OS 51.77303844 -38.51898316
OS 51.7693402 -38.531927
OS 51.76564196 -38.5457954
OS 51.7600946 -38.5596638
OS 51.75917004 -38.56151292
OS 51.75732092 -38.56613572
OS 51.75362268 -38.5735322
OS 51.74807532 -38.58370236
OS 51.74067884 -38.59479708
OS 51.73143324 -38.60866548
OS 51.72033852 -38.62253388
OS 51.70739468 -38.6382514
OS 51.70554556 -38.64010052
OS 51.70092276 -38.64564788
OS 51.69629996 -38.65027068
OS 51.69167716 -38.65489348
OS 51.6861298 -38.66044084
OS 51.67873332 -38.66783732
OS 51.67133684 -38.6752338
OS 51.66209124 -38.68355484
OS 51.65284564 -38.69280044
OS 51.64175092 -38.7029706
OS 51.62973164 -38.71314076
OS 51.6167878 -38.72516004
OS 51.60199484 -38.73717932
OS 51.58720188 -38.75012316
OS 51.58627732 -38.75104772
OS 51.5844282 -38.75289684
OS 51.58072996 -38.75567052
OS 51.57610716 -38.75936876
OS 51.5705598 -38.76491612
OS 51.56408788 -38.77046348
OS 51.54929492 -38.78248276
OS 51.5335774 -38.79635116
OS 51.51878444 -38.81021956
OS 51.5058406 -38.82223884
OS 51.50029324 -38.82686164
OS 51.49567044 -38.83148444
OS 51.49474588 -38.832409
OS 51.4919722 -38.83518268
OS 51.48827396 -38.83888092
OS 51.48365116 -38.84442828
OS 51.47902836 -38.8509002
OS 51.473481 -38.85737212
OS 51.46238628 -38.87308964
OS 51.77766124 -38.87308964
OS 51.77766124 -38.94890356
OS 51.3532882 -38.94890356
OS 51.3532882 -38.947979
OS 51.3532882 -38.94428076
OS 51.3532882 -38.9387334
OS 51.35421276 -38.93133692
OS 51.35513732 -38.92301588
OS 51.35698644 -38.91377028
OS 51.35883556 -38.90452468
OS 51.3625338 -38.89435452
OS 51.3625338 -38.89342996
OS 51.36345836 -38.8925054
OS 51.36530748 -38.88695804
OS 51.36900572 -38.878637
OS 51.37455308 -38.86754228
OS 51.38194956 -38.85459844
OS 51.39119516 -38.83980548
OS 51.40136532 -38.82501252
OS 51.41430916 -38.809295
OS 51.41430916 -38.80837044
OS 51.41615828 -38.80744588
OS 51.42078108 -38.80189852
OS 51.42910212 -38.79357748
OS 51.4411214 -38.7815582
OS 51.4549898 -38.7676898
OS 51.47255644 -38.75104772
OS 51.49382132 -38.73255652
OS 51.51693532 -38.71314076
OS 51.51785988 -38.7122162
OS 51.52155812 -38.70944252
OS 51.52710548 -38.70481972
OS 51.5335774 -38.69927236
OS 51.54189844 -38.69187588
OS 51.5520686 -38.68355484
OS 51.56223876 -38.67430924
OS 51.57425804 -38.66413908
OS 51.59737204 -38.64194964
OS 51.62048604 -38.6197602
OS 51.63158076 -38.60866548
OS 51.64175092 -38.59757076
OS 51.65099652 -38.5874006
OS 51.658393 -38.57723044
OS 51.658393 -38.57630588
OS 51.66024212 -38.57538132
OS 51.66209124 -38.57260764
OS 51.66394036 -38.5689094
OS 51.67041228 -38.55873924
OS 51.67780876 -38.54671996
OS 51.68428068 -38.531927
OS 51.6907526 -38.51620948
OS 51.69445084 -38.49864284
OS 51.69629996 -38.48200076
OS 51.69629996 -38.4810762
OS 51.69629996 -38.48015164
OS 51.6953754 -38.47460428
OS 51.69445084 -38.46535868
OS 51.69167716 -38.45518852
OS 51.68797892 -38.44224468
OS 51.681507 -38.42930084
OS 51.67318596 -38.416357
OS 51.66209124 -38.40341316
OS 51.66024212 -38.40156404
OS 51.65561932 -38.3978658
OS 51.6491474 -38.393243
OS 51.63897724 -38.38677108
OS 51.6260334 -38.38122372
OS 51.61124044 -38.37567636
OS 51.5936738 -38.37197812
OS 51.57425804 -38.37105356
OS 51.56871068 -38.37105356
OS 51.56501244 -38.37197812
OS 51.55391772 -38.37290268
OS 51.54097388 -38.37567636
OS 51.52710548 -38.3793746
OS 51.51138796 -38.38584652
OS 51.496595 -38.39416756
OS 51.4827266 -38.40526228
OS 51.48087748 -38.4071114
OS 51.47717924 -38.4117342
OS 51.47163188 -38.41913068
OS 51.46608452 -38.4302254
OS 51.4596126 -38.44316924
OS 51.45406524 -38.45981132
OS 51.450367 -38.47830252
OS 51.44851788 -38.4995674
OS 51.36808116 -38.49124636
OS 51.36808116 -38.4903218
OS 51.36900572 -38.48754812
OS 51.36900572 -38.48292532
OS 51.36993028 -38.4764534
OS 51.3717794 -38.46905692
OS 51.37362852 -38.46073588
OS 51.3764022 -38.45056572
OS 51.37917588 -38.44039556
OS 51.38657236 -38.41820612
OS 51.39766708 -38.39601668
OS 51.404139 -38.38492196
OS 51.41246004 -38.37382724
OS 51.42078108 -38.36365708
OS 51.43002668 -38.35441148
OS 51.43095124 -38.35348692
OS 51.43280036 -38.35256236
OS 51.43557404 -38.34978868
OS 51.44019684 -38.347015
OS 51.4457442 -38.34331676
OS 51.45221612 -38.33961852
OS 51.4596126 -38.33499572
OS 51.4688582 -38.33037292
OS 51.47902836 -38.32575012
OS 51.49012308 -38.32112732
OS 51.50214236 -38.31742908
OS 51.5150862 -38.31373084
OS 51.5289546 -38.31095716
OS 51.54374756 -38.30818348
OS 51.55946508 -38.30725892
OS 51.57610716 -38.30633436
OS 51.58535276 -38.30633436
OS 51.59182468 -38.30725892
OE
OB 52.08184148 -38.30725892 I
OS 52.09386076 -38.30910804
OS 52.10865372 -38.31188172
OS 52.1252958 -38.31650452
OS 52.14193788 -38.32205188
OS 52.15857996 -38.32944836
OS 52.15950452 -38.32944836
OS 52.16042908 -38.33037292
OS 52.16597644 -38.3331466
OS 52.17429748 -38.33869396
OS 52.18354308 -38.34516588
OS 52.1946378 -38.35441148
OS 52.20573252 -38.36458164
OS 52.21682724 -38.37660092
OS 52.22607284 -38.39046932
OS 52.2269974 -38.39231844
OS 52.22977108 -38.39694124
OS 52.23346932 -38.40526228
OS 52.23809212 -38.41543244
OS 52.24271492 -38.42745172
OS 52.24641316 -38.44132012
OS 52.24918684 -38.45703764
OS 52.2501114 -38.47275516
OS 52.2501114 -38.47460428
OS 52.2501114 -38.48015164
OS 52.24918684 -38.48754812
OS 52.24733772 -38.49771828
OS 52.24456404 -38.50973756
OS 52.23994124 -38.5226814
OS 52.23439388 -38.53562524
OS 52.2269974 -38.54856908
OS 52.22607284 -38.5504182
OS 52.22329916 -38.55411644
OS 52.2177518 -38.56058836
OS 52.21035532 -38.56798484
OS 52.20110972 -38.57630588
OS 52.190015 -38.58555148
OS 52.17707116 -38.59387252
OS 52.16135364 -38.60219356
OS 52.1622782 -38.60219356
OS 52.16412732 -38.60311812
OS 52.166901 -38.60404268
OS 52.17059924 -38.60496724
OS 52.1807694 -38.60866548
OS 52.19371324 -38.61421284
OS 52.2085062 -38.62160932
OS 52.22329916 -38.63085492
OS 52.23716756 -38.6428742
OS 52.2501114 -38.6567426
OS 52.25103596 -38.65859172
OS 52.2547342 -38.66413908
OS 52.26028156 -38.67338468
OS 52.26582892 -38.68540396
OS 52.27137628 -38.70019692
OS 52.27692364 -38.71776356
OS 52.28062188 -38.73810388
OS 52.28154644 -38.76029332
OS 52.28154644 -38.76121788
OS 52.28154644 -38.76399156
OS 52.28154644 -38.76861436
OS 52.28062188 -38.77416172
OS 52.27969732 -38.7815582
OS 52.2778482 -38.78987924
OS 52.27599908 -38.79912484
OS 52.27414996 -38.809295
OS 52.26675348 -38.83148444
OS 52.26120612 -38.84350372
OS 52.25565876 -38.85459844
OS 52.24826228 -38.86661772
OS 52.23994124 -38.878637
OS 52.23069564 -38.89065628
OS 52.21960092 -38.901751
OS 52.21867636 -38.90267556
OS 52.21682724 -38.90452468
OS 52.213129 -38.90729836
OS 52.2085062 -38.9109966
OS 52.20295884 -38.9156194
OS 52.19556236 -38.9202422
OS 52.18724132 -38.92578956
OS 52.17707116 -38.93041236
OS 52.166901 -38.93595972
OS 52.15488172 -38.94150708
OS 52.14286244 -38.94612988
OS 52.12899404 -38.95075268
OS 52.11420108 -38.95445092
OS 52.09848356 -38.9572246
OS 52.08276604 -38.95907372
OS 52.0651994 -38.95999828
OS 52.05687836 -38.95999828
OS 52.051331 -38.95907372
OS 52.04393452 -38.95814916
OS 52.03561348 -38.9572246
OS 52.02636788 -38.95537548
OS 52.01619772 -38.95352636
OS 51.99400828 -38.947979
OS 51.97089428 -38.9387334
OS 51.958875 -38.93318604
OS 51.94778028 -38.92671412
OS 51.93668556 -38.91839308
OS 51.92559084 -38.91007204
OS 51.92466628 -38.90914748
OS 51.92281716 -38.90729836
OS 51.92004348 -38.90452468
OS 51.9172698 -38.90082644
OS 51.912647 -38.89620364
OS 51.9080242 -38.88973172
OS 51.90247684 -38.8832598
OS 51.89692948 -38.87493876
OS 51.89138212 -38.86569316
OS 51.88583476 -38.85644756
OS 51.8756646 -38.83425812
OS 51.86734356 -38.80837044
OS 51.86456988 -38.79450204
OS 51.86272076 -38.77970908
OS 51.94130836 -38.76953892
OS 51.94130836 -38.77046348
OS 51.94223292 -38.7723126
OS 51.94315748 -38.77601084
OS 51.94408204 -38.78063364
OS 51.9450066 -38.786181
OS 51.94685572 -38.79265292
OS 51.95147852 -38.80652132
OS 51.95795044 -38.8231634
OS 51.96627148 -38.83888092
OS 51.97551708 -38.85367388
OS 51.9866118 -38.86661772
OS 51.98846092 -38.86754228
OS 51.99215916 -38.87124052
OS 51.99955564 -38.87586332
OS 52.00880124 -38.88048612
OS 52.01989596 -38.88603348
OS 52.03376436 -38.89065628
OS 52.04948188 -38.89435452
OS 52.06612396 -38.89527908
OS 52.07167132 -38.89527908
OS 52.07536956 -38.89435452
OS 52.08553972 -38.89342996
OS 52.09848356 -38.89065628
OS 52.11327652 -38.88603348
OS 52.12899404 -38.87956156
OS 52.14471156 -38.87031596
OS 52.15950452 -38.85737212
OS 52.16135364 -38.855523
OS 52.16597644 -38.84997564
OS 52.1715238 -38.8416546
OS 52.17892028 -38.83055988
OS 52.18631676 -38.81669148
OS 52.19186412 -38.80097396
OS 52.19648692 -38.78248276
OS 52.19833604 -38.76214244
OS 52.19833604 -38.76121788
OS 52.19833604 -38.75936876
OS 52.19833604 -38.75659508
OS 52.19741148 -38.75289684
OS 52.19648692 -38.74272668
OS 52.19371324 -38.7307074
OS 52.190015 -38.71591444
OS 52.18354308 -38.70112148
OS 52.17429748 -38.68632852
OS 52.1622782 -38.67246012
OS 52.16042908 -38.670611
OS 52.15580628 -38.66691276
OS 52.1484098 -38.6613654
OS 52.13823964 -38.65489348
OS 52.1252958 -38.64842156
OS 52.10957828 -38.6428742
OS 52.09201164 -38.63917596
OS 52.07259588 -38.63732684
OS 52.06427484 -38.63732684
OS 52.05780292 -38.6382514
OS 52.04948188 -38.63917596
OS 52.04023628 -38.64102508
OS 52.02914156 -38.6428742
OS 52.01712228 -38.64564788
OS 52.02636788 -38.57630588
OS 52.03099068 -38.57630588
OS 52.03468892 -38.57723044
OS 52.0467082 -38.57723044
OS 52.05687836 -38.57538132
OS 52.06889764 -38.5735322
OS 52.08276604 -38.57075852
OS 52.09848356 -38.56613572
OS 52.11327652 -38.5596638
OS 52.12899404 -38.55134276
OS 52.1299186 -38.55134276
OS 52.13084316 -38.5504182
OS 52.13546596 -38.54671996
OS 52.14193788 -38.54024804
OS 52.14933436 -38.531927
OS 52.15673084 -38.51990772
OS 52.16320276 -38.50603932
OS 52.16782556 -38.4903218
OS 52.16967468 -38.4810762
OS 52.16967468 -38.47090604
OS 52.16967468 -38.46998148
OS 52.16967468 -38.46905692
OS 52.16967468 -38.46350956
OS 52.16782556 -38.45611308
OS 52.16597644 -38.44594292
OS 52.1622782 -38.4348482
OS 52.1576554 -38.42282892
OS 52.15025892 -38.41080964
OS 52.14008876 -38.39971492
OS 52.1391642 -38.39879036
OS 52.1345414 -38.39509212
OS 52.12806948 -38.39046932
OS 52.11974844 -38.38492196
OS 52.10865372 -38.38029916
OS 52.09570988 -38.37567636
OS 52.08091692 -38.37197812
OS 52.06427484 -38.37105356
OS 52.05687836 -38.37105356
OS 52.04855732 -38.37290268
OS 52.0374626 -38.3747518
OS 52.02544332 -38.37845004
OS 52.01342404 -38.38307284
OS 52.0004802 -38.39046932
OS 51.98846092 -38.39971492
OS 51.98753636 -38.40063948
OS 51.98383812 -38.40526228
OS 51.97829076 -38.4117342
OS 51.97181884 -38.4209798
OS 51.96534692 -38.43299908
OS 51.958875 -38.44779204
OS 51.95332764 -38.46535868
OS 51.9496294 -38.485699
OS 51.8710418 -38.4718306
OS 51.8710418 -38.47090604
OS 51.87196636 -38.46813236
OS 51.87289092 -38.46443412
OS 51.87381548 -38.45888676
OS 51.8756646 -38.45241484
OS 51.87843828 -38.44501836
OS 51.88398564 -38.42745172
OS 51.89323124 -38.4071114
OS 51.90432596 -38.38677108
OS 51.91819436 -38.36735532
OS 51.935761 -38.34978868
OS 51.93668556 -38.34886412
OS 51.93853468 -38.34793956
OS 51.94130836 -38.34609044
OS 51.9450066 -38.34331676
OS 51.9496294 -38.33961852
OS 51.95610132 -38.33592028
OS 51.96257324 -38.33222204
OS 51.97089428 -38.32759924
OS 51.98938548 -38.32020276
OS 52.01065036 -38.31280628
OS 52.03561348 -38.30818348
OS 52.04855732 -38.30633436
OS 52.07167132 -38.30633436
OS 52.08184148 -38.30725892
OE
OB 51.07499564 -38.37105356 H
OS 51.06944828 -38.37105356
OS 51.06575004 -38.37197812
OS 51.05557988 -38.37382724
OS 51.0435606 -38.37660092
OS 51.0296922 -38.38214828
OS 51.01489924 -38.39046932
OS 51.00750276 -38.39601668
OS 51.00010628 -38.40156404
OS 50.99363436 -38.40896052
OS 50.98716244 -38.41728156
OS 50.98716244 -38.41820612
OS 50.98531332 -38.42005524
OS 50.9834642 -38.42375348
OS 50.98069052 -38.42837628
OS 50.97791684 -38.43577276
OS 50.9742186 -38.4440938
OS 50.97144492 -38.45426396
OS 50.96774668 -38.46628324
OS 50.96404844 -38.48015164
OS 50.9603502 -38.49586916
OS 50.95665196 -38.5134358
OS 50.95387828 -38.53285156
OS 50.9511046 -38.555041
OS 50.94925548 -38.57907956
OS 50.94833092 -38.60496724
OS 50.94740636 -38.6336286
OS 50.94740636 -38.63547772
OS 50.94740636 -38.64010052
OS 50.94740636 -38.64842156
OS 50.94833092 -38.65951628
OS 50.94833092 -38.67153556
OS 50.94925548 -38.68632852
OS 50.95018004 -38.70204604
OS 50.95202916 -38.71868812
OS 50.95665196 -38.75474596
OS 50.95942564 -38.7723126
OS 50.96312388 -38.78895468
OS 50.96682212 -38.8046722
OS 50.97236948 -38.81946516
OS 50.97791684 -38.832409
OS 50.98438876 -38.84350372
OS 50.98438876 -38.84442828
OS 50.98623788 -38.84535284
OS 50.99086068 -38.85182476
OS 50.99918172 -38.8601458
OS 51.00935188 -38.8693914
OS 51.02322028 -38.878637
OS 51.0389378 -38.88695804
OS 51.05650444 -38.89342996
OS 51.06575004 -38.89435452
OS 51.0759202 -38.89527908
OS 51.08146756 -38.89527908
OS 51.0851658 -38.89435452
OS 51.0944114 -38.8925054
OS 51.10735524 -38.88880716
OS 51.12122364 -38.88233524
OS 51.13694116 -38.87308964
OS 51.14433764 -38.86754228
OS 51.15173412 -38.8601458
OS 51.1591306 -38.85274932
OS 51.16652708 -38.84350372
OS 51.16652708 -38.84257916
OS 51.1683762 -38.84073004
OS 51.17022532 -38.83795636
OS 51.17207444 -38.83333356
OS 51.17577268 -38.82686164
OS 51.17854636 -38.8185406
OS 51.1822446 -38.809295
OS 51.18594284 -38.79820028
OS 51.18871652 -38.78433188
OS 51.19241476 -38.76953892
OS 51.196113 -38.75197228
OS 51.19888668 -38.73348108
OS 51.2007358 -38.71129164
OS 51.20258492 -38.68817764
OS 51.20443404 -38.66228996
OS 51.20443404 -38.6336286
OS 51.20443404 -38.63270404
OS 51.20443404 -38.63177948
OS 51.20443404 -38.62715668
OS 51.20443404 -38.61883564
OS 51.20350948 -38.60774092
OS 51.20350948 -38.59572164
OS 51.20258492 -38.58092868
OS 51.20166036 -38.56521116
OS 51.19981124 -38.54764452
OS 51.19518844 -38.51251124
OS 51.19241476 -38.4949446
OS 51.18871652 -38.47830252
OS 51.18501828 -38.462585
OS 51.17947092 -38.44779204
OS 51.17392356 -38.4348482
OS 51.16745164 -38.42375348
OS 51.16745164 -38.42282892
OS 51.16560252 -38.42190436
OS 51.1637534 -38.41913068
OS 51.16097972 -38.41543244
OS 51.15265868 -38.4071114
OS 51.14248852 -38.39694124
OS 51.12862012 -38.38769564
OS 51.1129026 -38.3793746
OS 51.10458156 -38.37567636
OS 51.09533596 -38.37290268
OS 51.0851658 -38.37197812
OS 51.07499564 -38.37105356
OE
OB 54.05947532 -38.37105356 H
OS 54.05392796 -38.37105356
OS 54.05022972 -38.37197812
OS 54.04005956 -38.37382724
OS 54.02804028 -38.37660092
OS 54.01417188 -38.38214828
OS 53.99937892 -38.39046932
OS 53.99198244 -38.39601668
OS 53.98458596 -38.40156404
OS 53.97811404 -38.40896052
OS 53.97164212 -38.41728156
OS 53.97164212 -38.41820612
OS 53.969793 -38.42005524
OS 53.96794388 -38.42375348
OS 53.9651702 -38.42837628
OS 53.96239652 -38.43577276
OS 53.95869828 -38.4440938
OS 53.9559246 -38.45426396
OS 53.95222636 -38.46628324
OS 53.94852812 -38.48015164
OS 53.94482988 -38.49586916
OS 53.94113164 -38.5134358
OS 53.93835796 -38.53285156
OS 53.93558428 -38.555041
OS 53.93373516 -38.57907956
OS 53.9328106 -38.60496724
OS 53.93188604 -38.6336286
OS 53.93188604 -38.63547772
OS 53.93188604 -38.64010052
OS 53.93188604 -38.64842156
OS 53.9328106 -38.65951628
OS 53.9328106 -38.67153556
OS 53.93373516 -38.68632852
OS 53.93465972 -38.70204604
OS 53.93650884 -38.71868812
OS 53.94113164 -38.75474596
OS 53.94390532 -38.7723126
OS 53.94760356 -38.78895468
OS 53.9513018 -38.8046722
OS 53.95684916 -38.81946516
OS 53.96239652 -38.832409
OS 53.96886844 -38.84350372
OS 53.96886844 -38.84442828
OS 53.97071756 -38.84535284
OS 53.97534036 -38.85182476
OS 53.9836614 -38.8601458
OS 53.99383156 -38.8693914
OS 54.00769996 -38.878637
OS 54.02341748 -38.88695804
OS 54.04098412 -38.89342996
OS 54.05022972 -38.89435452
OS 54.06039988 -38.89527908
OS 54.06594724 -38.89527908
OS 54.06964548 -38.89435452
OS 54.07889108 -38.8925054
OS 54.09183492 -38.88880716
OS 54.10570332 -38.88233524
OS 54.12142084 -38.87308964
OS 54.12881732 -38.86754228
OS 54.1362138 -38.8601458
OS 54.14361028 -38.85274932
OS 54.15100676 -38.84350372
OS 54.15100676 -38.84257916
OS 54.15285588 -38.84073004
OS 54.154705 -38.83795636
OS 54.15655412 -38.83333356
OS 54.16025236 -38.82686164
OS 54.16302604 -38.8185406
OS 54.16672428 -38.809295
OS 54.17042252 -38.79820028
OS 54.1731962 -38.78433188
OS 54.17689444 -38.76953892
OS 54.18059268 -38.75197228
OS 54.18336636 -38.73348108
OS 54.18521548 -38.71129164
OS 54.1870646 -38.68817764
OS 54.18891372 -38.66228996
OS 54.18891372 -38.6336286
OS 54.18891372 -38.63270404
OS 54.18891372 -38.63177948
OS 54.18891372 -38.62715668
OS 54.18891372 -38.61883564
OS 54.18798916 -38.60774092
OS 54.18798916 -38.59572164
OS 54.1870646 -38.58092868
OS 54.18614004 -38.56521116
OS 54.18429092 -38.54764452
OS 54.17966812 -38.51251124
OS 54.17689444 -38.4949446
OS 54.1731962 -38.47830252
OS 54.16949796 -38.462585
OS 54.1639506 -38.44779204
OS 54.15840324 -38.4348482
OS 54.15193132 -38.42375348
OS 54.15193132 -38.42282892
OS 54.1500822 -38.42190436
OS 54.14823308 -38.41913068
OS 54.1454594 -38.41543244
OS 54.13713836 -38.4071114
OS 54.1269682 -38.39694124
OS 54.1130998 -38.38769564
OS 54.09738228 -38.3793746
OS 54.08906124 -38.37567636
OS 54.07981564 -38.37290268
OS 54.06964548 -38.37197812
OS 54.05947532 -38.37105356
OE
OB 49.87491676 -38.43669732 H
OS 49.67336268 -38.72331092
OS 49.87491676 -38.72331092
OS 49.87491676 -38.43669732
OE
OB 56.14158444 -38.38492196 H
OS 55.95852156 -38.38492196
OS 55.95852156 -38.61328828
OS 56.13048972 -38.61328828
OS 56.13696164 -38.61236372
OS 56.14343356 -38.61236372
OS 56.15083004 -38.61143916
OS 56.16839668 -38.60959004
OS 56.18781244 -38.6058918
OS 56.2072282 -38.60034444
OS 56.22479484 -38.59294796
OS 56.23311588 -38.58832516
OS 56.2395878 -38.5827778
OS 56.24143692 -38.58092868
OS 56.24513516 -38.57723044
OS 56.25068252 -38.56983396
OS 56.25715444 -38.56058836
OS 56.26362636 -38.54856908
OS 56.26917372 -38.53377612
OS 56.27287196 -38.51713404
OS 56.27472108 -38.49771828
OS 56.27472108 -38.49679372
OS 56.27472108 -38.49586916
OS 56.27472108 -38.49124636
OS 56.27379652 -38.48292532
OS 56.2719474 -38.47367972
OS 56.27009828 -38.46350956
OS 56.26640004 -38.45149028
OS 56.26085268 -38.44039556
OS 56.25438076 -38.42930084
OS 56.2534562 -38.42837628
OS 56.25068252 -38.42467804
OS 56.24605972 -38.42005524
OS 56.24051236 -38.41358332
OS 56.23219132 -38.4071114
OS 56.22294572 -38.40156404
OS 56.21277556 -38.39601668
OS 56.20075628 -38.39139388
OS 56.19983172 -38.39139388
OS 56.19613348 -38.39046932
OS 56.19058612 -38.38954476
OS 56.18318964 -38.38769564
OS 56.17209492 -38.38677108
OS 56.15822652 -38.38584652
OS 56.14158444 -38.38492196
OE
SE
P -2.99999908 16.00000102 6 P 0 0 ;0=4,1=1
P -2.99999908 17.99999956 6 P 0 0 ;0=4,1=1
P -2.99999908 20.00000064 6 P 0 0 ;0=4,1=1
P -2.99999908 21.99999918 6 P 0 0 ;0=4,1=1
P -2.99999908 24.00000026 6 P 0 0 ;0=4,1=1
P -2.99999908 25.9999988 6 P 0 0 ;0=4,1=1
P -2.99999908 27.99999988 6 P 0 0 ;0=4,1=1
P -2.99999908 30.00000096 6 P 0 0 ;0=4,1=1
P -2.99999908 31.9999995 6 P 0 0 ;0=4,1=1
P -2.99999908 34.00000058 6 P 0 0 ;0=4,1=1
P -2.99999908 35.99999912 6 P 0 0 ;0=4,1=1
P -2.99999908 38.0000002 6 P 0 0 ;0=4,1=1
P -2.99999908 39.99999874 6 P 0 0 ;0=4,1=1
P 0.50000154 -3.99999962 6 P 0 0 ;0=4,1=1
P 2.50000008 -3.99999962 6 P 0 0 ;0=4,1=1
P 4.50000116 -3.99999962 6 P 0 0 ;0=4,1=1
P 6.4999997 -3.99999962 6 P 0 0 ;0=4,1=1
P 8.50000078 -3.99999962 6 P 0 0 ;0=4,1=1
P 10.49999932 -3.99999962 6 P 0 0 ;0=4,1=1
P 12.5000004 -3.99999962 6 P 0 0 ;0=4,1=1
P 12.74500118 40.26499948 6 P 0 0 ;0=4,1=1
P 12.74500118 41.21500012 6 P 0 0 ;0=4,1=1
P 12.74500118 44.63999962 6 P 0 0 ;0=4,1=1
P 12.75500116 42.16500076 6 P 0 0 ;0=4,1=1
P 12.98999942 18.0150008 6 P 0 0 ;0=4,1=1
P 14.50000148 -3.99999962 6 P 0 0 ;0=4,1=1
P 15.88470534 21.56499878 6 P 0 0 ;0=4,1=1
P 16.30970576 23.03999964 6 P 0 0 ;0=4,1=1
P 16.50000002 -3.99999962 6 P 0 0 ;0=4,1=1
P 17.57500168 13.89000016 6 P 0 0 ;0=4,1=1
P 17.915001 15.69625258 6 P 0 0 ;0=4,1=1
P 18.8149992 15.10000028 6 P 0 0 ;0=4,1=1
P 18.8149992 15.98270108 6 P 0 0 ;0=4,1=1
P 18.8149992 16.85250122 6 P 0 0 ;0=4,1=1
P 19.01500134 7.39000046 6 P 0 0 ;0=4,1=1
P 19.01500134 8.5900006 6 P 0 0 ;0=4,1=1
P 19.01500134 9.7899982 6 P 0 0 ;0=4,1=1
P 19.01500134 11.09000068 6 P 0 0 ;0=4,1=1
P 19.01500134 12.39000062 6 P 0 0 ;0=4,1=1
P 21.11499968 6.76500044 6 P 0 0 ;0=4,1=1
P 21.11499968 7.78999966 6 P 0 0 ;0=4,1=1
P 21.11499968 8.9899998 6 P 0 0 ;0=4,1=1
P 21.11499968 10.28999974 6 P 0 0 ;0=4,1=1
P 21.11499968 11.38590052 6 P 0 0 ;0=4,1=1
P 22.05919388 12.29000082 6 P 0 0 ;0=4,1=1
P 22.45970616 20.01499934 6 P 0 0 ;0=4,1=1
P 23.29999912 38.90000094 6 P 0 0 ;0=4,1=1
P 23.33999904 44.0138312 6 P 0 0 ;0=4,1=1
P 23.4097068 20.04000056 6 P 0 0 ;0=4,1=1
P 24.35970744 20.04000056 6 P 0 0 ;0=4,1=1
P 24.49999926 -3.50000062 6 P 0 0 ;0=4,1=1
P 25.7999992 38.90000094 6 P 0 0 ;0=4,1=1
P 26.50000034 -3.50000062 6 P 0 0 ;0=4,1=1
P 28.50000142 -3.50000062 6 P 0 0 ;0=4,1=1
P 30.49999996 -3.50000062 6 P 0 0 ;0=4,1=1
P 32.50000104 -3.50000062 6 P 0 0 ;0=4,1=1
P 32.80000044 38.90000094 6 P 0 0 ;0=4,1=1
P 35.30000052 44.0000009 6 P 0 0 ;0=4,1=1
P 38.4999992 -3.50000062 6 P 0 0 ;0=4,1=1
P 39.60000208 38.91499964 6 P 0 0 ;0=4,1=1
P 40.50000028 -3.50000062 6 P 0 0 ;0=4,1=1
P 40.67999992 42.76499956 6 P 0 0 ;0=4,1=1
P 42.2249981 38.91499964 6 P 0 0 ;0=4,1=1
P 44.4999999 0.499999 6 P 0 0 ;0=4,1=1
P 44.4999999 2.50000008 6 P 0 0 ;0=4,1=1
P 44.4999999 4.49999862 6 P 0 0 ;0=4,1=1
P 44.4999999 6.4999997 6 P 0 0 ;0=4,1=1
P 44.4999999 8.49999824 6 P 0 0 ;0=4,1=1
P 44.4999999 10.49999932 6 P 0 0 ;0=4,1=1
P 44.4999999 12.49999786 6 P 0 0 ;0=4,1=1
P 44.4999999 14.49999894 6 P 0 0 ;0=4,1=1
P 44.4999999 16.50000002 6 P 0 0 ;0=4,1=1
P 44.4999999 18.49999856 6 P 0 0 ;0=4,1=1
P 44.4999999 20.49999964 6 P 0 0 ;0=4,1=1
P 44.4999999 22.49999818 6 P 0 0 ;0=4,1=1
P 44.4999999 24.49999926 6 P 0 0 ;0=4,1=1
P 44.4999999 26.4999978 6 P 0 0 ;0=4,1=1
P 44.4999999 28.49999888 6 P 0 0 ;0=4,1=1
P 44.4999999 30.49999996 6 P 0 0 ;0=4,1=1
P 44.4999999 32.4999985 6 P 0 0 ;0=4,1=1
P 44.4999999 34.49999958 6 P 0 0 ;0=4,1=1
P 44.4999999 36.49999812 6 P 0 0 ;0=4,1=1
P 44.4999999 38.4999992 6 P 0 0 ;0=4,1=1
P 44.4999999 40.49999774 6 P 0 0 ;0=4,1=1

### steps/pcb/layers/l03-inner_layer/features
UNITS=MM
#Layer_Physical_Order=3
#Layer_Color=65280
#
#Feature symbol names
#
$0 r99.9998
$1 r2090.0009
$2 r1562.00094
$3 r1799.99894
$4 r599.9988

#
#Feature attribute names
#
@0 .geometry
@1 .pad_usage
@2 .nomenclature
@3 .string
@4 .string_angle

#
#Feature attribute text strings
#
&0 Pad_Simple_X2090.0009Y2090.0009H1090.0004C2106.0004
&1 Pad_Simple_X1562.0009Y1562.0009H961.9996C1977.9996
&2 Pad_Simple_X1799.9989Y1799.9989H1200.0001C2216.0001
&3 VIA_RoundD599.9988H299.9994C1315.9994

#
#Layer features
#
L -9.5600012 -24.45999934 40.4400004 -24.45999934 0 P 0
L -9.5600012 -35.9599992 -9.5600012 -24.45999934 0 P 0
L -9.5600012 -35.9599992 28.439999 -35.9599992 0 P 0
L -9.5600012 -39.45999982 -9.5600012 -35.9599992 0 P 0
L -9.5600012 -39.45999982 28.439999 -39.45999982 0 P 0
L -9.5600012 -42.96000044 -9.5600012 -39.45999982 0 P 0
L -9.5600012 -42.96000044 28.439999 -42.96000044 0 P 0
L -10.0600002 -23.96000034 62.93999858 -23.96000034 0 P 0
L -10.0600002 -43.45999944 -10.0600002 -23.96000034 0 P 0
L -10.0600002 -43.45999944 62.93999858 -43.45999944 0 P 0
L 28.439999 -35.96000174 45.44000056 -35.9599992 0 P 0
L 28.439999 -39.45999982 28.439999 -35.9599992 0 P 0
L 28.439999 -39.46000236 45.44000056 -39.45999982 0 P 0
L 28.439999 -42.96000044 28.439999 -39.45999982 0 P 0
L 28.439999 -42.96000298 45.44000056 -42.96000044 0 P 0
L 40.4400004 -24.45999934 62.43999958 -24.45999934 0 P 0
L 40.4400004 -35.9599992 40.4400004 -24.45999934 0 P 0
L 45.44000056 -35.9599992 62.43999958 -35.9599992 0 P 0
L 45.44000056 -39.45999982 62.43999958 -39.45999982 0 P 0
L 45.44000056 -42.96000044 45.44000056 -35.9599992 0 P 0
L 45.44000056 -42.96000044 62.43999958 -42.96000044 0 P 0
L 62.43999958 -35.9599992 62.43999958 -24.45999934 0 P 0
L 62.43999958 -42.96000044 62.43999958 -35.9599992 0 P 0
L 62.93999858 -43.45999944 62.93999858 -23.96000034 0 P 0
P 0 40.64 1 P 0 0 ;0=0,1=0
P 37.8500005 12.71999996 3 P 0 0 ;0=2,1=0
P 37.8500005 12.71999996 2 P 0 0 ;0=1,1=0
P 40.67999992 20.33999996 1 P 0 0 ;0=0,1=0
S P 0
OB 43.2467766 45.28782662 I
OS 43.5750081 45.19987658
OS 43.8889648 45.06983112
OS 44.18321872 44.89994068
OS 44.45280162 44.69308308
OS 44.693078 44.45280924
OS 44.89994068 44.18322126
OS 45.06983112 43.8889648
OS 45.19986896 43.57502842
OS 45.28782408 43.24677914
OS 45.33217502 42.90990402
OS 45.33217756 42.7399958
OS 45.33217502 -2.06000096
OS 45.33217502 -2.22990918
OS 45.28782662 -2.56677922
OS 45.19987658 -2.89501072
OS 45.06983112 -3.20896742
OS 44.89994068 -3.50322134
OS 44.69308308 -3.77280424
OS 44.45280924 -4.01308062
OS 44.18322126 -4.2199433
OS 43.8889648 -4.38983374
OS 43.57502842 -4.51987158
OS 43.24677914 -4.6078267
OS 42.90989132 -4.6521751
OS 42.7399958 -4.65217764
OS -2.06000096 -4.65218272
OS -2.22990918 -4.65218272
OS -2.56678938 -4.60783178
OS -2.89502088 -4.51988428
OS -3.20895472 -4.38984644
OS -3.50322388 -4.21994838
OS -3.77279916 -4.0130984
OS -4.0130984 -3.77279916
OS -4.21994584 -3.50322642
OS -4.38984136 -3.2089598
OS -4.51988174 -2.89502088
OS -4.60782924 -2.56679192
OS -4.65218018 -2.22991172
OS -4.65217764 -2.06000604
OS -4.65218526 42.73999834
OS -4.65218526 42.90990656
OS -4.60783432 43.24678422
OS -4.51988682 43.57501318
OS -4.38984644 43.88895464
OS -4.21995092 44.18321872
OS -4.01310094 44.452794
OS -3.77280932 44.69308562
OS -3.50323404 44.89993814
OS -3.20894964 45.06984128
OS -2.89502342 45.19987658
OS -2.56679192 45.28782408
OS -2.22992188 45.33217248
OS -2.07798416 45.33216486
OS -2.07795622 45.33216994
OS 42.74000088 45.33217502
OS 42.90990656 45.33217502
OS 43.2467766 45.28782662
OE
OB 14.42216826 44.87499788 H
OS 14.11783054 44.87499788
OS 13.8193399 44.81562538
OS 13.53816952 44.69915876
OS 13.28511948 44.53007858
OS 13.06992052 44.31487962
OS 12.90084034 44.06182958
OS 12.8147318 43.85394836
OS 12.677267 43.85394836
OS 12.59115846 44.06182958
OS 12.42207828 44.31487962
OS 12.20687932 44.53007858
OS 11.95382928 44.69915876
OS 11.6726589 44.81562538
OS 11.37416826 44.87499788
OS 11.06983054 44.87499788
OS 10.7713399 44.81562538
OS 10.49016952 44.69915876
OS 10.23711948 44.53007858
OS 10.02192052 44.31487962
OS 9.85284034 44.06182958
OS 9.73637372 43.7806592
OS 9.67700122 43.48216856
OS 9.67700122 43.17783084
OS 9.73637372 42.8793402
OS 9.85284034 42.59816982
OS 10.02192052 42.34511978
OS 10.23711948 42.12992082
OS 10.49016952 41.96084064
OS 10.7713399 41.84437402
OS 11.06983054 41.78500152
OS 11.37416826 41.78500152
OS 11.6726589 41.84437402
OS 11.95382928 41.96084064
OS 12.20687932 42.12992082
OS 12.42207828 42.34511978
OS 12.59115846 42.59816982
OS 12.677267 42.80605104
OS 12.8147318 42.80605104
OS 12.90084034 42.59816982
OS 13.06992052 42.34511978
OS 13.28511948 42.12992082
OS 13.53816952 41.96084064
OS 13.8193399 41.84437402
OS 14.11783054 41.78500152
OS 14.42216826 41.78500152
OS 14.7206589 41.84437402
OS 15.00182928 41.96084064
OS 15.25487932 42.12992082
OS 15.47007828 42.34511978
OS 15.63915846 42.59816982
OS 15.75562508 42.8793402
OS 15.81499758 43.17783084
OS 15.81499758 43.48216856
OS 15.75562508 43.7806592
OS 15.63915846 44.06182958
OS 15.47007828 44.31487962
OS 15.25487932 44.53007858
OS 15.00182928 44.69915876
OS 14.7206589 44.81562538
OS 14.42216826 44.87499788
OE
OB 8.3379056 44.57499848 H
OS 8.0100932 44.57499848
OS 7.69344664 44.49015486
OS 7.40955084 44.32624866
OS 7.17775044 44.09444826
OS 7.01384424 43.81055246
OS 6.92900062 43.4939059
OS 6.92900062 43.1660935
OS 7.01384424 42.84944694
OS 7.17775044 42.56555114
OS 7.40955084 42.33375074
OS 7.69344664 42.16984454
OS 8.0100932 42.08500092
OS 8.3379056 42.08500092
OS 8.65455216 42.16984454
OS 8.93844796 42.33375074
OS 9.17024836 42.56555114
OS 9.33415456 42.84944694
OS 9.41899818 43.1660935
OS 9.41899818 43.4939059
OS 9.33415456 43.81055246
OS 9.17024836 44.09444826
OS 8.93844796 44.32624866
OS 8.65455216 44.49015486
OS 8.3379056 44.57499848
OE
OB 5.2899056 44.57499848 H
OS 4.9620932 44.57499848
OS 4.64544664 44.49015486
OS 4.36155084 44.32624866
OS 4.12975044 44.09444826
OS 3.96584424 43.81055246
OS 3.88100062 43.4939059
OS 3.88100062 43.1660935
OS 3.96584424 42.84944694
OS 4.12975044 42.56555114
OS 4.36155084 42.33375074
OS 4.64544664 42.16984454
OS 4.9620932 42.08500092
OS 5.2899056 42.08500092
OS 5.60655216 42.16984454
OS 5.89044796 42.33375074
OS 6.12224836 42.56555114
OS 6.28615456 42.84944694
OS 6.37099818 43.1660935
OS 6.37099818 43.4939059
OS 6.28615456 43.81055246
OS 6.12224836 44.09444826
OS 5.89044796 44.32624866
OS 5.60655216 44.49015486
OS 5.2899056 44.57499848
OE
OB 2.2419056 44.57499848 H
OS 1.9140932 44.57499848
OS 1.59744664 44.49015486
OS 1.31355084 44.32624866
OS 1.08175044 44.09444826
OS 0.91784424 43.81055246
OS 0.83300062 43.4939059
OS 0.83300062 43.1660935
OS 0.91784424 42.84944694
OS 1.08175044 42.56555114
OS 1.31355084 42.33375074
OS 1.59744664 42.16984454
OS 1.9140932 42.08500092
OS 2.2419056 42.08500092
OS 2.55855216 42.16984454
OS 2.84244796 42.33375074
OS 3.07424836 42.56555114
OS 3.23815456 42.84944694
OS 3.32299818 43.1660935
OS 3.32299818 43.4939059
OS 3.23815456 43.81055246
OS 3.07424836 44.09444826
OS 2.84244796 44.32624866
OS 2.55855216 44.49015486
OS 2.2419056 44.57499848
OE
OB 0.17101566 41.93899918 H
OS 0.12699492 41.93899918
OS 0.12699492 40.76701016
OS 1.29899918 40.76701016
OS 1.29899918 40.81101566
OS 1.2104751 41.141396
OS 1.0394569 41.43760318
OS 0.79760318 41.6794569
OS 0.501396 41.8504751
OS 0.17101566 41.93899918
OE
OB -0.12700508 41.93899918 H
OS -0.17101566 41.93899918
OS -0.501396 41.8504751
OS -0.79760318 41.6794569
OS -1.0394569 41.43760318
OS -1.2104751 41.141396
OS -1.29899918 40.81101566
OS -1.29899918 40.76701016
OS -0.12700508 40.76701016
OS -0.12700508 41.93899918
OE
OB 1.29899918 40.51301016 H
OS 0.12699492 40.51301016
OS 0.12699492 39.34100082
OS 0.17101566 39.34100082
OS 0.501396 39.4295249
OS 0.79760318 39.6005431
OS 1.0394569 39.84239682
OS 1.2104751 40.138604
OS 1.29899918 40.46898434
OS 1.29899918 40.51301016
OE
OB -0.12700508 40.51301016 H
OS -1.29899918 40.51301016
OS -1.29899918 40.46898434
OS -1.2104751 40.138604
OS -1.0394569 39.84239682
OS -0.79760318 39.6005431
OS -0.501396 39.4295249
OS -0.17101566 39.34100082
OS -0.12700508 39.34100082
OS -0.12700508 40.51301016
OE
OB 20.46429994 44.98999892 H
OS 20.01570038 44.98999892
OS 19.57262278 44.9198238
OS 19.14597898 44.78119822
OS 18.74627442 44.57753848
OS 18.38334906 44.31385854
OS 18.06614116 43.99665064
OS 17.80246122 43.63372528
OS 17.59880148 43.23402072
OS 17.4601759 42.80737692
OS 17.39000078 42.36429932
OS 17.39000078 41.91569976
OS 17.4601759 41.47262216
OS 17.59880148 41.04597836
OS 17.80246122 40.6462738
OS 18.06614116 40.28334844
OS 18.38334906 39.96614054
OS 18.74627442 39.7024606
OS 19.14597898 39.49880086
OS 19.57262278 39.36017528
OS 20.01570038 39.29000016
OS 20.46429994 39.29000016
OS 20.90737754 39.36017528
OS 21.33402134 39.49880086
OS 21.7337259 39.7024606
OS 22.09665126 39.96614054
OS 22.41385916 40.28334844
OS 22.6775391 40.6462738
OS 22.88119884 41.04597836
OS 23.01982442 41.47262216
OS 23.08999954 41.91569976
OS 23.08999954 42.36429932
OS 23.01982442 42.80737692
OS 22.88119884 43.23402072
OS 22.6775391 43.63372528
OS 22.41385916 43.99665064
OS 22.09665126 44.31385854
OS 21.7337259 44.57753848
OS 21.33402134 44.78119822
OS 20.90737754 44.9198238
OS 20.46429994 44.98999892
OE
OB 40.79216886 42.18499818 H
OS 40.48783114 42.18499818
OS 40.1893405 42.12562568
OS 39.90817012 42.00915906
OS 39.65512008 41.84007888
OS 39.43992112 41.62487992
OS 39.27084094 41.37182988
OS 39.15437432 41.0906595
OS 39.09500182 40.79216886
OS 39.09500182 40.48783114
OS 39.15437432 40.1893405
OS 39.27084094 39.90817012
OS 39.43992112 39.65512008
OS 39.65512008 39.43992112
OS 39.90817012 39.27084094
OS 40.1893405 39.15437432
OS 40.48783114 39.09500182
OS 40.79216886 39.09500182
OS 41.0906595 39.15437432
OS 41.37182988 39.27084094
OS 41.62487992 39.43992112
OS 41.84007888 39.65512008
OS 42.00915906 39.90817012
OS 42.12562568 40.1893405
OS 42.18499818 40.48783114
OS 42.18499818 40.79216886
OS 42.12562568 41.0906595
OS 42.00915906 41.37182988
OS 41.84007888 41.62487992
OS 41.62487992 41.84007888
OS 41.37182988 42.00915906
OS 41.0906595 42.12562568
OS 40.79216886 42.18499818
OE
OB 36.4019084 42.14999952 H
OS 35.99809412 42.14999952
OS 35.60203954 42.07121888
OS 35.2289618 41.91668528
OS 34.89320428 41.69233978
OS 34.60766256 41.40679806
OS 34.38331706 41.07104054
OS 34.22878346 40.6979628
OS 34.15000282 40.30190822
OS 34.15000282 39.89809394
OS 34.22878346 39.50203936
OS 34.38331706 39.12896162
OS 34.60766256 38.7932041
OS 34.89320428 38.50766238
OS 35.2289618 38.28331688
OS 35.60203954 38.12878328
OS 35.99809412 38.05000264
OS 36.4019084 38.05000264
OS 36.79796298 38.12878328
OS 37.17104072 38.28331688
OS 37.50679824 38.50766238
OS 37.79233996 38.7932041
OS 38.01668546 39.12896162
OS 38.17121906 39.50203936
OS 38.2499997 39.89809394
OS 38.2499997 40.30190822
OS 38.17121906 40.6979628
OS 38.01668546 41.07104054
OS 37.79233996 41.40679806
OS 37.50679824 41.69233978
OS 37.17104072 41.91668528
OS 36.79796298 42.07121888
OS 36.4019084 42.14999952
OE
OB 4.60190596 40.64999744 H
OS 4.19809168 40.64999744
OS 3.8020371 40.5712168
OS 3.42895936 40.4166832
OS 3.09320184 40.1923377
OS 2.80766012 39.90679598
OS 2.58331462 39.57103846
OS 2.42878102 39.19796072
OS 2.35000038 38.80190614
OS 2.35000038 38.39809186
OS 2.42878102 38.00203728
OS 2.58331462 37.62895954
OS 2.80766012 37.29320202
OS 3.09320184 37.0076603
OS 3.42895936 36.7833148
OS 3.8020371 36.6287812
OS 4.19809168 36.55000056
OS 4.60190596 36.55000056
OS 4.99796054 36.6287812
OS 5.37103828 36.7833148
OS 5.7067958 37.0076603
OS 5.99233752 37.29320202
OS 6.21668302 37.62895954
OS 6.37121662 38.00203728
OS 6.44999726 38.39809186
OS 6.44999726 38.80190614
OS 6.37121662 39.19796072
OS 6.21668302 39.57103846
OS 5.99233752 39.90679598
OS 5.7067958 40.1923377
OS 5.37103828 40.4166832
OS 4.99796054 40.5712168
OS 4.60190596 40.64999744
OE
OB 4.9748186 34.13999776 H
OS 4.6851824 34.13999776
OS 4.40541664 34.06503474
OS 4.15458656 33.92021664
OS 3.94978382 33.7154139
OS 3.80496572 33.46458382
OS 3.7300027 33.18481806
OS 3.7300027 32.89518186
OS 3.80496572 32.6154161
OS 3.94978382 32.36458602
OS 4.15458656 32.15978328
OS 4.40541664 32.01496518
OS 4.6851824 31.94000216
OS 4.9748186 31.94000216
OS 5.25458436 32.01496518
OS 5.50541444 32.15978328
OS 5.71021718 32.36458602
OS 5.85503528 32.6154161
OS 5.9299983 32.89518186
OS 5.9299983 33.18481806
OS 5.85503528 33.46458382
OS 5.71021718 33.7154139
OS 5.50541444 33.92021664
OS 5.25458436 34.06503474
OS 4.9748186 34.13999776
OE
OB 38.03431306 34.43999716 H
OS 37.66568794 34.43999716
OS 37.30962312 34.34458968
OS 36.99038322 34.16027712
OS 36.72972334 33.89961724
OS 36.54541078 33.58037734
OS 36.4500033 33.22431252
OS 36.4500033 32.8556874
OS 36.54541078 32.49962258
OS 36.72972334 32.18038268
OS 36.99038322 31.9197228
OS 37.30962312 31.73541024
OS 37.66568794 31.64000276
OS 38.03431306 31.64000276
OS 38.39037788 31.73541024
OS 38.70961778 31.9197228
OS 38.97027766 32.18038268
OS 39.15459022 32.49962258
OS 39.2499977 32.8556874
OS 39.2499977 33.22431252
OS 39.15459022 33.58037734
OS 38.97027766 33.89961724
OS 38.70961778 34.16027712
OS 38.39037788 34.34458968
OS 38.03431306 34.43999716
OE
OB 38.03431306 24.27999716 H
OS 37.66568794 24.27999716
OS 37.30962312 24.18458968
OS 36.99038322 24.00027712
OS 36.72972334 23.73961724
OS 36.54541078 23.42037734
OS 36.4500033 23.06431252
OS 36.4500033 22.6956874
OS 36.54541078 22.33962258
OS 36.72972334 22.02038268
OS 36.99038322 21.7597228
OS 37.30962312 21.57541024
OS 37.66568794 21.48000276
OS 38.03431306 21.48000276
OS 38.39037788 21.57541024
OS 38.70961778 21.7597228
OS 38.97027766 22.02038268
OS 39.15459022 22.33962258
OS 39.2499977 22.6956874
OS 39.2499977 23.06431252
OS 39.15459022 23.42037734
OS 38.97027766 23.73961724
OS 38.70961778 24.00027712
OS 38.39037788 24.18458968
OS 38.03431306 24.27999716
OE
OB 40.85101558 21.63899914 H
OS 40.80699484 21.63899914
OS 40.80699484 20.46699996
OS 41.9789991 20.46699996
OS 41.9789991 20.51101562
OS 41.89047502 20.84139596
OS 41.71945682 21.13760314
OS 41.4776031 21.37945686
OS 41.18139592 21.55047506
OS 40.85101558 21.63899914
OE
OB 40.55299484 21.63899914 H
OS 40.50898426 21.63899914
OS 40.17860392 21.55047506
OS 39.88239674 21.37945686
OS 39.64054302 21.13760314
OS 39.46952482 20.84139596
OS 39.38100074 20.51101562
OS 39.38100074 20.46699996
OS 40.55299484 20.46699996
OS 40.55299484 21.63899914
OE
OB 41.9789991 20.21299996 H
OS 40.80699484 20.21299996
OS 40.80699484 19.04100078
OS 40.85101558 19.04100078
OS 41.18139592 19.12952486
OS 41.4776031 19.30054306
OS 41.71945682 19.54239678
OS 41.89047502 19.83860396
OS 41.9789991 20.1689843
OS 41.9789991 20.21299996
OE
OB 40.55299484 20.21299996 H
OS 39.38100074 20.21299996
OS 39.38100074 20.1689843
OS 39.46952482 19.83860396
OS 39.64054302 19.54239678
OS 39.88239674 19.30054306
OS 40.17860392 19.12952486
OS 40.50898426 19.04100078
OS 40.55299484 19.04100078
OS 40.55299484 20.21299996
OE
OB 4.9748186 18.89999776 H
OS 4.6851824 18.89999776
OS 4.40541664 18.82503474
OS 4.15458656 18.68021664
OS 3.94978382 18.4754139
OS 3.80496572 18.22458382
OS 3.7300027 17.94481806
OS 3.7300027 17.65518186
OS 3.80496572 17.3754161
OS 3.94978382 17.12458602
OS 4.15458656 16.91978328
OS 4.40541664 16.77496518
OS 4.6851824 16.70000216
OS 4.9748186 16.70000216
OS 5.25458436 16.77496518
OS 5.50541444 16.91978328
OS 5.71021718 17.12458602
OS 5.85503528 17.3754161
OS 5.9299983 17.65518186
OS 5.9299983 17.94481806
OS 5.85503528 18.22458382
OS 5.71021718 18.4754139
OS 5.50541444 18.68021664
OS 5.25458436 18.82503474
OS 4.9748186 18.89999776
OE
OB 38.03431306 19.19999716 H
OS 37.66568794 19.19999716
OS 37.30962312 19.10458968
OS 36.99038322 18.92027712
OS 36.72972334 18.65961724
OS 36.54541078 18.34037734
OS 36.4500033 17.98431252
OS 36.4500033 17.6156874
OS 36.54541078 17.25962258
OS 36.72972334 16.94038268
OS 36.99038322 16.6797228
OS 37.30962312 16.49541024
OS 37.66568794 16.40000276
OS 38.03431306 16.40000276
OS 38.39037788 16.49541024
OS 38.70961778 16.6797228
OS 38.97027766 16.94038268
OS 39.15459022 17.25962258
OS 39.2499977 17.6156874
OS 39.2499977 17.98431252
OS 39.15459022 18.34037734
OS 38.97027766 18.65961724
OS 38.70961778 18.92027712
OS 38.39037788 19.10458968
OS 38.03431306 19.19999716
OE
OB 38.00192806 13.87399816 H
OS 37.97699034 13.87399816
OS 37.97699034 12.8469898
OS 39.0039987 12.8469898
OS 39.0039987 12.87192752
OS 38.92535522 13.16542706
OS 38.77342766 13.42857106
OS 38.5585716 13.64342712
OS 38.2954276 13.79535468
OS 38.00192806 13.87399816
OE
OB 37.72299034 13.87399816 H
OS 37.69807294 13.87399816
OS 37.4045734 13.79535468
OS 37.1414294 13.64342712
OS 36.92657334 13.42857106
OS 36.77464578 13.16542706
OS 36.6960023 12.87192752
OS 36.6960023 12.8469898
OS 37.72299034 12.8469898
OS 37.72299034 13.87399816
OE
OB 4.9748186 13.81999776 H
OS 4.6851824 13.81999776
OS 4.40541664 13.74503474
OS 4.15458656 13.60021664
OS 3.94978382 13.3954139
OS 3.80496572 13.14458382
OS 3.7300027 12.86481806
OS 3.7300027 12.57518186
OS 3.80496572 12.2954161
OS 3.94978382 12.04458602
OS 4.15458656 11.83978328
OS 4.40541664 11.69496518
OS 4.6851824 11.62000216
OS 4.9748186 11.62000216
OS 5.25458436 11.69496518
OS 5.50541444 11.83978328
OS 5.71021718 12.04458602
OS 5.85503528 12.2954161
OS 5.9299983 12.57518186
OS 5.9299983 12.86481806
OS 5.85503528 13.14458382
OS 5.71021718 13.3954139
OS 5.50541444 13.60021664
OS 5.25458436 13.74503474
OS 4.9748186 13.81999776
OE
OB 39.0039987 12.5929898 H
OS 37.97699034 12.5929898
OS 37.97699034 11.56600176
OS 38.00192806 11.56600176
OS 38.2954276 11.64464524
OS 38.5585716 11.7965728
OS 38.77342766 12.01142886
OS 38.92535522 12.27457286
OS 39.0039987 12.5680724
OS 39.0039987 12.5929898
OE
OB 37.72299034 12.5929898 H
OS 36.6960023 12.5929898
OS 36.6960023 12.5680724
OS 36.77464578 12.27457286
OS 36.92657334 12.01142886
OS 37.1414294 11.7965728
OS 37.4045734 11.64464524
OS 37.69807294 11.56600176
OS 37.72299034 11.56600176
OS 37.72299034 12.5929898
OE
OB 37.9948186 8.73999776 H
OS 37.7051824 8.73999776
OS 37.42541664 8.66503474
OS 37.17458656 8.52021664
OS 36.96978382 8.3154139
OS 36.82496572 8.06458382
OS 36.7500027 7.78481806
OS 36.7500027 7.49518186
OS 36.82496572 7.2154161
OS 36.96978382 6.96458602
OS 37.17458656 6.75978328
OS 37.42541664 6.61496518
OS 37.7051824 6.54000216
OS 37.9948186 6.54000216
OS 38.27458436 6.61496518
OS 38.52541444 6.75978328
OS 38.73021718 6.96458602
OS 38.87503528 7.2154161
OS 38.9499983 7.49518186
OS 38.9499983 7.78481806
OS 38.87503528 8.06458382
OS 38.73021718 8.3154139
OS 38.52541444 8.52021664
OS 38.27458436 8.66503474
OS 37.9948186 8.73999776
OE
OB 4.9748186 8.73999776 H
OS 4.6851824 8.73999776
OS 4.40541664 8.66503474
OS 4.15458656 8.52021664
OS 3.94978382 8.3154139
OS 3.80496572 8.06458382
OS 3.7300027 7.78481806
OS 3.7300027 7.49518186
OS 3.80496572 7.2154161
OS 3.94978382 6.96458602
OS 4.15458656 6.75978328
OS 4.40541664 6.61496518
OS 4.6851824 6.54000216
OS 4.9748186 6.54000216
OS 5.25458436 6.61496518
OS 5.50541444 6.75978328
OS 5.71021718 6.96458602
OS 5.85503528 7.2154161
OS 5.9299983 7.49518186
OS 5.9299983 7.78481806
OS 5.85503528 8.06458382
OS 5.71021718 8.3154139
OS 5.50541444 8.52021664
OS 5.25458436 8.66503474
OS 4.9748186 8.73999776
OE
OB 4.60190596 4.04999952 H
OS 4.19809168 4.04999952
OS 3.8020371 3.97121888
OS 3.42895936 3.81668528
OS 3.09320184 3.59233978
OS 2.80766012 3.30679806
OS 2.58331462 2.97104054
OS 2.42878102 2.5979628
OS 2.35000038 2.20190822
OS 2.35000038 1.79809394
OS 2.42878102 1.40203936
OS 2.58331462 1.02896162
OS 2.80766012 0.6932041
OS 3.09320184 0.40766238
OS 3.42895936 0.18331688
OS 3.8020371 0.02878328
OS 4.19809168 -0.04999736
OS 4.60190596 -0.04999736
OS 4.99796054 0.02878328
OS 5.37103828 0.18331688
OS 5.7067958 0.40766238
OS 5.99233752 0.6932041
OS 6.21668302 1.02896162
OS 6.37121662 1.40203936
OS 6.44999726 1.79809394
OS 6.44999726 2.20190822
OS 6.37121662 2.5979628
OS 6.21668302 2.97104054
OS 5.99233752 3.30679806
OS 5.7067958 3.59233978
OS 5.37103828 3.81668528
OS 4.99796054 3.97121888
OS 4.60190596 4.04999952
OE
OB 40.8039062 1.24499878 H
OS 40.4760938 1.24499878
OS 40.15944724 1.16015516
OS 39.87555144 0.99624896
OS 39.64375104 0.76444856
OS 39.47984484 0.48055276
OS 39.39500122 0.1639062
OS 39.39500122 -0.1639062
OS 39.47984484 -0.48055276
OS 39.64375104 -0.76444856
OS 39.87555144 -0.99624896
OS 40.15944724 -1.16015516
OS 40.4760938 -1.24499878
OS 40.8039062 -1.24499878
OS 41.12055276 -1.16015516
OS 41.40444856 -0.99624896
OS 41.63624896 -0.76444856
OS 41.80015516 -0.48055276
OS 41.88499878 -0.1639062
OS 41.88499878 0.1639062
OS 41.80015516 0.48055276
OS 41.63624896 0.76444856
OS 41.40444856 0.99624896
OS 41.12055276 1.16015516
OS 40.8039062 1.24499878
OE
OB 0.1639062 1.24499878 H
OS -0.1639062 1.24499878
OS -0.48055276 1.16015516
OS -0.76444856 0.99624896
OS -0.99624896 0.76444856
OS -1.16015516 0.48055276
OS -1.24499878 0.1639062
OS -1.24499878 -0.1639062
OS -1.16015516 -0.48055276
OS -0.99624896 -0.76444856
OS -0.76444856 -0.99624896
OS -0.48055276 -1.16015516
OS -0.1639062 -1.24499878
OS 0.1639062 -1.24499878
OS 0.48055276 -1.16015516
OS 0.76444856 -0.99624896
OS 0.99624896 -0.76444856
OS 1.16015516 -0.48055276
OS 1.24499878 -0.1639062
OS 1.24499878 0.1639062
OS 1.16015516 0.48055276
OS 0.99624896 0.76444856
OS 0.76444856 0.99624896
OS 0.48055276 1.16015516
OS 0.1639062 1.24499878
OE
OB 35.70190726 1.0499979 H
OS 35.29809298 1.0499979
OS 34.9020384 0.97121726
OS 34.52896066 0.81668366
OS 34.19320314 0.59233816
OS 33.90766142 0.30679644
OS 33.68331592 -0.02896108
OS 33.52878232 -0.40203882
OS 33.45000168 -0.7980934
OS 33.45000168 -1.20190768
OS 33.52878232 -1.59796226
OS 33.68331592 -1.97104
OS 33.90766142 -2.30679752
OS 34.19320314 -2.59233924
OS 34.52896066 -2.81668474
OS 34.9020384 -2.97121834
OS 35.29809298 -3.04999898
OS 35.70190726 -3.04999898
OS 36.09796184 -2.97121834
OS 36.47103958 -2.81668474
OS 36.8067971 -2.59233924
OS 37.09233882 -2.30679752
OS 37.31668432 -1.97104
OS 37.47121792 -1.59796226
OS 37.54999856 -1.20190768
OS 37.54999856 -0.7980934
OS 37.47121792 -0.40203882
OS 37.31668432 -0.02896108
OS 37.09233882 0.30679644
OS 36.8067971 0.59233816
OS 36.47103958 0.81668366
OS 36.09796184 0.97121726
OS 35.70190726 1.0499979
OE
OB 20.66429954 1.58999936 H
OS 20.21569998 1.58999936
OS 19.77262238 1.51982424
OS 19.34597858 1.38119866
OS 18.94627402 1.17753892
OS 18.58334866 0.91385898
OS 18.26614076 0.59665108
OS 18.00246082 0.23372572
OS 17.79880108 -0.16597884
OS 17.6601755 -0.59262264
OS 17.59000038 -1.03570024
OS 17.59000038 -1.4842998
OS 17.6601755 -1.9273774
OS 17.79880108 -2.3540212
OS 18.00246082 -2.75372576
OS 18.26614076 -3.11665112
OS 18.58334866 -3.43385902
OS 18.94627402 -3.69753896
OS 19.34597858 -3.9011987
OS 19.77262238 -4.03982428
OS 20.21569998 -4.1099994
OS 20.66429954 -4.1099994
OS 21.10737714 -4.03982428
OS 21.53402094 -3.9011987
OS 21.9337255 -3.69753896
OS 22.29665086 -3.43385902
OS 22.61385876 -3.11665112
OS 22.8775387 -2.75372576
OS 23.08119844 -2.3540212
OS 23.21982402 -1.9273774
OS 23.28999914 -1.4842998
OS 23.28999914 -1.03570024
OS 23.21982402 -0.59262264
OS 23.08119844 -0.16597884
OS 22.8775387 0.23372572
OS 22.61385876 0.59665108
OS 22.29665086 0.91385898
OS 21.9337255 1.17753892
OS 21.53402094 1.38119866
OS 21.10737714 1.51982424
OS 20.66429954 1.58999936
OE
SE
S P 0
OB -2.97936666 -38.48662356 I
OS -2.97197018 -38.48754812
OS -2.96272458 -38.48939724
OS -2.95255442 -38.49124636
OS -2.94053514 -38.49402004
OS -2.92944042 -38.49679372
OS -2.91649658 -38.50141652
OS -2.9044773 -38.50603932
OS -2.89153346 -38.51251124
OS -2.87858962 -38.51990772
OS -2.86564578 -38.52822876
OS -2.8536265 -38.53839892
OS -2.84253178 -38.54949364
OS -2.84160722 -38.5504182
OS -2.8397581 -38.55226732
OS -2.83698442 -38.55596556
OS -2.83328618 -38.56151292
OS -2.82866338 -38.56798484
OS -2.82404058 -38.57538132
OS -2.81849322 -38.58462692
OS -2.81294586 -38.59572164
OS -2.8073985 -38.60774092
OS -2.80185114 -38.62068476
OS -2.79722834 -38.63547772
OS -2.79260554 -38.65119524
OS -2.7889073 -38.66876188
OS -2.78613362 -38.68725308
OS -2.7842845 -38.70666884
OS -2.78335994 -38.72793372
OS -2.78335994 -38.72885828
OS -2.78335994 -38.73255652
OS -2.78335994 -38.73902844
OS -2.7842845 -38.74827404
OS -3.1309945 -38.74827404
OS -3.1309945 -38.7491986
OS -3.1309945 -38.75197228
OS -3.13006994 -38.75567052
OS -3.13006994 -38.76121788
OS -3.12914538 -38.7676898
OS -3.12729626 -38.77508628
OS -3.12452258 -38.79172836
OS -3.11897522 -38.81021956
OS -3.11157874 -38.83055988
OS -3.10140858 -38.84905108
OS -3.08846474 -38.86569316
OS -3.08754018 -38.86569316
OS -3.08661562 -38.86754228
OS -3.08106826 -38.87216508
OS -3.07274722 -38.878637
OS -3.0616525 -38.88510892
OS -3.04685954 -38.8925054
OS -3.03021746 -38.89897732
OS -3.01172626 -38.90360012
OS -3.0015561 -38.90452468
OS -2.99046138 -38.90544924
OS -2.9830649 -38.90544924
OS -2.97474386 -38.90452468
OS -2.9645737 -38.90267556
OS -2.95347898 -38.89990188
OS -2.94053514 -38.89620364
OS -2.92851586 -38.89065628
OS -2.91649658 -38.8832598
OS -2.91557202 -38.88233524
OS -2.91094922 -38.878637
OS -2.90540186 -38.87308964
OS -2.89892994 -38.86569316
OS -2.89153346 -38.855523
OS -2.88321242 -38.84257916
OS -2.87489138 -38.8277862
OS -2.8674949 -38.81021956
OS -2.78613362 -38.82038972
OS -2.78613362 -38.82131428
OS -2.78705818 -38.8231634
OS -2.78798274 -38.82686164
OS -2.78983186 -38.832409
OS -2.79260554 -38.83795636
OS -2.79537922 -38.84535284
OS -2.8027757 -38.86107036
OS -2.8120213 -38.878637
OS -2.82496514 -38.8971282
OS -2.8397581 -38.91469484
OS -2.8582493 -38.93133692
OS -2.85917386 -38.93133692
OS -2.86102298 -38.93318604
OS -2.86379666 -38.93503516
OS -2.8674949 -38.93780884
OS -2.87304226 -38.94058252
OS -2.87858962 -38.9433562
OS -2.8859861 -38.94705444
OS -2.89430714 -38.95075268
OS -2.90355274 -38.95445092
OS -2.91279834 -38.95814916
OS -2.93591234 -38.96369652
OS -2.96180002 -38.96831932
OS -2.99046138 -38.97016844
OS -3.00063154 -38.97016844
OS -3.00710346 -38.96924388
OS -3.0154245 -38.96831932
OS -3.02559466 -38.9664702
OS -3.03668938 -38.96462108
OS -3.04870866 -38.96277196
OS -3.07459634 -38.95537548
OS -3.08846474 -38.94982812
OS -3.10140858 -38.94428076
OS -3.11527698 -38.93688428
OS -3.12822082 -38.92856324
OS -3.1402401 -38.91931764
OS -3.15225938 -38.90822292
OS -3.15318394 -38.90729836
OS -3.15503306 -38.90544924
OS -3.15780674 -38.901751
OS -3.16150498 -38.89620364
OS -3.16612778 -38.88973172
OS -3.17075058 -38.88233524
OS -3.17629794 -38.87308964
OS -3.1818453 -38.86291948
OS -3.18739266 -38.8509002
OS -3.19294002 -38.83795636
OS -3.19756282 -38.8231634
OS -3.20218562 -38.80744588
OS -3.20588386 -38.7908038
OS -3.20865754 -38.7723126
OS -3.21050666 -38.75289684
OS -3.21143122 -38.73255652
OS -3.21143122 -38.73163196
OS -3.21143122 -38.72700916
OS -3.21143122 -38.7214618
OS -3.21050666 -38.71314076
OS -3.2095821 -38.7029706
OS -3.20865754 -38.69187588
OS -3.20680842 -38.67893204
OS -3.20403474 -38.6659882
OS -3.19663826 -38.63640228
OS -3.19201546 -38.62160932
OS -3.1864681 -38.6058918
OS -3.17907162 -38.59109884
OS -3.17075058 -38.57723044
OS -3.16150498 -38.56336204
OS -3.15133482 -38.5504182
OS -3.15041026 -38.54949364
OS -3.14856114 -38.54764452
OS -3.1448629 -38.54487084
OS -3.1402401 -38.54024804
OS -3.13469274 -38.53562524
OS -3.12729626 -38.53007788
OS -3.11897522 -38.52360596
OS -3.10880506 -38.5180586
OS -3.0986349 -38.51158668
OS -3.08661562 -38.50603932
OS -3.07367178 -38.50049196
OS -3.05980338 -38.49586916
OS -3.04501042 -38.49124636
OS -3.0292929 -38.48847268
OS -3.01265082 -38.48662356
OS -2.99508418 -38.485699
OS -2.98583858 -38.485699
OS -2.97936666 -38.48662356
OE
OB -2.5022937 -38.48662356 I
OS -2.49212354 -38.48847268
OS -2.48010426 -38.49217092
OS -2.46716042 -38.49679372
OS -2.45236746 -38.50326564
OS -2.43664994 -38.51158668
OS -2.4653113 -38.58370236
OS -2.46623586 -38.5827778
OS -2.4699341 -38.58092868
OS -2.47548146 -38.578155
OS -2.48287794 -38.57538132
OS -2.49119898 -38.57260764
OS -2.50136914 -38.56983396
OS -2.5115393 -38.56798484
OS -2.52170946 -38.56706028
OS -2.52633226 -38.56706028
OS -2.53095506 -38.56798484
OS -2.53742698 -38.5689094
OS -2.5438989 -38.57075852
OS -2.55221994 -38.5735322
OS -2.56054098 -38.57723044
OS -2.56793746 -38.5827778
OS -2.56886202 -38.58370236
OS -2.5716357 -38.58555148
OS -2.57440938 -38.58924972
OS -2.57903218 -38.59387252
OS -2.58365498 -38.60034444
OS -2.58827778 -38.60774092
OS -2.59290058 -38.61606196
OS -2.59659882 -38.62623212
OS -2.59752338 -38.62808124
OS -2.59844794 -38.6336286
OS -2.60029706 -38.64194964
OS -2.60307074 -38.65304436
OS -2.60584442 -38.66691276
OS -2.60769354 -38.68263028
OS -2.6086181 -38.69927236
OS -2.60954266 -38.71776356
OS -2.60954266 -38.95999828
OS -2.68813026 -38.95999828
OS -2.68813026 -38.49586916
OS -2.61693914 -38.49586916
OS -2.61693914 -38.56613572
OS -2.61601458 -38.56521116
OS -2.61231634 -38.55873924
OS -2.60769354 -38.5504182
OS -2.60029706 -38.54024804
OS -2.59290058 -38.53007788
OS -2.58457954 -38.51898316
OS -2.5762585 -38.50973756
OS -2.56793746 -38.50234108
OS -2.5670129 -38.50141652
OS -2.56423922 -38.4995674
OS -2.55869186 -38.49679372
OS -2.5531445 -38.49402004
OS -2.54574802 -38.49124636
OS -2.53650242 -38.48847268
OS -2.52725682 -38.48662356
OS -2.51708666 -38.485699
OS -2.51061474 -38.485699
OS -2.5022937 -38.48662356
OE
OB -3.4499677 -38.48662356 I
OS -3.43979754 -38.48754812
OS -3.42777826 -38.48939724
OS -3.41483442 -38.49217092
OS -3.40096602 -38.49586916
OS -3.38802218 -38.50141652
OS -3.38617306 -38.50234108
OS -3.38247482 -38.5041902
OS -3.3760029 -38.50696388
OS -3.36860642 -38.51158668
OS -3.35936082 -38.51713404
OS -3.35103978 -38.52453052
OS -3.34271874 -38.531927
OS -3.33532226 -38.5411726
OS -3.3343977 -38.54209716
OS -3.33254858 -38.5457954
OS -3.3297749 -38.5504182
OS -3.3251521 -38.55689012
OS -3.32145386 -38.56613572
OS -3.31775562 -38.57538132
OS -3.31313282 -38.58647604
OS -3.31035914 -38.59849532
OS -3.31035914 -38.59941988
OS -3.30943458 -38.60311812
OS -3.30851002 -38.60866548
OS -3.30758546 -38.61606196
OS -3.30758546 -38.62715668
OS -3.3066609 -38.64010052
OS -3.30573634 -38.65581804
OS -3.30573634 -38.6752338
OS -3.30573634 -38.95999828
OS -3.38432394 -38.95999828
OS -3.38432394 -38.67893204
OS -3.38432394 -38.67800748
OS -3.38432394 -38.67708292
OS -3.38432394 -38.670611
OS -3.38432394 -38.66228996
OS -3.3852485 -38.6521198
OS -3.38617306 -38.64010052
OS -3.38802218 -38.62808124
OS -3.39079586 -38.61698652
OS -3.39356954 -38.60681636
OS -3.39356954 -38.6058918
OS -3.39541866 -38.60311812
OS -3.39819234 -38.59849532
OS -3.40096602 -38.59294796
OS -3.40558882 -38.5874006
OS -3.41113618 -38.58092868
OS -3.41853266 -38.57445676
OS -3.4268537 -38.5689094
OS -3.42777826 -38.56798484
OS -3.43055194 -38.56613572
OS -3.4360993 -38.5642866
OS -3.44257122 -38.56151292
OS -3.4499677 -38.55873924
OS -3.4592133 -38.55596556
OS -3.47030802 -38.555041
OS -3.48140274 -38.55411644
OS -3.48602554 -38.55411644
OS -3.48972378 -38.555041
OS -3.49896938 -38.55596556
OS -3.51098866 -38.55781468
OS -3.5239325 -38.56243748
OS -3.53872546 -38.56798484
OS -3.55351842 -38.57538132
OS -3.56738682 -38.58647604
OS -3.56923594 -38.58832516
OS -3.57293418 -38.59294796
OS -3.57570786 -38.5966462
OS -3.57848154 -38.601269
OS -3.58217978 -38.60681636
OS -3.58495346 -38.61328828
OS -3.5886517 -38.62068476
OS -3.59234994 -38.62993036
OS -3.59512362 -38.64010052
OS -3.5978973 -38.65119524
OS -3.59974642 -38.66321452
OS -3.60159554 -38.67615836
OS -3.60344466 -38.69187588
OS -3.60344466 -38.7075934
OS -3.60344466 -38.95999828
OS -3.68203226 -38.95999828
OS -3.68203226 -38.49586916
OS -3.6117657 -38.49586916
OS -3.6117657 -38.56243748
OS -3.61084114 -38.56151292
OS -3.60899202 -38.55873924
OS -3.60621834 -38.555041
OS -3.6025201 -38.5504182
OS -3.59697274 -38.54487084
OS -3.59050082 -38.53839892
OS -3.58310434 -38.53100244
OS -3.57385874 -38.52360596
OS -3.56461314 -38.51713404
OS -3.55351842 -38.50973756
OS -3.54149914 -38.50326564
OS -3.5285553 -38.49771828
OS -3.51376234 -38.49309548
OS -3.49896938 -38.48939724
OS -3.4823273 -38.48662356
OS -3.46476066 -38.485699
OS -3.45736418 -38.485699
OS -3.4499677 -38.48662356
OE
OB -0.0660781 -38.48662356 I
OS -0.05590794 -38.48847268
OS -0.04388866 -38.49217092
OS -0.03094482 -38.49679372
OS -0.01615186 -38.50326564
OS -0.00043434 -38.51158668
OS -0.0290957 -38.58370236
OS -0.03002026 -38.5827778
OS -0.0337185 -38.58092868
OS -0.03926586 -38.578155
OS -0.04666234 -38.57538132
OS -0.05498338 -38.57260764
OS -0.06515354 -38.56983396
OS -0.0753237 -38.56798484
OS -0.08549386 -38.56706028
OS -0.09011666 -38.56706028
OS -0.09473946 -38.56798484
OS -0.10121138 -38.5689094
OS -0.1076833 -38.57075852
OS -0.11600434 -38.5735322
OS -0.12432538 -38.57723044
OS -0.13172186 -38.5827778
OS -0.13264642 -38.58370236
OS -0.1354201 -38.58555148
OS -0.13819378 -38.58924972
OS -0.14281658 -38.59387252
OS -0.14743938 -38.60034444
OS -0.15206218 -38.60774092
OS -0.15668498 -38.61606196
OS -0.16038322 -38.62623212
OS -0.16130778 -38.62808124
OS -0.16223234 -38.6336286
OS -0.16408146 -38.64194964
OS -0.16685514 -38.65304436
OS -0.16962882 -38.66691276
OS -0.17147794 -38.68263028
OS -0.1724025 -38.69927236
OS -0.17332706 -38.71776356
OS -0.17332706 -38.95999828
OS -0.25191466 -38.95999828
OS -0.25191466 -38.49586916
OS -0.18072354 -38.49586916
OS -0.18072354 -38.56613572
OS -0.17979898 -38.56521116
OS -0.17610074 -38.55873924
OS -0.17147794 -38.5504182
OS -0.16408146 -38.54024804
OS -0.15668498 -38.53007788
OS -0.14836394 -38.51898316
OS -0.1400429 -38.50973756
OS -0.13172186 -38.50234108
OS -0.1307973 -38.50141652
OS -0.12802362 -38.4995674
OS -0.12247626 -38.49679372
OS -0.1169289 -38.49402004
OS -0.10953242 -38.49124636
OS -0.10028682 -38.48847268
OS -0.09104122 -38.48662356
OS -0.08087106 -38.485699
OS -0.07439914 -38.485699
OS -0.0660781 -38.48662356
OE
OB -1.94201034 -39.1375138 I
OS -2.46253762 -39.1375138
OS -2.46253762 -39.08111564
OS -1.94201034 -39.08111564
OS -1.94201034 -39.1375138
OE
OB -1.81534562 -38.95999828 I
OS -1.89393322 -38.95999828
OS -1.89393322 -38.32020276
OS -1.81534562 -38.32020276
OS -1.81534562 -38.95999828
OE
OB -0.99248722 -38.96739476 I
OS -0.99248722 -38.96831932
OS -0.99341178 -38.971093
OS -0.9952609 -38.97479124
OS -0.99711002 -38.97941404
OS -0.9998837 -38.98588596
OS -1.00265738 -38.99328244
OS -1.0091293 -39.00899996
OS -1.01560122 -39.0265666
OS -1.0229977 -39.04413324
OS -1.03039418 -39.05985076
OS -1.03409242 -39.06632268
OS -1.0368661 -39.0727946
OS -1.03779066 -39.07464372
OS -1.04056434 -39.07926652
OS -1.04518714 -39.08573844
OS -1.0507345 -39.09405948
OS -1.05813098 -39.10330508
OS -1.06645202 -39.11255068
OS -1.07477306 -39.12179628
OS -1.08494322 -39.12919276
OS -1.08586778 -39.13011732
OS -1.08956602 -39.13196644
OS -1.09511338 -39.13474012
OS -1.10343442 -39.13843836
OS -1.11268002 -39.1421366
OS -1.12377474 -39.14491028
OS -1.13579402 -39.1467594
OS -1.14966242 -39.14768396
OS -1.15336066 -39.14768396
OS -1.15798346 -39.1467594
OS -1.16445538 -39.1467594
OS -1.17185186 -39.14491028
OS -1.1801729 -39.14306116
OS -1.1894185 -39.14121204
OS -1.19958866 -39.1375138
OS -1.2079097 -39.06447356
OS -1.20698514 -39.06447356
OS -1.2032869 -39.06539812
OS -1.1986641 -39.06632268
OS -1.19311674 -39.0681718
OS -1.17832378 -39.07094548
OS -1.16353082 -39.07187004
OS -1.15890802 -39.07187004
OS -1.15428522 -39.07094548
OS -1.14873786 -39.07094548
OS -1.13486946 -39.0681718
OS -1.12839754 -39.06539812
OS -1.12192562 -39.06262444
OS -1.12100106 -39.06262444
OS -1.11915194 -39.06077532
OS -1.11637826 -39.0589262
OS -1.11268002 -39.05615252
OS -1.10435898 -39.04875604
OS -1.0969625 -39.03858588
OS -1.0969625 -39.03766132
OS -1.09511338 -39.0358122
OS -1.09326426 -39.03211396
OS -1.09141514 -39.0265666
OS -1.0877169 -39.01917012
OS -1.08401866 -39.0080754
OS -1.0784713 -38.99513156
OS -1.07292394 -38.97941404
OS -1.07292394 -38.97848948
OS -1.07107482 -38.97479124
OS -1.0692257 -38.96831932
OS -1.06552746 -38.95999828
OS -1.24119386 -38.49586916
OS -1.15798346 -38.49586916
OS -1.06090466 -38.76491612
OS -1.06090466 -38.76584068
OS -1.0599801 -38.76676524
OS -1.05905554 -38.76953892
OS -1.05813098 -38.77416172
OS -1.05628186 -38.77878452
OS -1.05443274 -38.78433188
OS -1.04980994 -38.79727572
OS -1.04426258 -38.81299324
OS -1.03871522 -38.83148444
OS -1.03316786 -38.8509002
OS -1.0276205 -38.87216508
OS -1.0276205 -38.87124052
OS -1.02669594 -38.8693914
OS -1.02577138 -38.86661772
OS -1.02484682 -38.86291948
OS -1.02392226 -38.85829668
OS -1.02207314 -38.85274932
OS -1.0183749 -38.83888092
OS -1.0137521 -38.8231634
OS -1.00728018 -38.8046722
OS -1.00173282 -38.786181
OS -0.99433634 -38.76676524
OS -0.89448386 -38.49586916
OS -0.81589626 -38.49586916
OS -0.99248722 -38.96739476
OE
OB -0.54315106 -38.48662356 I
OS -0.53575458 -38.48754812
OS -0.52650898 -38.48939724
OS -0.51633882 -38.49124636
OS -0.50431954 -38.49402004
OS -0.49322482 -38.49679372
OS -0.48028098 -38.50141652
OS -0.4682617 -38.50603932
OS -0.45531786 -38.51251124
OS -0.44237402 -38.51990772
OS -0.42943018 -38.52822876
OS -0.4174109 -38.53839892
OS -0.40631618 -38.54949364
OS -0.40539162 -38.5504182
OS -0.4035425 -38.55226732
OS -0.40076882 -38.55596556
OS -0.39707058 -38.56151292
OS -0.39244778 -38.56798484
OS -0.38782498 -38.57538132
OS -0.38227762 -38.58462692
OS -0.37673026 -38.59572164
OS -0.3711829 -38.60774092
OS -0.36563554 -38.62068476
OS -0.36101274 -38.63547772
OS -0.35638994 -38.65119524
OS -0.3526917 -38.66876188
OS -0.34991802 -38.68725308
OS -0.3480689 -38.70666884
OS -0.34714434 -38.72793372
OS -0.34714434 -38.72885828
OS -0.34714434 -38.73255652
OS -0.34714434 -38.73902844
OS -0.3480689 -38.74827404
OS -0.6947789 -38.74827404
OS -0.6947789 -38.7491986
OS -0.6947789 -38.75197228
OS -0.69385434 -38.75567052
OS -0.69385434 -38.76121788
OS -0.69292978 -38.7676898
OS -0.69108066 -38.77508628
OS -0.68830698 -38.79172836
OS -0.68275962 -38.81021956
OS -0.67536314 -38.83055988
OS -0.66519298 -38.84905108
OS -0.65224914 -38.86569316
OS -0.65132458 -38.86569316
OS -0.65040002 -38.86754228
OS -0.64485266 -38.87216508
OS -0.63653162 -38.878637
OS -0.6254369 -38.88510892
OS -0.61064394 -38.8925054
OS -0.59400186 -38.89897732
OS -0.57551066 -38.90360012
OS -0.5653405 -38.90452468
OS -0.55424578 -38.90544924
OS -0.5468493 -38.90544924
OS -0.53852826 -38.90452468
OS -0.5283581 -38.90267556
OS -0.51726338 -38.89990188
OS -0.50431954 -38.89620364
OS -0.49230026 -38.89065628
OS -0.48028098 -38.8832598
OS -0.47935642 -38.88233524
OS -0.47473362 -38.878637
OS -0.46918626 -38.87308964
OS -0.46271434 -38.86569316
OS -0.45531786 -38.855523
OS -0.44699682 -38.84257916
OS -0.43867578 -38.8277862
OS -0.4312793 -38.81021956
OS -0.34991802 -38.82038972
OS -0.34991802 -38.82131428
OS -0.35084258 -38.8231634
OS -0.35176714 -38.82686164
OS -0.35361626 -38.832409
OS -0.35638994 -38.83795636
OS -0.35916362 -38.84535284
OS -0.3665601 -38.86107036
OS -0.3758057 -38.878637
OS -0.38874954 -38.8971282
OS -0.4035425 -38.91469484
OS -0.4220337 -38.93133692
OS -0.42295826 -38.93133692
OS -0.42480738 -38.93318604
OS -0.42758106 -38.93503516
OS -0.4312793 -38.93780884
OS -0.43682666 -38.94058252
OS -0.44237402 -38.9433562
OS -0.4497705 -38.94705444
OS -0.45809154 -38.95075268
OS -0.46733714 -38.95445092
OS -0.47658274 -38.95814916
OS -0.49969674 -38.96369652
OS -0.52558442 -38.96831932
OS -0.55424578 -38.97016844
OS -0.56441594 -38.97016844
OS -0.57088786 -38.96924388
OS -0.5792089 -38.96831932
OS -0.58937906 -38.9664702
OS -0.60047378 -38.96462108
OS -0.61249306 -38.96277196
OS -0.63838074 -38.95537548
OS -0.65224914 -38.94982812
OS -0.66519298 -38.94428076
OS -0.67906138 -38.93688428
OS -0.69200522 -38.92856324
OS -0.7040245 -38.91931764
OS -0.71604378 -38.90822292
OS -0.71696834 -38.90729836
OS -0.71881746 -38.90544924
OS -0.72159114 -38.901751
OS -0.72528938 -38.89620364
OS -0.72991218 -38.88973172
OS -0.73453498 -38.88233524
OS -0.74008234 -38.87308964
OS -0.7456297 -38.86291948
OS -0.75117706 -38.8509002
OS -0.75672442 -38.83795636
OS -0.76134722 -38.8231634
OS -0.76597002 -38.80744588
OS -0.76966826 -38.7908038
OS -0.77244194 -38.7723126
OS -0.77429106 -38.75289684
OS -0.77521562 -38.73255652
OS -0.77521562 -38.73163196
OS -0.77521562 -38.72700916
OS -0.77521562 -38.7214618
OS -0.77429106 -38.71314076
OS -0.7733665 -38.7029706
OS -0.77244194 -38.69187588
OS -0.77059282 -38.67893204
OS -0.76781914 -38.6659882
OS -0.76042266 -38.63640228
OS -0.75579986 -38.62160932
OS -0.7502525 -38.6058918
OS -0.74285602 -38.59109884
OS -0.73453498 -38.57723044
OS -0.72528938 -38.56336204
OS -0.71511922 -38.5504182
OS -0.71419466 -38.54949364
OS -0.71234554 -38.54764452
OS -0.7086473 -38.54487084
OS -0.7040245 -38.54024804
OS -0.69847714 -38.53562524
OS -0.69108066 -38.53007788
OS -0.68275962 -38.52360596
OS -0.67258946 -38.5180586
OS -0.6624193 -38.51158668
OS -0.65040002 -38.50603932
OS -0.63745618 -38.50049196
OS -0.62358778 -38.49586916
OS -0.60879482 -38.49124636
OS -0.5930773 -38.48847268
OS -0.57643522 -38.48662356
OS -0.55886858 -38.485699
OS -0.54962298 -38.485699
OS -0.54315106 -38.48662356
OE
OB -1.47695666 -38.48662356 I
OS -1.46308826 -38.48754812
OS -1.44737074 -38.48939724
OS -1.43165322 -38.49217092
OS -1.4159357 -38.49586916
OS -1.40114274 -38.50049196
OS -1.39929362 -38.50141652
OS -1.39467082 -38.50326564
OS -1.3881989 -38.50603932
OS -1.37987786 -38.50973756
OS -1.37063226 -38.51528492
OS -1.36138666 -38.52083228
OS -1.35306562 -38.52822876
OS -1.34566914 -38.53562524
OS -1.34474458 -38.5365498
OS -1.34289546 -38.53932348
OS -1.34012178 -38.54394628
OS -1.33642354 -38.54949364
OS -1.33180074 -38.55781468
OS -1.3281025 -38.56613572
OS -1.32440426 -38.57630588
OS -1.32163058 -38.58832516
OS -1.32163058 -38.58924972
OS -1.32070602 -38.5920234
OS -1.31978146 -38.59757076
OS -1.3188569 -38.60496724
OS -1.3188569 -38.6151374
OS -1.31793234 -38.62715668
OS -1.31700778 -38.6428742
OS -1.31700778 -38.66044084
OS -1.31700778 -38.76584068
OS -1.31700778 -38.76676524
OS -1.31700778 -38.77046348
OS -1.31700778 -38.77601084
OS -1.31700778 -38.78340732
OS -1.31700778 -38.79172836
OS -1.31700778 -38.80189852
OS -1.31608322 -38.82408796
OS -1.31608322 -38.84720196
OS -1.31515866 -38.87031596
OS -1.3142341 -38.88048612
OS -1.3142341 -38.88973172
OS -1.31330954 -38.89805276
OS -1.31238498 -38.90452468
OS -1.31238498 -38.90544924
OS -1.31146042 -38.90914748
OS -1.31053586 -38.91469484
OS -1.30776218 -38.92209132
OS -1.30591306 -38.93041236
OS -1.30221482 -38.93965796
OS -1.29759202 -38.94982812
OS -1.29296922 -38.95999828
OS -1.37525506 -38.95999828
OS -1.37617962 -38.95907372
OS -1.37710418 -38.95537548
OS -1.3789533 -38.95075268
OS -1.38172698 -38.9433562
OS -1.38450066 -38.93503516
OS -1.38634978 -38.924865
OS -1.3881989 -38.91377028
OS -1.39004802 -38.901751
OS -1.39097258 -38.901751
OS -1.39189714 -38.90360012
OS -1.3974445 -38.90822292
OS -1.40576554 -38.91469484
OS -1.41686026 -38.92301588
OS -1.43072866 -38.93133692
OS -1.44459706 -38.94058252
OS -1.45939002 -38.94890356
OS -1.47510754 -38.95537548
OS -1.47695666 -38.95630004
OS -1.48250402 -38.9572246
OS -1.49082506 -38.95999828
OS -1.50099522 -38.96277196
OS -1.51393906 -38.96554564
OS -1.52873202 -38.96739476
OS -1.5453741 -38.96924388
OS -1.56201618 -38.97016844
OS -1.56941266 -38.97016844
OS -1.57496002 -38.96924388
OS -1.58143194 -38.96924388
OS -1.58882842 -38.96831932
OS -1.6054705 -38.96554564
OS -1.6239617 -38.96092284
OS -1.64430202 -38.95445092
OS -1.66279322 -38.94520532
OS -1.6794353 -38.93318604
OS -1.68128442 -38.93133692
OS -1.68590722 -38.92671412
OS -1.69237914 -38.91839308
OS -1.69977562 -38.90729836
OS -1.7071721 -38.89342996
OS -1.71364402 -38.87771244
OS -1.71826682 -38.85829668
OS -1.71919138 -38.84905108
OS -1.72011594 -38.83795636
OS -1.72011594 -38.83610724
OS -1.72011594 -38.832409
OS -1.71919138 -38.82593708
OS -1.71826682 -38.81761604
OS -1.7164177 -38.80744588
OS -1.71364402 -38.79727572
OS -1.70994578 -38.786181
OS -1.70532298 -38.77601084
OS -1.70439842 -38.77508628
OS -1.7025493 -38.77138804
OS -1.69885106 -38.76584068
OS -1.69422826 -38.75936876
OS -1.6886809 -38.75197228
OS -1.68128442 -38.7445758
OS -1.67388794 -38.73717932
OS -1.66464234 -38.7307074
OS -1.66371778 -38.72978284
OS -1.66001954 -38.72793372
OS -1.65539674 -38.72423548
OS -1.64800026 -38.72053724
OS -1.63967922 -38.716839
OS -1.62950906 -38.7122162
OS -1.6193389 -38.70851796
OS -1.60731962 -38.70481972
OS -1.60639506 -38.70481972
OS -1.60269682 -38.70389516
OS -1.59714946 -38.70204604
OS -1.58975298 -38.70112148
OS -1.58050738 -38.69927236
OS -1.5684881 -38.69742324
OS -1.5546197 -38.69464956
OS -1.53797762 -38.69280044
OS -1.53705306 -38.69280044
OS -1.53335482 -38.69187588
OS -1.52873202 -38.69187588
OS -1.5222601 -38.69095132
OS -1.51486362 -38.69002676
OS -1.50561802 -38.68817764
OS -1.49544786 -38.68725308
OS -1.48435314 -38.68540396
OS -1.4621637 -38.68078116
OS -1.43812514 -38.67615836
OS -1.41686026 -38.670611
OS -1.4066901 -38.66783732
OS -1.3974445 -38.66506364
OS -1.3974445 -38.66413908
OS -1.3974445 -38.66228996
OS -1.39651994 -38.6567426
OS -1.39651994 -38.65027068
OS -1.39651994 -38.64657244
OS -1.39651994 -38.64472332
OS -1.39651994 -38.64379876
OS -1.39651994 -38.6428742
OS -1.39651994 -38.63732684
OS -1.3974445 -38.62808124
OS -1.39929362 -38.61791108
OS -1.4020673 -38.60681636
OS -1.4066901 -38.59572164
OS -1.41223746 -38.58555148
OS -1.41963394 -38.57723044
OS -1.4205585 -38.57630588
OS -1.4251813 -38.57260764
OS -1.43257778 -38.5689094
OS -1.44182338 -38.56336204
OS -1.45476722 -38.55873924
OS -1.46956018 -38.55411644
OS -1.48805138 -38.55134276
OS -1.50931626 -38.5504182
OS -1.51856186 -38.5504182
OS -1.52780746 -38.55134276
OS -1.5407513 -38.55319188
OS -1.55369514 -38.555041
OS -1.56756354 -38.55873924
OS -1.58050738 -38.56336204
OS -1.5916021 -38.56983396
OS -1.59252666 -38.57075852
OS -1.5962249 -38.5735322
OS -1.6008477 -38.578155
OS -1.60639506 -38.58555148
OS -1.61194242 -38.59479708
OS -1.61841434 -38.60681636
OS -1.6239617 -38.62160932
OS -1.62950906 -38.6382514
OS -1.70624754 -38.62808124
OS -1.70624754 -38.62715668
OS -1.70532298 -38.62623212
OS -1.70532298 -38.62345844
OS -1.70439842 -38.6197602
OS -1.70162474 -38.61143916
OS -1.6979265 -38.59941988
OS -1.6933037 -38.5874006
OS -1.68775634 -38.57445676
OS -1.68035986 -38.56151292
OS -1.67203882 -38.54949364
OS -1.67111426 -38.54856908
OS -1.66741602 -38.54487084
OS -1.66186866 -38.53932348
OS -1.65447218 -38.531927
OS -1.64430202 -38.52453052
OS -1.63228274 -38.51713404
OS -1.61841434 -38.508813
OS -1.60269682 -38.50234108
OS -1.60177226 -38.50234108
OS -1.6008477 -38.50141652
OS -1.59807402 -38.50049196
OS -1.59437578 -38.4995674
OS -1.58513018 -38.49679372
OS -1.57218634 -38.49402004
OS -1.55739338 -38.49124636
OS -1.53890218 -38.48847268
OS -1.51948642 -38.48662356
OS -1.49729698 -38.485699
OS -1.48712682 -38.485699
OS -1.47695666 -38.48662356
OE
OB 0.11698478 -38.42745172 I
OS 0.0957199 -38.54671996
OS 0.04671822 -38.54671996
OS 0.02730246 -38.42745172
OS 0.02730246 -38.32020276
OS 0.11698478 -38.32020276
OS 0.11698478 -38.42745172
OE
OB -5.4655085 -38.31835364 I
OS -5.45348922 -38.32020276
OS -5.43962082 -38.32297644
OS -5.42482786 -38.32667468
OS -5.40911034 -38.33129748
OS -5.39431738 -38.33869396
OS -5.39339282 -38.33869396
OS -5.39246826 -38.33961852
OS -5.38784546 -38.3423922
OS -5.38044898 -38.347015
OS -5.37120338 -38.35348692
OS -5.36103322 -38.36273252
OS -5.3499385 -38.37290268
OS -5.33976834 -38.38492196
OS -5.32959818 -38.39879036
OS -5.32867362 -38.40063948
OS -5.32497538 -38.40526228
OS -5.32127714 -38.41358332
OS -5.31480522 -38.4256026
OS -5.30925786 -38.439471
OS -5.30186138 -38.45518852
OS -5.29538946 -38.47367972
OS -5.2898421 -38.49402004
OS -5.2898421 -38.4949446
OS -5.28891754 -38.49679372
OS -5.28799298 -38.4995674
OS -5.28706842 -38.5041902
OS -5.28614386 -38.50973756
OS -5.2852193 -38.51620948
OS -5.28337018 -38.52453052
OS -5.28244562 -38.53377612
OS -5.2805965 -38.54394628
OS -5.27967194 -38.555041
OS -5.27874738 -38.56798484
OS -5.27689826 -38.58092868
OS -5.2759737 -38.59572164
OS -5.2759737 -38.6105146
OS -5.27504914 -38.62715668
OS -5.27504914 -38.64472332
OS -5.27504914 -38.64564788
OS -5.27504914 -38.64934612
OS -5.27504914 -38.65581804
OS -5.27504914 -38.66321452
OS -5.2759737 -38.67338468
OS -5.2759737 -38.6844794
OS -5.27689826 -38.69649868
OS -5.27782282 -38.70944252
OS -5.2805965 -38.73902844
OS -5.2852193 -38.76953892
OS -5.29076666 -38.79912484
OS -5.2944649 -38.81299324
OS -5.2990877 -38.82686164
OS -5.2990877 -38.8277862
OS -5.30001226 -38.82963532
OS -5.30186138 -38.83333356
OS -5.3037105 -38.83795636
OS -5.30555962 -38.84442828
OS -5.30925786 -38.8509002
OS -5.31665434 -38.86661772
OS -5.32589994 -38.8832598
OS -5.33791922 -38.901751
OS -5.35178762 -38.91839308
OS -5.3684297 -38.9341106
OS -5.36935426 -38.9341106
OS -5.37027882 -38.93595972
OS -5.3730525 -38.93780884
OS -5.37675074 -38.93965796
OS -5.38137354 -38.94243164
OS -5.38599634 -38.94612988
OS -5.39986474 -38.9526018
OS -5.41650682 -38.95907372
OS -5.43592258 -38.96554564
OS -5.45903658 -38.96924388
OS -5.4839997 -38.971093
OS -5.4932453 -38.971093
OS -5.49971722 -38.97016844
OS -5.5071137 -38.96924388
OS -5.5163593 -38.96739476
OS -5.52652946 -38.96554564
OS -5.53762418 -38.96277196
OS -5.5487189 -38.95907372
OS -5.56073818 -38.95537548
OS -5.57275746 -38.94982812
OS -5.58477674 -38.9433562
OS -5.59679602 -38.93595972
OS -5.6088153 -38.92671412
OS -5.61991002 -38.91654396
OS -5.63008018 -38.90544924
OS -5.63100474 -38.90452468
OS -5.63285386 -38.901751
OS -5.63562754 -38.8971282
OS -5.64025034 -38.88973172
OS -5.64487314 -38.88141068
OS -5.64949594 -38.87031596
OS -5.65596786 -38.85737212
OS -5.66151522 -38.84257916
OS -5.66706258 -38.82593708
OS -5.67260994 -38.80652132
OS -5.6781573 -38.78525644
OS -5.6827801 -38.76121788
OS -5.6874029 -38.7353302
OS -5.69017658 -38.7075934
OS -5.6920257 -38.67708292
OS -5.69295026 -38.64472332
OS -5.69295026 -38.64379876
OS -5.69295026 -38.64010052
OS -5.69295026 -38.6336286
OS -5.69295026 -38.62623212
OS -5.6920257 -38.61606196
OS -5.6920257 -38.60496724
OS -5.69110114 -38.59294796
OS -5.69017658 -38.57907956
OS -5.6874029 -38.5504182
OS -5.6827801 -38.51990772
OS -5.67723274 -38.48939724
OS -5.6735345 -38.47552884
OS -5.66983626 -38.46166044
OS -5.66983626 -38.46073588
OS -5.6689117 -38.45888676
OS -5.66706258 -38.45518852
OS -5.66521346 -38.45056572
OS -5.66336434 -38.4440938
OS -5.6596661 -38.43762188
OS -5.65226962 -38.42190436
OS -5.64302402 -38.40526228
OS -5.63100474 -38.38769564
OS -5.61713634 -38.370129
OS -5.60049426 -38.35533604
OS -5.5995697 -38.35533604
OS -5.59864514 -38.35348692
OS -5.59587146 -38.3516378
OS -5.59217322 -38.34978868
OS -5.58755042 -38.34609044
OS -5.58200306 -38.34331676
OS -5.56813466 -38.33592028
OS -5.55149258 -38.32944836
OS -5.53207682 -38.32297644
OS -5.50896282 -38.3192782
OS -5.4839997 -38.31742908
OS -5.47567866 -38.31742908
OS -5.4655085 -38.31835364
OE
OB -5.79280274 -38.95999828 I
OS -5.87139034 -38.95999828
OS -5.87139034 -38.32020276
OS -5.79280274 -38.32020276
OS -5.79280274 -38.95999828
OE
OB -5.97031826 -38.42745172 I
OS -5.99158314 -38.54671996
OS -6.04058482 -38.54671996
OS -6.06000058 -38.42745172
OS -6.06000058 -38.32020276
OS -5.97031826 -38.32020276
OS -5.97031826 -38.42745172
OE
OB -4.9754917 -38.31835364 I
OS -4.96347242 -38.32020276
OS -4.94867946 -38.32297644
OS -4.93203738 -38.32759924
OS -4.9153953 -38.3331466
OS -4.89875322 -38.34054308
OS -4.89782866 -38.34054308
OS -4.8969041 -38.34146764
OS -4.89135674 -38.34424132
OS -4.8830357 -38.34978868
OS -4.8737901 -38.3562606
OS -4.86269538 -38.3655062
OS -4.85160066 -38.37567636
OS -4.84050594 -38.38769564
OS -4.83126034 -38.40156404
OS -4.83033578 -38.40341316
OS -4.8275621 -38.40803596
OS -4.82386386 -38.416357
OS -4.81924106 -38.42652716
OS -4.81461826 -38.43854644
OS -4.81092002 -38.45241484
OS -4.80814634 -38.46813236
OS -4.80722178 -38.48384988
OS -4.80722178 -38.485699
OS -4.80722178 -38.49124636
OS -4.80814634 -38.49864284
OS -4.80999546 -38.508813
OS -4.81276914 -38.52083228
OS -4.81739194 -38.53377612
OS -4.8229393 -38.54671996
OS -4.83033578 -38.5596638
OS -4.83126034 -38.56151292
OS -4.83403402 -38.56521116
OS -4.83958138 -38.57168308
OS -4.84697786 -38.57907956
OS -4.85622346 -38.5874006
OS -4.86731818 -38.5966462
OS -4.88026202 -38.60496724
OS -4.89597954 -38.61328828
OS -4.89505498 -38.61328828
OS -4.89320586 -38.61421284
OS -4.89043218 -38.6151374
OS -4.88673394 -38.61606196
OS -4.87656378 -38.6197602
OS -4.86361994 -38.62530756
OS -4.84882698 -38.63270404
OS -4.83403402 -38.64194964
OS -4.82016562 -38.65396892
OS -4.80722178 -38.66783732
OS -4.80629722 -38.66968644
OS -4.80259898 -38.6752338
OS -4.79705162 -38.6844794
OS -4.79150426 -38.69649868
OS -4.7859569 -38.71129164
OS -4.78040954 -38.72885828
OS -4.7767113 -38.7491986
OS -4.77578674 -38.77138804
OS -4.77578674 -38.7723126
OS -4.77578674 -38.77508628
OS -4.77578674 -38.77970908
OS -4.7767113 -38.78525644
OS -4.77763586 -38.79265292
OS -4.77948498 -38.80097396
OS -4.7813341 -38.81021956
OS -4.78318322 -38.82038972
OS -4.7905797 -38.84257916
OS -4.79612706 -38.85459844
OS -4.80167442 -38.86569316
OS -4.8090709 -38.87771244
OS -4.81739194 -38.88973172
OS -4.82663754 -38.901751
OS -4.83773226 -38.91284572
OS -4.83865682 -38.91377028
OS -4.84050594 -38.9156194
OS -4.84420418 -38.91839308
OS -4.84882698 -38.92209132
OS -4.85437434 -38.92671412
OS -4.86177082 -38.93133692
OS -4.87009186 -38.93688428
OS -4.88026202 -38.94150708
OS -4.89043218 -38.94705444
OS -4.90245146 -38.9526018
OS -4.91447074 -38.9572246
OS -4.92833914 -38.9618474
OS -4.9431321 -38.96554564
OS -4.95884962 -38.96831932
OS -4.97456714 -38.97016844
OS -4.99213378 -38.971093
OS -5.00045482 -38.971093
OS -5.00600218 -38.97016844
OS -5.01339866 -38.96924388
OS -5.0217197 -38.96831932
OS -5.0309653 -38.9664702
OS -5.04113546 -38.96462108
OS -5.0633249 -38.95907372
OS -5.0864389 -38.94982812
OS -5.09845818 -38.94428076
OS -5.1095529 -38.93780884
OS -5.12064762 -38.9294878
OS -5.13174234 -38.92116676
OS -5.1326669 -38.9202422
OS -5.13451602 -38.91839308
OS -5.1372897 -38.9156194
OS -5.14006338 -38.91192116
OS -5.14468618 -38.90729836
OS -5.14930898 -38.90082644
OS -5.15485634 -38.89435452
OS -5.1604037 -38.88603348
OS -5.16595106 -38.87678788
OS -5.17149842 -38.86754228
OS -5.18166858 -38.84535284
OS -5.18998962 -38.81946516
OS -5.1927633 -38.80559676
OS -5.19461242 -38.7908038
OS -5.11602482 -38.78063364
OS -5.11602482 -38.7815582
OS -5.11510026 -38.78340732
OS -5.1141757 -38.78710556
OS -5.11325114 -38.79172836
OS -5.11232658 -38.79727572
OS -5.11047746 -38.80374764
OS -5.10585466 -38.81761604
OS -5.09938274 -38.83425812
OS -5.0910617 -38.84997564
OS -5.0818161 -38.8647686
OS -5.07072138 -38.87771244
OS -5.06887226 -38.878637
OS -5.06517402 -38.88233524
OS -5.05777754 -38.88695804
OS -5.04853194 -38.89158084
OS -5.03743722 -38.8971282
OS -5.02356882 -38.901751
OS -5.0078513 -38.90544924
OS -4.99120922 -38.9063738
OS -4.98566186 -38.9063738
OS -4.98196362 -38.90544924
OS -4.97179346 -38.90452468
OS -4.95884962 -38.901751
OS -4.94405666 -38.8971282
OS -4.92833914 -38.89065628
OS -4.91262162 -38.88141068
OS -4.89782866 -38.86846684
OS -4.89597954 -38.86661772
OS -4.89135674 -38.86107036
OS -4.88580938 -38.85274932
OS -4.8784129 -38.8416546
OS -4.87101642 -38.8277862
OS -4.86546906 -38.81206868
OS -4.86084626 -38.79357748
OS -4.85899714 -38.77323716
OS -4.85899714 -38.7723126
OS -4.85899714 -38.77046348
OS -4.85899714 -38.7676898
OS -4.8599217 -38.76399156
OS -4.86084626 -38.7538214
OS -4.86361994 -38.74180212
OS -4.86731818 -38.72700916
OS -4.8737901 -38.7122162
OS -4.8830357 -38.69742324
OS -4.89505498 -38.68355484
OS -4.8969041 -38.68170572
OS -4.9015269 -38.67800748
OS -4.90892338 -38.67246012
OS -4.91909354 -38.6659882
OS -4.93203738 -38.65951628
OS -4.9477549 -38.65396892
OS -4.96532154 -38.65027068
OS -4.9847373 -38.64842156
OS -4.99305834 -38.64842156
OS -4.99953026 -38.64934612
OS -5.0078513 -38.65027068
OS -5.0170969 -38.6521198
OS -5.02819162 -38.65396892
OS -5.0402109 -38.6567426
OS -5.0309653 -38.5874006
OS -5.0263425 -38.5874006
OS -5.02264426 -38.58832516
OS -5.01062498 -38.58832516
OS -5.00045482 -38.58647604
OS -4.98843554 -38.58462692
OS -4.97456714 -38.58185324
OS -4.95884962 -38.57723044
OS -4.94405666 -38.57075852
OS -4.92833914 -38.56243748
OS -4.92741458 -38.56243748
OS -4.92649002 -38.56151292
OS -4.92186722 -38.55781468
OS -4.9153953 -38.55134276
OS -4.90799882 -38.54302172
OS -4.90060234 -38.53100244
OS -4.89413042 -38.51713404
OS -4.88950762 -38.50141652
OS -4.8876585 -38.49217092
OS -4.8876585 -38.48200076
OS -4.8876585 -38.4810762
OS -4.8876585 -38.48015164
OS -4.8876585 -38.47460428
OS -4.88950762 -38.4672078
OS -4.89135674 -38.45703764
OS -4.89505498 -38.44594292
OS -4.89967778 -38.43392364
OS -4.90707426 -38.42190436
OS -4.91724442 -38.41080964
OS -4.91816898 -38.40988508
OS -4.92279178 -38.40618684
OS -4.9292637 -38.40156404
OS -4.93758474 -38.39601668
OS -4.94867946 -38.39139388
OS -4.9616233 -38.38677108
OS -4.97641626 -38.38307284
OS -4.99305834 -38.38214828
OS -5.00045482 -38.38214828
OS -5.00877586 -38.3839974
OS -5.01987058 -38.38584652
OS -5.03188986 -38.38954476
OS -5.04390914 -38.39416756
OS -5.05685298 -38.40156404
OS -5.06887226 -38.41080964
OS -5.06979682 -38.4117342
OS -5.07349506 -38.416357
OS -5.07904242 -38.42282892
OS -5.08551434 -38.43207452
OS -5.09198626 -38.4440938
OS -5.09845818 -38.45888676
OS -5.10400554 -38.4764534
OS -5.10770378 -38.49679372
OS -5.18629138 -38.48292532
OS -5.18629138 -38.48200076
OS -5.18536682 -38.47922708
OS -5.18444226 -38.47552884
OS -5.1835177 -38.46998148
OS -5.18166858 -38.46350956
OS -5.1788949 -38.45611308
OS -5.17334754 -38.43854644
OS -5.16410194 -38.41820612
OS -5.15300722 -38.3978658
OS -5.13913882 -38.37845004
OS -5.12157218 -38.3608834
OS -5.12064762 -38.35995884
OS -5.1187985 -38.35903428
OS -5.11602482 -38.35718516
OS -5.11232658 -38.35441148
OS -5.10770378 -38.35071324
OS -5.10123186 -38.347015
OS -5.09475994 -38.34331676
OS -5.0864389 -38.33869396
OS -5.0679477 -38.33129748
OS -5.04668282 -38.323901
OS -5.0217197 -38.3192782
OS -5.00877586 -38.31742908
OS -4.98566186 -38.31742908
OS -4.9754917 -38.31835364
OE
OB -4.29963834 -38.40988508 I
OS -4.37822594 -38.40988508
OS -4.37822594 -38.32020276
OS -4.29963834 -38.32020276
OS -4.29963834 -38.40988508
OE
OB -4.29963834 -38.95999828 I
OS -4.37822594 -38.95999828
OS -4.37822594 -38.49586916
OS -4.29963834 -38.49586916
OS -4.29963834 -38.95999828
OE
OB -4.46421002 -38.7676898 I
OS -4.7073693 -38.7676898
OS -4.7073693 -38.6891022
OS -4.46421002 -38.6891022
OS -4.46421002 -38.7676898
OE
OB -3.94738098 -38.48662356 I
OS -3.93721082 -38.48754812
OS -3.92519154 -38.48939724
OS -3.9122477 -38.49217092
OS -3.8983793 -38.49586916
OS -3.88543546 -38.50141652
OS -3.88358634 -38.50234108
OS -3.8798881 -38.5041902
OS -3.87341618 -38.50696388
OS -3.8660197 -38.51158668
OS -3.8567741 -38.51713404
OS -3.84845306 -38.52453052
OS -3.84013202 -38.531927
OS -3.83273554 -38.5411726
OS -3.83181098 -38.54209716
OS -3.82996186 -38.5457954
OS -3.82718818 -38.5504182
OS -3.82256538 -38.55689012
OS -3.81886714 -38.56613572
OS -3.8151689 -38.57538132
OS -3.8105461 -38.58647604
OS -3.80777242 -38.59849532
OS -3.80777242 -38.59941988
OS -3.80684786 -38.60311812
OS -3.8059233 -38.60866548
OS -3.80499874 -38.61606196
OS -3.80499874 -38.62715668
OS -3.80407418 -38.64010052
OS -3.80314962 -38.65581804
OS -3.80314962 -38.6752338
OS -3.80314962 -38.95999828
OS -3.88173722 -38.95999828
OS -3.88173722 -38.67893204
OS -3.88173722 -38.67800748
OS -3.88173722 -38.67708292
OS -3.88173722 -38.670611
OS -3.88173722 -38.66228996
OS -3.88266178 -38.6521198
OS -3.88358634 -38.64010052
OS -3.88543546 -38.62808124
OS -3.88820914 -38.61698652
OS -3.89098282 -38.60681636
OS -3.89098282 -38.6058918
OS -3.89283194 -38.60311812
OS -3.89560562 -38.59849532
OS -3.8983793 -38.59294796
OS -3.9030021 -38.5874006
OS -3.90854946 -38.58092868
OS -3.91594594 -38.57445676
OS -3.92426698 -38.5689094
OS -3.92519154 -38.56798484
OS -3.92796522 -38.56613572
OS -3.93351258 -38.5642866
OS -3.9399845 -38.56151292
OS -3.94738098 -38.55873924
OS -3.95662658 -38.55596556
OS -3.9677213 -38.555041
OS -3.97881602 -38.55411644
OS -3.98343882 -38.55411644
OS -3.98713706 -38.555041
OS -3.99638266 -38.55596556
OS -4.00840194 -38.55781468
OS -4.02134578 -38.56243748
OS -4.03613874 -38.56798484
OS -4.0509317 -38.57538132
OS -4.0648001 -38.58647604
OS -4.06664922 -38.58832516
OS -4.07034746 -38.59294796
OS -4.07312114 -38.5966462
OS -4.07589482 -38.601269
OS -4.07959306 -38.60681636
OS -4.08236674 -38.61328828
OS -4.08606498 -38.62068476
OS -4.08976322 -38.62993036
OS -4.0925369 -38.64010052
OS -4.09531058 -38.65119524
OS -4.0971597 -38.66321452
OS -4.09900882 -38.67615836
OS -4.10085794 -38.69187588
OS -4.10085794 -38.7075934
OS -4.10085794 -38.95999828
OS -4.17944554 -38.95999828
OS -4.17944554 -38.49586916
OS -4.10917898 -38.49586916
OS -4.10917898 -38.56243748
OS -4.10825442 -38.56151292
OS -4.1064053 -38.55873924
OS -4.10363162 -38.555041
OS -4.09993338 -38.5504182
OS -4.09438602 -38.54487084
OS -4.0879141 -38.53839892
OS -4.08051762 -38.53100244
OS -4.07127202 -38.52360596
OS -4.06202642 -38.51713404
OS -4.0509317 -38.50973756
OS -4.03891242 -38.50326564
OS -4.02596858 -38.49771828
OS -4.01117562 -38.49309548
OS -3.99638266 -38.48939724
OS -3.97974058 -38.48662356
OS -3.96217394 -38.485699
OS -3.95477746 -38.485699
OS -3.94738098 -38.48662356
OE
OB -0.55794402 -38.5504182 H
OS -0.56349138 -38.5504182
OS -0.56718962 -38.55134276
OS -0.57735978 -38.55226732
OS -0.58937906 -38.555041
OS -0.60417202 -38.5596638
OS -0.61988954 -38.56613572
OS -0.6346825 -38.57538132
OS -0.64947546 -38.5874006
OS -0.65132458 -38.58924972
OS -0.65502282 -38.59387252
OS -0.66149474 -38.60219356
OS -0.66796666 -38.61328828
OS -0.67536314 -38.62623212
OS -0.68183506 -38.6428742
OS -0.68738242 -38.66228996
OS -0.6901561 -38.68355484
OS -0.43035474 -38.68355484
OS -0.43035474 -38.68263028
OS -0.43035474 -38.68078116
OS -0.4312793 -38.67800748
OS -0.4312793 -38.67430924
OS -0.43312842 -38.66321452
OS -0.4359021 -38.65119524
OS -0.4405249 -38.63640228
OS -0.4451477 -38.62253388
OS -0.45254418 -38.60866548
OS -0.46086522 -38.5966462
OS -0.46086522 -38.59572164
OS -0.46271434 -38.59479708
OS -0.46733714 -38.58924972
OS -0.47565818 -38.58185324
OS -0.4867529 -38.5735322
OS -0.5006213 -38.56521116
OS -0.51726338 -38.55781468
OS -0.53667914 -38.55226732
OS -0.5468493 -38.55134276
OS -0.55794402 -38.5504182
OE
OB -5.48492426 -38.38214828 H
OS -5.49047162 -38.38214828
OS -5.49416986 -38.38307284
OS -5.50434002 -38.38492196
OS -5.5163593 -38.38769564
OS -5.5302277 -38.393243
OS -5.54502066 -38.40156404
OS -5.55241714 -38.4071114
OS -5.55981362 -38.41265876
OS -5.56628554 -38.42005524
OS -5.57275746 -38.42837628
OS -5.57275746 -38.42930084
OS -5.57460658 -38.43114996
OS -5.5764557 -38.4348482
OS -5.57922938 -38.439471
OS -5.58200306 -38.44686748
OS -5.5857013 -38.45518852
OS -5.58847498 -38.46535868
OS -5.59217322 -38.47737796
OS -5.59587146 -38.49124636
OS -5.5995697 -38.50696388
OS -5.60326794 -38.52453052
OS -5.60604162 -38.54394628
OS -5.6088153 -38.56613572
OS -5.61066442 -38.59017428
OS -5.61158898 -38.61606196
OS -5.61251354 -38.64472332
OS -5.61251354 -38.64657244
OS -5.61251354 -38.65119524
OS -5.61251354 -38.65951628
OS -5.61158898 -38.670611
OS -5.61158898 -38.68263028
OS -5.61066442 -38.69742324
OS -5.60973986 -38.71314076
OS -5.60789074 -38.72978284
OS -5.60326794 -38.76584068
OS -5.60049426 -38.78340732
OS -5.59679602 -38.8000494
OS -5.59309778 -38.81576692
OS -5.58755042 -38.83055988
OS -5.58200306 -38.84350372
OS -5.57553114 -38.85459844
OS -5.57553114 -38.855523
OS -5.57368202 -38.85644756
OS -5.56905922 -38.86291948
OS -5.56073818 -38.87124052
OS -5.55056802 -38.88048612
OS -5.53669962 -38.88973172
OS -5.5209821 -38.89805276
OS -5.50341546 -38.90452468
OS -5.49416986 -38.90544924
OS -5.4839997 -38.9063738
OS -5.47845234 -38.9063738
OS -5.4747541 -38.90544924
OS -5.4655085 -38.90360012
OS -5.45256466 -38.89990188
OS -5.43869626 -38.89342996
OS -5.42297874 -38.88418436
OS -5.41558226 -38.878637
OS -5.40818578 -38.87124052
OS -5.4007893 -38.86384404
OS -5.39339282 -38.85459844
OS -5.39339282 -38.85367388
OS -5.3915437 -38.85182476
OS -5.38969458 -38.84905108
OS -5.38784546 -38.84442828
OS -5.38414722 -38.83795636
OS -5.38137354 -38.82963532
OS -5.3776753 -38.82038972
OS -5.37397706 -38.809295
OS -5.37120338 -38.7954266
OS -5.36750514 -38.78063364
OS -5.3638069 -38.763067
OS -5.36103322 -38.7445758
OS -5.3591841 -38.72238636
OS -5.35733498 -38.69927236
OS -5.35548586 -38.67338468
OS -5.35548586 -38.64472332
OS -5.35548586 -38.64379876
OS -5.35548586 -38.6428742
OS -5.35548586 -38.6382514
OS -5.35548586 -38.62993036
OS -5.35641042 -38.61883564
OS -5.35641042 -38.60681636
OS -5.35733498 -38.5920234
OS -5.35825954 -38.57630588
OS -5.36010866 -38.55873924
OS -5.36473146 -38.52360596
OS -5.36750514 -38.50603932
OS -5.37120338 -38.48939724
OS -5.37490162 -38.47367972
OS -5.38044898 -38.45888676
OS -5.38599634 -38.44594292
OS -5.39246826 -38.4348482
OS -5.39246826 -38.43392364
OS -5.39431738 -38.43299908
OS -5.3961665 -38.4302254
OS -5.39894018 -38.42652716
OS -5.40726122 -38.41820612
OS -5.41743138 -38.40803596
OS -5.43129978 -38.39879036
OS -5.4470173 -38.39046932
OS -5.45533834 -38.38677108
OS -5.46458394 -38.3839974
OS -5.4747541 -38.38307284
OS -5.48492426 -38.38214828
OE
OB -2.99415962 -38.5504182 H
OS -2.99970698 -38.5504182
OS -3.00340522 -38.55134276
OS -3.01357538 -38.55226732
OS -3.02559466 -38.555041
OS -3.04038762 -38.5596638
OS -3.05610514 -38.56613572
OS -3.0708981 -38.57538132
OS -3.08569106 -38.5874006
OS -3.08754018 -38.58924972
OS -3.09123842 -38.59387252
OS -3.09771034 -38.60219356
OS -3.10418226 -38.61328828
OS -3.11157874 -38.62623212
OS -3.11805066 -38.6428742
OS -3.12359802 -38.66228996
OS -3.1263717 -38.68355484
OS -2.86657034 -38.68355484
OS -2.86657034 -38.68263028
OS -2.86657034 -38.68078116
OS -2.8674949 -38.67800748
OS -2.8674949 -38.67430924
OS -2.86934402 -38.66321452
OS -2.8721177 -38.65119524
OS -2.8767405 -38.63640228
OS -2.8813633 -38.62253388
OS -2.88875978 -38.60866548
OS -2.89708082 -38.5966462
OS -2.89708082 -38.59572164
OS -2.89892994 -38.59479708
OS -2.90355274 -38.58924972
OS -2.91187378 -38.58185324
OS -2.9229685 -38.5735322
OS -2.9368369 -38.56521116
OS -2.95347898 -38.55781468
OS -2.97289474 -38.55226732
OS -2.9830649 -38.55134276
OS -2.99415962 -38.5504182
OE
OB -1.39651994 -38.72700916 H
OS -1.3974445 -38.72700916
OS -1.39836906 -38.72793372
OS -1.40114274 -38.72885828
OS -1.40484098 -38.72978284
OS -1.40946378 -38.73163196
OS -1.41501114 -38.73348108
OS -1.42148306 -38.7353302
OS -1.42887954 -38.73717932
OS -1.43720058 -38.739953
OS -1.44737074 -38.74180212
OS -1.4575409 -38.7445758
OS -1.46956018 -38.74734948
OS -1.48250402 -38.75012316
OS -1.49544786 -38.75289684
OS -1.51024082 -38.75474596
OS -1.52595834 -38.75751964
OS -1.52780746 -38.75751964
OS -1.53335482 -38.7584442
OS -1.54260042 -38.76029332
OS -1.55277058 -38.76214244
OS -1.5638653 -38.76399156
OS -1.57496002 -38.76676524
OS -1.58513018 -38.76953892
OS -1.59437578 -38.77323716
OS -1.59530034 -38.77323716
OS -1.59807402 -38.77508628
OS -1.60177226 -38.7769354
OS -1.6054705 -38.77970908
OS -1.61656522 -38.78710556
OS -1.62581082 -38.79820028
OS -1.62581082 -38.79912484
OS -1.62765994 -38.80097396
OS -1.6285845 -38.8046722
OS -1.63043362 -38.809295
OS -1.63228274 -38.81484236
OS -1.63413186 -38.82038972
OS -1.63505642 -38.8277862
OS -1.63598098 -38.83518268
OS -1.63598098 -38.83610724
OS -1.63598098 -38.84073004
OS -1.63505642 -38.8462774
OS -1.6332073 -38.85367388
OS -1.63043362 -38.86199492
OS -1.62581082 -38.87031596
OS -1.62026346 -38.87956156
OS -1.61286698 -38.8878826
OS -1.61194242 -38.88880716
OS -1.60824418 -38.89065628
OS -1.60269682 -38.89435452
OS -1.59530034 -38.89805276
OS -1.58513018 -38.901751
OS -1.5731109 -38.90544924
OS -1.5592425 -38.90729836
OS -1.54260042 -38.90822292
OS -1.53520394 -38.90822292
OS -1.52595834 -38.90729836
OS -1.51578818 -38.90544924
OS -1.50284434 -38.90360012
OS -1.4899005 -38.89990188
OS -1.4760321 -38.89527908
OS -1.4621637 -38.88880716
OS -1.46031458 -38.8878826
OS -1.45661634 -38.88510892
OS -1.45014442 -38.88048612
OS -1.44274794 -38.8740142
OS -1.4344269 -38.86661772
OS -1.4251813 -38.85737212
OS -1.41778482 -38.8462774
OS -1.41038834 -38.83425812
OS -1.40946378 -38.83333356
OS -1.40853922 -38.82963532
OS -1.4066901 -38.8231634
OS -1.40391642 -38.81484236
OS -1.40114274 -38.80374764
OS -1.39929362 -38.7908038
OS -1.39836906 -38.77508628
OS -1.3974445 -38.75659508
OS -1.39651994 -38.72700916
OE
SE
S P 0
OB -4.66714078 -36.5016923 I
OS -4.65465922 -36.5016923
OS -4.62553558 -36.50307914
OS -4.5950251 -36.50723966
OS -4.56174094 -36.51140018
OS -4.53123046 -36.51833438
OS -4.51597522 -36.5224949
OS -4.50349366 -36.52665542
OS -4.50210682 -36.52665542
OS -4.50071998 -36.52804226
OS -4.49239894 -36.53220278
OS -4.47991738 -36.53775014
OS -4.46466214 -36.54745802
OS -4.44802006 -36.55993958
OS -4.42999114 -36.57658166
OS -4.41334906 -36.59599742
OS -4.39670698 -36.61818686
OS -4.39670698 -36.6195737
OS -4.39532014 -36.62096054
OS -4.38977278 -36.62928158
OS -4.38422542 -36.64314998
OS -4.37590438 -36.6611789
OS -4.36897018 -36.6819815
OS -4.36203598 -36.70694462
OS -4.35787546 -36.73329458
OS -4.35648862 -36.76241822
OS -4.35648862 -36.76380506
OS -4.35648862 -36.76657874
OS -4.35648862 -36.7721261
OS -4.35787546 -36.7790603
OS -4.35787546 -36.78876818
OS -4.3592623 -36.79847606
OS -4.36480966 -36.82205234
OS -4.3731307 -36.84978914
OS -4.38422542 -36.87891278
OS -4.4008675 -36.90803642
OS -4.41196222 -36.92190482
OS -4.42305694 -36.93577322
OS -4.42444378 -36.93716006
OS -4.42583062 -36.9385469
OS -4.42999114 -36.94270742
OS -4.4355385 -36.94686794
OS -4.4424727 -36.9524153
OS -4.45079374 -36.95796266
OS -4.46188846 -36.96489686
OS -4.47298318 -36.9732179
OS -4.48685158 -36.9801521
OS -4.50210682 -36.9870863
OS -4.5187489 -36.99540734
OS -4.53677782 -37.00234154
OS -4.55758042 -37.0078889
OS -4.57838302 -37.0148231
OS -4.6019593 -37.01898362
OS -4.62692242 -37.02314414
OS -4.62414874 -37.02453098
OS -4.61860138 -37.02730466
OS -4.61028034 -37.03285202
OS -4.59918562 -37.03839938
OS -4.5742225 -37.05365462
OS -4.56174094 -37.0633625
OS -4.55064622 -37.07168354
OS -4.54787254 -37.07445722
OS -4.54093834 -37.08139142
OS -4.52984362 -37.09248614
OS -4.51597522 -37.10635454
OS -4.50071998 -37.1257703
OS -4.48269106 -37.1465729
OS -4.46466214 -37.17153602
OS -4.44524638 -37.19927282
OS -4.28021242 -37.45999874
OS -4.43831218 -37.45999874
OS -4.56451462 -37.26029378
OS -4.56451462 -37.25890694
OS -4.5672883 -37.25613326
OS -4.57006198 -37.25197274
OS -4.5742225 -37.24642538
OS -4.58393038 -37.23117014
OS -4.59641194 -37.21175438
OS -4.61166718 -37.19095178
OS -4.62692242 -37.16876234
OS -4.64217766 -37.14795974
OS -4.65604606 -37.12854398
OS -4.6574329 -37.12715714
OS -4.66159342 -37.12160978
OS -4.66852762 -37.11328874
OS -4.6782355 -37.10358086
OS -4.6990381 -37.08277826
OS -4.71013282 -37.07307038
OS -4.72122754 -37.06474934
OS -4.72261438 -37.0633625
OS -4.72538806 -37.06197566
OS -4.73093542 -37.05920198
OS -4.73925646 -37.05504146
OS -4.7475775 -37.05088094
OS -4.75728538 -37.04672042
OS -4.77947482 -37.03978622
OS -4.78086166 -37.03978622
OS -4.78363534 -37.03839938
OS -4.7891827 -37.03839938
OS -4.7961169 -37.03701254
OS -4.80582478 -37.0356257
OS -4.8169195 -37.0356257
OS -4.83217474 -37.03423886
OS -4.99582186 -37.03423886
OS -4.99582186 -37.45999874
OS -5.12341114 -37.45999874
OS -5.12341114 -36.50030546
OS -4.6782355 -36.50030546
OS -4.66714078 -36.5016923
OE
OB -1.0100437 -37.45999874 I
OS -1.13208562 -37.45999874
OS -1.13208562 -36.65701838
OS -1.4122273 -37.45999874
OS -1.52594818 -37.45999874
OS -1.80331618 -36.64314998
OS -1.80331618 -37.45999874
OS -1.9253581 -37.45999874
OS -1.9253581 -36.50030546
OS -1.73536102 -36.50030546
OS -1.50791926 -37.1812439
OS -1.50791926 -37.18263074
OS -1.50653242 -37.18540442
OS -1.50514558 -37.18956494
OS -1.5023719 -37.19649914
OS -1.49682454 -37.21314122
OS -1.48989034 -37.23394382
OS -1.48295614 -37.2575201
OS -1.4746351 -37.28109638
OS -1.4677009 -37.30328582
OS -1.46215354 -37.32270158
OS -1.4607667 -37.3199279
OS -1.45937986 -37.3129937
OS -1.45521934 -37.30051214
OS -1.44967198 -37.28387006
OS -1.44273778 -37.26168062
OS -1.4330299 -37.23533066
OS -1.42332202 -37.20482018
OS -1.41084046 -37.16876234
OS -1.18062502 -36.50030546
OS -1.0100437 -36.50030546
OS -1.0100437 -37.45999874
OE
OB -2.02382374 -37.45999874 I
OS -2.1680551 -37.45999874
OS -2.28038914 -37.16876234
OS -2.68257274 -37.16876234
OS -2.78658574 -37.45999874
OS -2.92110922 -37.45999874
OS -2.55498346 -36.50030546
OS -2.41629946 -36.50030546
OS -2.02382374 -37.45999874
OE
OB -3.02928274 -37.45999874 I
OS -3.16103254 -37.45999874
OS -3.66306862 -36.70694462
OS -3.66306862 -37.45999874
OS -3.78511054 -37.45999874
OS -3.78511054 -36.50030546
OS -3.65474758 -36.50030546
OS -3.15132466 -37.25474642
OS -3.15132466 -36.50030546
OS -3.02928274 -36.50030546
OS -3.02928274 -37.45999874
OE
OB -5.3231161 -36.61402634 I
OS -5.89033366 -36.61402634
OS -5.89033366 -36.90664958
OS -5.35917394 -36.90664958
OS -5.35917394 -37.02037046
OS -5.89033366 -37.02037046
OS -5.89033366 -37.34627786
OS -5.30092666 -37.34627786
OS -5.30092666 -37.45999874
OS -6.01792294 -37.45999874
OS -6.01792294 -36.50030546
OS -5.3231161 -36.50030546
OS -5.3231161 -36.61402634
OE
OB -0.10721086 -36.61402634 I
OS -0.67442842 -36.61402634
OS -0.67442842 -36.90664958
OS -0.1432687 -36.90664958
OS -0.1432687 -37.02037046
OS -0.67442842 -37.02037046
OS -0.67442842 -37.34627786
OS -0.08502142 -37.34627786
OS -0.08502142 -37.45999874
OS -0.8020177 -37.45999874
OS -0.8020177 -36.50030546
OS -0.10721086 -36.50030546
OS -0.10721086 -36.61402634
OE
OB -8.43241138 -37.34627786 I
OS -7.95949894 -37.34627786
OS -7.95949894 -37.45999874
OS -8.56000066 -37.45999874
OS -8.56000066 -36.50030546
OS -8.43241138 -36.50030546
OS -8.43241138 -37.34627786
OE
OB -6.51718534 -37.05365462 I
OS -6.51718534 -37.45999874
OS -6.64477462 -37.45999874
OS -6.64477462 -37.05365462
OS -7.0150609 -36.50030546
OS -6.86112166 -36.50030546
OS -6.67251142 -36.79154186
OS -6.67251142 -36.7929287
OS -6.66973774 -36.79570238
OS -6.66696406 -36.7998629
OS -6.66419038 -36.80541026
OS -6.65864302 -36.81234446
OS -6.65309566 -36.8206655
OS -6.6406141 -36.8414681
OS -6.62535886 -36.86643122
OS -6.60871678 -36.89416802
OS -6.59068786 -36.92329166
OS -6.57404578 -36.95380214
OS -6.57404578 -36.9524153
OS -6.57265894 -36.94964162
OS -6.56988526 -36.9454811
OS -6.56572474 -36.93993374
OS -6.56156422 -36.93299954
OS -6.55601686 -36.9246785
OS -6.5435353 -36.9038759
OS -6.52828006 -36.87891278
OS -6.51025114 -36.84978914
OS -6.48944854 -36.81789182
OS -6.4672591 -36.78322082
OS -6.28280938 -36.50030546
OS -6.1344175 -36.50030546
OS -6.51718534 -37.05365462
OE
OB -7.01644774 -37.45999874 I
OS -7.1606791 -37.45999874
OS -7.27301314 -37.16876234
OS -7.67519674 -37.16876234
OS -7.77920974 -37.45999874
OS -7.91373322 -37.45999874
OS -7.54760746 -36.50030546
OS -7.40892346 -36.50030546
OS -7.01644774 -37.45999874
OE
OB -7.48103914 -36.60015794 H
OS -7.48103914 -36.60154478
OS -7.48242598 -36.60431846
OS -7.48242598 -36.60986582
OS -7.48519966 -36.61541318
OS -7.4865865 -36.62512106
OS -7.48936018 -36.63482894
OS -7.49490754 -36.65840522
OS -7.50184174 -36.68614202
OS -7.51154962 -36.7166525
OS -7.5212575 -36.74993666
OS -7.53373906 -36.78460766
OS -7.63775206 -37.06474934
OS -7.3132315 -37.06474934
OS -7.41308398 -36.80124974
OS -7.41308398 -36.7998629
OS -7.41447082 -36.79570238
OS -7.4172445 -36.78876818
OS -7.42001818 -36.78044714
OS -7.4241787 -36.77073926
OS -7.42833922 -36.7582577
OS -7.43249974 -36.7443893
OS -7.4380471 -36.7305209
OS -7.44914182 -36.69862358
OS -7.46023654 -36.66533942
OS -7.47133126 -36.63205526
OS -7.48103914 -36.60015794
OE
OB -4.69349074 -36.60709214 H
OS -4.99582186 -36.60709214
OS -4.99582186 -36.9246785
OS -4.71013282 -36.9246785
OS -4.69349074 -36.92329166
OS -4.67407498 -36.92190482
OS -4.65188554 -36.92051798
OS -4.6296961 -36.9177443
OS -4.60750666 -36.91358378
OS -4.5880909 -36.90803642
OS -4.58531722 -36.90664958
OS -4.57976986 -36.9038759
OS -4.57144882 -36.89971538
OS -4.5603541 -36.89416802
OS -4.54787254 -36.88584698
OS -4.53539098 -36.8761391
OS -4.52290942 -36.86365754
OS -4.51320154 -36.84978914
OS -4.5118147 -36.8484023
OS -4.50904102 -36.84285494
OS -4.5048805 -36.8345339
OS -4.49933314 -36.82343918
OS -4.49517262 -36.81095762
OS -4.4910121 -36.79708922
OS -4.48823842 -36.78044714
OS -4.48685158 -36.76380506
OS -4.48685158 -36.76241822
OS -4.48685158 -36.76103138
OS -4.48823842 -36.75271034
OS -4.48962526 -36.74022878
OS -4.49239894 -36.7235867
OS -4.49933314 -36.70694462
OS -4.50765418 -36.68752886
OS -4.52013574 -36.66949994
OS -4.53677782 -36.65147102
OS -4.5395515 -36.65008418
OS -4.5464857 -36.64453682
OS -4.55758042 -36.63760262
OS -4.57560934 -36.62928158
OS -4.59641194 -36.62096054
OS -4.62414874 -36.61402634
OS -4.65604606 -36.60847898
OS -4.69349074 -36.60709214
OE
OB -2.48841514 -36.60015794 H
OS -2.48841514 -36.60154478
OS -2.48980198 -36.60431846
OS -2.48980198 -36.60986582
OS -2.49257566 -36.61541318
OS -2.4939625 -36.62512106
OS -2.49673618 -36.63482894
OS -2.50228354 -36.65840522
OS -2.50921774 -36.68614202
OS -2.51892562 -36.7166525
OS -2.5286335 -36.74993666
OS -2.54111506 -36.78460766
OS -2.64512806 -37.06474934
OS -2.3206075 -37.06474934
OS -2.42045998 -36.80124974
OS -2.42045998 -36.7998629
OS -2.42184682 -36.79570238
OS -2.4246205 -36.78876818
OS -2.42739418 -36.78044714
OS -2.4315547 -36.77073926
OS -2.43571522 -36.7582577
OS -2.43987574 -36.7443893
OS -2.4454231 -36.7305209
OS -2.45651782 -36.69862358
OS -2.46761254 -36.66533942
OS -2.47870726 -36.63205526
OS -2.48841514 -36.60015794
OE
SE
S P 0
OB 35.73690338 -37.45999874 I
OS 35.61486146 -37.45999874
OS 35.61486146 -36.65701838
OS 35.33471978 -37.45999874
OS 35.2209989 -37.45999874
OS 34.9436309 -36.64314998
OS 34.9436309 -37.45999874
OS 34.82158898 -37.45999874
OS 34.82158898 -36.50030546
OS 35.01158606 -36.50030546
OS 35.23902782 -37.1812439
OS 35.23902782 -37.18263074
OS 35.24041466 -37.18540442
OS 35.2418015 -37.18956494
OS 35.24457518 -37.19649914
OS 35.25012254 -37.21314122
OS 35.25705674 -37.23394382
OS 35.26399094 -37.2575201
OS 35.27231198 -37.28109638
OS 35.27924618 -37.30328582
OS 35.28479354 -37.32270158
OS 35.28618038 -37.3199279
OS 35.28756722 -37.3129937
OS 35.29172774 -37.30051214
OS 35.2972751 -37.28387006
OS 35.3042093 -37.26168062
OS 35.31391718 -37.23533066
OS 35.32362506 -37.20482018
OS 35.33610662 -37.16876234
OS 35.56632206 -36.50030546
OS 35.73690338 -36.50030546
OS 35.73690338 -37.45999874
OE
OB 34.61356298 -37.05504146 I
OS 34.61356298 -37.0564283
OS 34.61356298 -37.06197566
OS 34.61356298 -37.06890986
OS 34.61356298 -37.07861774
OS 34.61217614 -37.0910993
OS 34.61217614 -37.1049677
OS 34.6107893 -37.12160978
OS 34.60940246 -37.13825186
OS 34.60524194 -37.17569654
OS 34.59969458 -37.21452806
OS 34.59137354 -37.25197274
OS 34.58582618 -37.27000166
OS 34.58027882 -37.28664374
OS 34.58027882 -37.28803058
OS 34.57889198 -37.29080426
OS 34.5761183 -37.29496478
OS 34.57334462 -37.30051214
OS 34.56502358 -37.31576738
OS 34.55254202 -37.33518314
OS 34.53589994 -37.35737258
OS 34.51648418 -37.37956202
OS 34.49152106 -37.4031383
OS 34.46101058 -37.4239409
OS 34.45962374 -37.4239409
OS 34.45685006 -37.42671458
OS 34.45268954 -37.42810142
OS 34.44575534 -37.43226194
OS 34.4374343 -37.43642246
OS 34.42633958 -37.44058298
OS 34.41524486 -37.4447435
OS 34.40137646 -37.45029086
OS 34.38612122 -37.45583822
OS 34.36947914 -37.45999874
OS 34.35145022 -37.46415926
OS 34.33064762 -37.46831978
OS 34.30984502 -37.47109346
OS 34.28765558 -37.47386714
OS 34.23772934 -37.47664082
OS 34.22524778 -37.47664082
OS 34.2155399 -37.47525398
OS 34.20444518 -37.47525398
OS 34.19057678 -37.47386714
OS 34.17532154 -37.4724803
OS 34.1600663 -37.47109346
OS 34.1253953 -37.4655461
OS 34.08795062 -37.45722506
OS 34.05189278 -37.44613034
OS 34.01722178 -37.4308751
OS 34.01583494 -37.4308751
OS 34.01306126 -37.42810142
OS 34.00890074 -37.42532774
OS 34.00335338 -37.42255406
OS 33.98809814 -37.41145934
OS 33.97006922 -37.3962041
OS 33.94926662 -37.37678834
OS 33.92985086 -37.3545989
OS 33.9104351 -37.3268621
OS 33.89517986 -37.29635162
OS 33.89517986 -37.29496478
OS 33.89379302 -37.2921911
OS 33.89240618 -37.28664374
OS 33.8896325 -37.27970954
OS 33.88685882 -37.2713885
OS 33.88408514 -37.26029378
OS 33.87992462 -37.24781222
OS 33.87715094 -37.23255698
OS 33.87437726 -37.2159149
OS 33.87021674 -37.19788598
OS 33.86744306 -37.17847022
OS 33.86466938 -37.15766762
OS 33.8618957 -37.13409134
OS 33.86050886 -37.10912822
OS 33.85912202 -37.08277826
OS 33.85912202 -37.05504146
OS 33.85912202 -36.50030546
OS 33.9867113 -36.50030546
OS 33.9867113 -37.05504146
OS 33.9867113 -37.0564283
OS 33.9867113 -37.06058882
OS 33.9867113 -37.06752302
OS 33.9867113 -37.07584406
OS 33.98809814 -37.08555194
OS 33.98809814 -37.0980335
OS 33.98948498 -37.12438346
OS 33.99225866 -37.15489394
OS 33.99641918 -37.18540442
OS 34.00196654 -37.21452806
OS 34.00474022 -37.22700962
OS 34.00890074 -37.23949118
OS 34.01028758 -37.24226486
OS 34.01306126 -37.24919906
OS 34.01999546 -37.25890694
OS 34.0283165 -37.27277534
OS 34.03802438 -37.28664374
OS 34.05189278 -37.30189898
OS 34.06853486 -37.31715422
OS 34.08795062 -37.32963578
OS 34.0907243 -37.33102262
OS 34.0976585 -37.33518314
OS 34.11014006 -37.33934366
OS 34.12678214 -37.34489102
OS 34.1461979 -37.35182522
OS 34.17116102 -37.35598574
OS 34.19751098 -37.36014626
OS 34.22663462 -37.3615331
OS 34.24050302 -37.3615331
OS 34.24882406 -37.36014626
OS 34.26130562 -37.36014626
OS 34.27378718 -37.35875942
OS 34.30429766 -37.35321206
OS 34.33758182 -37.34627786
OS 34.36947914 -37.33518314
OS 34.39998962 -37.3199279
OS 34.41385802 -37.31022002
OS 34.42633958 -37.2991253
OS 34.42772642 -37.29773846
OS 34.42911326 -37.29635162
OS 34.43188694 -37.2921911
OS 34.43604746 -37.28664374
OS 34.44020798 -37.2783227
OS 34.44575534 -37.27000166
OS 34.4513027 -37.2575201
OS 34.45685006 -37.24503854
OS 34.46239742 -37.2297833
OS 34.46655794 -37.21175438
OS 34.4721053 -37.19095178
OS 34.47626582 -37.16876234
OS 34.48042634 -37.14379922
OS 34.48320002 -37.11744926
OS 34.4859737 -37.08693878
OS 34.4859737 -37.05504146
OS 34.4859737 -36.50030546
OS 34.61356298 -36.50030546
OS 34.61356298 -37.05504146
OE
OB 33.64416182 -37.45999874 I
OS 33.51241202 -37.45999874
OS 33.01037594 -36.70694462
OS 33.01037594 -37.45999874
OS 32.88833402 -37.45999874
OS 32.88833402 -36.50030546
OS 33.01869698 -36.50030546
OS 33.5221199 -37.25474642
OS 33.5221199 -36.50030546
OS 33.64416182 -36.50030546
OS 33.64416182 -37.45999874
OE
OB 38.19022334 -36.5016923 I
OS 38.2027049 -36.5016923
OS 38.23182854 -36.50307914
OS 38.26233902 -36.50723966
OS 38.29562318 -36.51140018
OS 38.32613366 -36.51833438
OS 38.3413889 -36.5224949
OS 38.35387046 -36.52665542
OS 38.3552573 -36.52665542
OS 38.35664414 -36.52804226
OS 38.36496518 -36.53220278
OS 38.37744674 -36.53775014
OS 38.39270198 -36.54745802
OS 38.40934406 -36.55993958
OS 38.42737298 -36.57658166
OS 38.44401506 -36.59599742
OS 38.46065714 -36.61818686
OS 38.46065714 -36.6195737
OS 38.46204398 -36.62096054
OS 38.46759134 -36.62928158
OS 38.4731387 -36.64314998
OS 38.48145974 -36.6611789
OS 38.48839394 -36.6819815
OS 38.49532814 -36.70694462
OS 38.49948866 -36.73329458
OS 38.5008755 -36.76241822
OS 38.5008755 -36.76380506
OS 38.5008755 -36.76657874
OS 38.5008755 -36.7721261
OS 38.49948866 -36.7790603
OS 38.49948866 -36.78876818
OS 38.49810182 -36.79847606
OS 38.49255446 -36.82205234
OS 38.48423342 -36.84978914
OS 38.4731387 -36.87891278
OS 38.45649662 -36.90803642
OS 38.4454019 -36.92190482
OS 38.43430718 -36.93577322
OS 38.43292034 -36.93716006
OS 38.4315335 -36.9385469
OS 38.42737298 -36.94270742
OS 38.42182562 -36.94686794
OS 38.41489142 -36.9524153
OS 38.40657038 -36.95796266
OS 38.39547566 -36.96489686
OS 38.38438094 -36.9732179
OS 38.37051254 -36.9801521
OS 38.3552573 -36.9870863
OS 38.33861522 -36.99540734
OS 38.3205863 -37.00234154
OS 38.2997837 -37.0078889
OS 38.2789811 -37.0148231
OS 38.25540482 -37.01898362
OS 38.2304417 -37.02314414
OS 38.23321538 -37.02453098
OS 38.23876274 -37.02730466
OS 38.24708378 -37.03285202
OS 38.2581785 -37.03839938
OS 38.28314162 -37.05365462
OS 38.29562318 -37.0633625
OS 38.3067179 -37.07168354
OS 38.30949158 -37.07445722
OS 38.31642578 -37.08139142
OS 38.3275205 -37.09248614
OS 38.3413889 -37.10635454
OS 38.35664414 -37.1257703
OS 38.37467306 -37.1465729
OS 38.39270198 -37.17153602
OS 38.41211774 -37.19927282
OS 38.5771517 -37.45999874
OS 38.41905194 -37.45999874
OS 38.2928495 -37.26029378
OS 38.2928495 -37.25890694
OS 38.29007582 -37.25613326
OS 38.28730214 -37.25197274
OS 38.28314162 -37.24642538
OS 38.27343374 -37.23117014
OS 38.26095218 -37.21175438
OS 38.24569694 -37.19095178
OS 38.2304417 -37.16876234
OS 38.21518646 -37.14795974
OS 38.20131806 -37.12854398
OS 38.19993122 -37.12715714
OS 38.1957707 -37.12160978
OS 38.1888365 -37.11328874
OS 38.17912862 -37.10358086
OS 38.15832602 -37.08277826
OS 38.1472313 -37.07307038
OS 38.13613658 -37.06474934
OS 38.13474974 -37.0633625
OS 38.13197606 -37.06197566
OS 38.1264287 -37.05920198
OS 38.11810766 -37.05504146
OS 38.10978662 -37.05088094
OS 38.10007874 -37.04672042
OS 38.0778893 -37.03978622
OS 38.07650246 -37.03978622
OS 38.07372878 -37.03839938
OS 38.06818142 -37.03839938
OS 38.06124722 -37.03701254
OS 38.05153934 -37.0356257
OS 38.04044462 -37.0356257
OS 38.02518938 -37.03423886
OS 37.86154226 -37.03423886
OS 37.86154226 -37.45999874
OS 37.73395298 -37.45999874
OS 37.73395298 -36.50030546
OS 38.17912862 -36.50030546
OS 38.19022334 -36.5016923
OE
OB 37.53424802 -36.61402634 I
OS 36.96703046 -36.61402634
OS 36.96703046 -36.90664958
OS 37.49819018 -36.90664958
OS 37.49819018 -37.02037046
OS 36.96703046 -37.02037046
OS 36.96703046 -37.34627786
OS 37.55643746 -37.34627786
OS 37.55643746 -37.45999874
OS 36.83944118 -37.45999874
OS 36.83944118 -36.50030546
OS 37.53424802 -36.50030546
OS 37.53424802 -36.61402634
OE
OB 36.32492354 -36.5016923 I
OS 36.33601826 -36.5016923
OS 36.36098138 -36.50446598
OS 36.38871818 -36.50723966
OS 36.41784182 -36.51278702
OS 36.44696546 -36.51972122
OS 36.47331542 -36.5294291
OS 36.47470226 -36.5294291
OS 36.4760891 -36.53081594
OS 36.48441014 -36.53497646
OS 36.4968917 -36.54191066
OS 36.5107601 -36.55161854
OS 36.52740218 -36.5641001
OS 36.5454311 -36.57935534
OS 36.56207318 -36.5987711
OS 36.57732842 -36.6195737
OS 36.57871526 -36.62234738
OS 36.58287578 -36.63066842
OS 36.58980998 -36.64176314
OS 36.59674418 -36.65840522
OS 36.60367838 -36.67782098
OS 36.61061258 -36.69862358
OS 36.6147731 -36.72219986
OS 36.61615994 -36.74577614
OS 36.61615994 -36.74854982
OS 36.61615994 -36.75548402
OS 36.6147731 -36.76796558
OS 36.61199942 -36.78322082
OS 36.6078389 -36.80124974
OS 36.6009047 -36.8206655
OS 36.59258366 -36.84008126
OS 36.58148894 -36.86088386
OS 36.5801021 -36.86365754
OS 36.57594158 -36.8692049
OS 36.56762054 -36.88029962
OS 36.55652582 -36.89139434
OS 36.54265742 -36.90526274
OS 36.52601534 -36.92051798
OS 36.50521274 -36.93438638
OS 36.48163646 -36.94825478
OS 36.4830233 -36.94825478
OS 36.48579698 -36.94964162
OS 36.4899575 -36.95102846
OS 36.49550486 -36.95380214
OS 36.51214694 -36.9593495
OS 36.5315627 -36.96905738
OS 36.5523653 -36.98153894
OS 36.57594158 -36.99679418
OS 36.59674418 -37.0148231
OS 36.61615994 -37.03701254
OS 36.61754678 -37.03978622
OS 36.62309414 -37.04810726
OS 36.63141518 -37.06058882
OS 36.63973622 -37.0772309
OS 36.64805726 -37.09942034
OS 36.6563783 -37.12299662
OS 36.66192566 -37.15073342
OS 36.6633125 -37.1812439
OS 36.6633125 -37.18263074
OS 36.6633125 -37.18401758
OS 36.6633125 -37.19233862
OS 36.66192566 -37.20620702
OS 36.65915198 -37.2228491
OS 36.6563783 -37.24226486
OS 36.65083094 -37.26306746
OS 36.64389674 -37.2852569
OS 36.63418886 -37.30744634
OS 36.63280202 -37.31022002
OS 36.6286415 -37.31715422
OS 36.62309414 -37.3268621
OS 36.6147731 -37.3407305
OS 36.60367838 -37.3545989
OS 36.59258366 -37.36985414
OS 36.57871526 -37.38510938
OS 36.56346002 -37.39759094
OS 36.56207318 -37.39897778
OS 36.55652582 -37.4031383
OS 36.54681794 -37.40868566
OS 36.53433638 -37.41423302
OS 36.51908114 -37.42255406
OS 36.50105222 -37.4308751
OS 36.48163646 -37.4378093
OS 36.45806018 -37.4447435
OS 36.4552865 -37.4447435
OS 36.44696546 -37.44751718
OS 36.43309706 -37.44890402
OS 36.41506814 -37.4516777
OS 36.3928787 -37.45445138
OS 36.36652874 -37.45722506
OS 36.3374051 -37.4586119
OS 36.30412094 -37.45999874
OS 35.93799518 -37.45999874
OS 35.93799518 -36.50030546
OS 36.31521566 -36.50030546
OS 36.32492354 -36.5016923
OE
OB 32.3849111 -36.61402634 I
OS 32.06871158 -36.61402634
OS 32.06871158 -37.45999874
OS 31.9411223 -37.45999874
OS 31.9411223 -36.61402634
OS 31.62492278 -36.61402634
OS 31.62492278 -36.50030546
OS 32.3849111 -36.50030546
OS 32.3849111 -36.61402634
OE
OB 30.62639798 -37.45999874 I
OS 30.48216662 -37.45999874
OS 30.36983258 -37.16876234
OS 29.96764898 -37.16876234
OS 29.86363598 -37.45999874
OS 29.7291125 -37.45999874
OS 30.09523826 -36.50030546
OS 30.23392226 -36.50030546
OS 30.62639798 -37.45999874
OE
OB 29.3546657 -36.5016923 I
OS 29.37824198 -36.50307914
OS 29.4032051 -36.50446598
OS 29.42678138 -36.50723966
OS 29.44758398 -36.51001334
OS 29.45035766 -36.51001334
OS 29.46006554 -36.51278702
OS 29.4725471 -36.5155607
OS 29.48918918 -36.51972122
OS 29.5072181 -36.52665542
OS 29.52663386 -36.53497646
OS 29.54743646 -36.54468434
OS 29.56546538 -36.55577906
OS 29.56823906 -36.5571659
OS 29.57378642 -36.56132642
OS 29.58210746 -36.56964746
OS 29.59320218 -36.57935534
OS 29.60568374 -36.5918369
OS 29.6181653 -36.60847898
OS 29.6320337 -36.6265079
OS 29.64312842 -36.6473105
OS 29.64451526 -36.65008418
OS 29.64728894 -36.65701838
OS 29.6528363 -36.66949994
OS 29.65838366 -36.68614202
OS 29.66254418 -36.70555778
OS 29.66809154 -36.72774722
OS 29.67086522 -36.75271034
OS 29.67225206 -36.7790603
OS 29.67225206 -36.78044714
OS 29.67225206 -36.78460766
OS 29.67225206 -36.79015502
OS 29.67086522 -36.7998629
OS 29.66947838 -36.80957078
OS 29.66809154 -36.82205234
OS 29.66531786 -36.83592074
OS 29.66254418 -36.85117598
OS 29.6528363 -36.8830733
OS 29.64728894 -36.89971538
OS 29.6389679 -36.9177443
OS 29.62926002 -36.93577322
OS 29.61955214 -36.9524153
OS 29.60707058 -36.96905738
OS 29.59320218 -36.98569946
OS 29.59181534 -36.9870863
OS 29.58904166 -36.98985998
OS 29.58488114 -36.9940205
OS 29.57794694 -36.99818102
OS 29.5696259 -37.00511522
OS 29.55853118 -37.01204942
OS 29.54466278 -37.02037046
OS 29.52940754 -37.02730466
OS 29.51137862 -37.0356257
OS 29.49057602 -37.04394674
OS 29.46838658 -37.05088094
OS 29.44203662 -37.0564283
OS 29.41429982 -37.06197566
OS 29.38378934 -37.06613618
OS 29.34911834 -37.06890986
OS 29.3130605 -37.0702967
OS 29.06758982 -37.0702967
OS 29.06758982 -37.45999874
OS 28.94000054 -37.45999874
OS 28.94000054 -36.50030546
OS 29.3338631 -36.50030546
OS 29.3546657 -36.5016923
OE
OB 31.18668134 -36.5016923 I
OS 31.1991629 -36.5016923
OS 31.22828654 -36.50307914
OS 31.25879702 -36.50723966
OS 31.29208118 -36.51140018
OS 31.32259166 -36.51833438
OS 31.3378469 -36.5224949
OS 31.35032846 -36.52665542
OS 31.3517153 -36.52665542
OS 31.35310214 -36.52804226
OS 31.36142318 -36.53220278
OS 31.37390474 -36.53775014
OS 31.38915998 -36.54745802
OS 31.40580206 -36.55993958
OS 31.42383098 -36.57658166
OS 31.44047306 -36.59599742
OS 31.45711514 -36.61818686
OS 31.45711514 -36.6195737
OS 31.45850198 -36.62096054
OS 31.46404934 -36.62928158
OS 31.4695967 -36.64314998
OS 31.47791774 -36.6611789
OS 31.48485194 -36.6819815
OS 31.49178614 -36.70694462
OS 31.49594666 -36.73329458
OS 31.4973335 -36.76241822
OS 31.4973335 -36.76380506
OS 31.4973335 -36.76657874
OS 31.4973335 -36.7721261
OS 31.49594666 -36.7790603
OS 31.49594666 -36.78876818
OS 31.49455982 -36.79847606
OS 31.48901246 -36.82205234
OS 31.48069142 -36.84978914
OS 31.4695967 -36.87891278
OS 31.45295462 -36.90803642
OS 31.4418599 -36.92190482
OS 31.43076518 -36.93577322
OS 31.42937834 -36.93716006
OS 31.4279915 -36.9385469
OS 31.42383098 -36.94270742
OS 31.41828362 -36.94686794
OS 31.41134942 -36.9524153
OS 31.40302838 -36.95796266
OS 31.39193366 -36.96489686
OS 31.38083894 -36.9732179
OS 31.36697054 -36.9801521
OS 31.3517153 -36.9870863
OS 31.33507322 -36.99540734
OS 31.3170443 -37.00234154
OS 31.2962417 -37.0078889
OS 31.2754391 -37.0148231
OS 31.25186282 -37.01898362
OS 31.2268997 -37.02314414
OS 31.22967338 -37.02453098
OS 31.23522074 -37.02730466
OS 31.24354178 -37.03285202
OS 31.2546365 -37.03839938
OS 31.27959962 -37.05365462
OS 31.29208118 -37.0633625
OS 31.3031759 -37.07168354
OS 31.30594958 -37.07445722
OS 31.31288378 -37.08139142
OS 31.3239785 -37.09248614
OS 31.3378469 -37.10635454
OS 31.35310214 -37.1257703
OS 31.37113106 -37.1465729
OS 31.38915998 -37.17153602
OS 31.40857574 -37.19927282
OS 31.5736097 -37.45999874
OS 31.41550994 -37.45999874
OS 31.2893075 -37.26029378
OS 31.2893075 -37.25890694
OS 31.28653382 -37.25613326
OS 31.28376014 -37.25197274
OS 31.27959962 -37.24642538
OS 31.26989174 -37.23117014
OS 31.25741018 -37.21175438
OS 31.24215494 -37.19095178
OS 31.2268997 -37.16876234
OS 31.21164446 -37.14795974
OS 31.19777606 -37.12854398
OS 31.19638922 -37.12715714
OS 31.1922287 -37.12160978
OS 31.1852945 -37.11328874
OS 31.17558662 -37.10358086
OS 31.15478402 -37.08277826
OS 31.1436893 -37.07307038
OS 31.13259458 -37.06474934
OS 31.13120774 -37.0633625
OS 31.12843406 -37.06197566
OS 31.1228867 -37.05920198
OS 31.11456566 -37.05504146
OS 31.10624462 -37.05088094
OS 31.09653674 -37.04672042
OS 31.0743473 -37.03978622
OS 31.07296046 -37.03978622
OS 31.07018678 -37.03839938
OS 31.06463942 -37.03839938
OS 31.05770522 -37.03701254
OS 31.04799734 -37.0356257
OS 31.03690262 -37.0356257
OS 31.02164738 -37.03423886
OS 30.85800026 -37.03423886
OS 30.85800026 -37.45999874
OS 30.73041098 -37.45999874
OS 30.73041098 -36.50030546
OS 31.17558662 -36.50030546
OS 31.18668134 -36.5016923
OE
OB 38.16387338 -36.60709214 H
OS 37.86154226 -36.60709214
OS 37.86154226 -36.9246785
OS 38.1472313 -36.9246785
OS 38.16387338 -36.92329166
OS 38.18328914 -36.92190482
OS 38.20547858 -36.92051798
OS 38.22766802 -36.9177443
OS 38.24985746 -36.91358378
OS 38.26927322 -36.90803642
OS 38.2720469 -36.90664958
OS 38.27759426 -36.9038759
OS 38.2859153 -36.89971538
OS 38.29701002 -36.89416802
OS 38.30949158 -36.88584698
OS 38.32197314 -36.8761391
OS 38.3344547 -36.86365754
OS 38.34416258 -36.84978914
OS 38.34554942 -36.8484023
OS 38.3483231 -36.84285494
OS 38.35248362 -36.8345339
OS 38.35803098 -36.82343918
OS 38.3621915 -36.81095762
OS 38.36635202 -36.79708922
OS 38.3691257 -36.78044714
OS 38.37051254 -36.76380506
OS 38.37051254 -36.76241822
OS 38.37051254 -36.76103138
OS 38.3691257 -36.75271034
OS 38.36773886 -36.74022878
OS 38.36496518 -36.7235867
OS 38.35803098 -36.70694462
OS 38.34970994 -36.68752886
OS 38.33722838 -36.66949994
OS 38.3205863 -36.65147102
OS 38.31781262 -36.65008418
OS 38.31087842 -36.64453682
OS 38.2997837 -36.63760262
OS 38.28175478 -36.62928158
OS 38.26095218 -36.62096054
OS 38.23321538 -36.61402634
OS 38.20131806 -36.60847898
OS 38.16387338 -36.60709214
OE
OB 29.34218414 -36.61402634 H
OS 29.06758982 -36.61402634
OS 29.06758982 -36.95657582
OS 29.32554206 -36.95657582
OS 29.33524994 -36.95518898
OS 29.34495782 -36.95518898
OS 29.35605254 -36.95380214
OS 29.3824025 -36.95102846
OS 29.41152614 -36.9454811
OS 29.44064978 -36.93716006
OS 29.46699974 -36.92606534
OS 29.4794813 -36.91913114
OS 29.48918918 -36.9108101
OS 29.49196286 -36.90803642
OS 29.49751022 -36.90248906
OS 29.50583126 -36.89139434
OS 29.51553914 -36.87752594
OS 29.52524702 -36.85949702
OS 29.53356806 -36.83730758
OS 29.53911542 -36.81234446
OS 29.5418891 -36.78322082
OS 29.5418891 -36.78183398
OS 29.5418891 -36.78044714
OS 29.5418891 -36.77351294
OS 29.54050226 -36.76103138
OS 29.53772858 -36.74716298
OS 29.5349549 -36.73190774
OS 29.52940754 -36.71387882
OS 29.5210865 -36.69723674
OS 29.51137862 -36.68059466
OS 29.50999178 -36.67920782
OS 29.50583126 -36.67366046
OS 29.49889706 -36.66672626
OS 29.49057602 -36.65701838
OS 29.47809446 -36.6473105
OS 29.46422606 -36.63898946
OS 29.44897082 -36.63066842
OS 29.4309419 -36.62373422
OS 29.42955506 -36.62373422
OS 29.4240077 -36.62234738
OS 29.41568666 -36.62096054
OS 29.40459194 -36.61818686
OS 29.38794986 -36.61680002
OS 29.36714726 -36.61541318
OS 29.34218414 -36.61402634
OE
OB 30.16180658 -36.60015794 H
OS 30.16180658 -36.60154478
OS 30.16041974 -36.60431846
OS 30.16041974 -36.60986582
OS 30.15764606 -36.61541318
OS 30.15625922 -36.62512106
OS 30.15348554 -36.63482894
OS 30.14793818 -36.65840522
OS 30.14100398 -36.68614202
OS 30.1312961 -36.7166525
OS 30.12158822 -36.74993666
OS 30.10910666 -36.78460766
OS 30.00509366 -37.06474934
OS 30.32961422 -37.06474934
OS 30.22976174 -36.80124974
OS 30.22976174 -36.7998629
OS 30.2283749 -36.79570238
OS 30.22560122 -36.78876818
OS 30.22282754 -36.78044714
OS 30.21866702 -36.77073926
OS 30.2145065 -36.7582577
OS 30.21034598 -36.7443893
OS 30.20479862 -36.7305209
OS 30.1937039 -36.69862358
OS 30.18260918 -36.66533942
OS 30.17151446 -36.63205526
OS 30.16180658 -36.60015794
OE
OB 31.16033138 -36.60709214 H
OS 30.85800026 -36.60709214
OS 30.85800026 -36.9246785
OS 31.1436893 -36.9246785
OS 31.16033138 -36.92329166
OS 31.17974714 -36.92190482
OS 31.20193658 -36.92051798
OS 31.22412602 -36.9177443
OS 31.24631546 -36.91358378
OS 31.26573122 -36.90803642
OS 31.2685049 -36.90664958
OS 31.27405226 -36.9038759
OS 31.2823733 -36.89971538
OS 31.29346802 -36.89416802
OS 31.30594958 -36.88584698
OS 31.31843114 -36.8761391
OS 31.3309127 -36.86365754
OS 31.34062058 -36.84978914
OS 31.34200742 -36.8484023
OS 31.3447811 -36.84285494
OS 31.34894162 -36.8345339
OS 31.35448898 -36.82343918
OS 31.3586495 -36.81095762
OS 31.36281002 -36.79708922
OS 31.3655837 -36.78044714
OS 31.36697054 -36.76380506
OS 31.36697054 -36.76241822
OS 31.36697054 -36.76103138
OS 31.3655837 -36.75271034
OS 31.36419686 -36.74022878
OS 31.36142318 -36.7235867
OS 31.35448898 -36.70694462
OS 31.34616794 -36.68752886
OS 31.33368638 -36.66949994
OS 31.3170443 -36.65147102
OS 31.31427062 -36.65008418
OS 31.30733642 -36.64453682
OS 31.2962417 -36.63760262
OS 31.27821278 -36.62928158
OS 31.25741018 -36.62096054
OS 31.22967338 -36.61402634
OS 31.19777606 -36.60847898
OS 31.16033138 -36.60709214
OE
OB 36.29302622 -36.61402634 H
OS 36.06558446 -36.61402634
OS 36.06558446 -36.90248906
OS 36.30134726 -36.90248906
OS 36.31937618 -36.90110222
OS 36.33879194 -36.89971538
OS 36.3582077 -36.89832854
OS 36.37762346 -36.89555486
OS 36.3928787 -36.89278118
OS 36.39565238 -36.89139434
OS 36.40119974 -36.8900075
OS 36.40952078 -36.88584698
OS 36.4206155 -36.88029962
OS 36.43171022 -36.87475226
OS 36.44419178 -36.86643122
OS 36.45667334 -36.8553365
OS 36.46638122 -36.84424178
OS 36.46776806 -36.84285494
OS 36.47054174 -36.83869442
OS 36.47470226 -36.83037338
OS 36.47886278 -36.8206655
OS 36.4830233 -36.80957078
OS 36.48718382 -36.79570238
OS 36.4899575 -36.7790603
OS 36.49134434 -36.76103138
OS 36.49134434 -36.7582577
OS 36.49134434 -36.75271034
OS 36.4899575 -36.7443893
OS 36.48857066 -36.73329458
OS 36.48579698 -36.71942618
OS 36.48163646 -36.70555778
OS 36.4760891 -36.69168938
OS 36.46776806 -36.67782098
OS 36.46638122 -36.67643414
OS 36.46360754 -36.67227362
OS 36.45806018 -36.66533942
OS 36.45112598 -36.65840522
OS 36.4414181 -36.65008418
OS 36.43032338 -36.64176314
OS 36.41645498 -36.6334421
OS 36.40119974 -36.62789474
OS 36.3998129 -36.62789474
OS 36.3928787 -36.62512106
OS 36.38317082 -36.62373422
OS 36.36791558 -36.62096054
OS 36.34711298 -36.61818686
OS 36.3235367 -36.61680002
OS 36.29302622 -36.61402634
OE
OB 36.31798934 -37.01620994 H
OS 36.06558446 -37.01620994
OS 36.06558446 -37.34627786
OS 36.33879194 -37.34627786
OS 36.36791558 -37.34489102
OS 36.38039714 -37.34350418
OS 36.39149186 -37.34211734
OS 36.3928787 -37.34211734
OS 36.39842606 -37.3407305
OS 36.4067471 -37.33934366
OS 36.41645498 -37.33656998
OS 36.44003126 -37.32824894
OS 36.46360754 -37.31715422
OS 36.46499438 -37.31576738
OS 36.4691549 -37.3129937
OS 36.47470226 -37.30883318
OS 36.48163646 -37.30328582
OS 36.48857066 -37.29496478
OS 36.49827854 -37.28664374
OS 36.50521274 -37.27554902
OS 36.51353378 -37.26306746
OS 36.51492062 -37.26168062
OS 36.51630746 -37.2575201
OS 36.51908114 -37.24919906
OS 36.52324166 -37.23949118
OS 36.52740218 -37.22839646
OS 36.53017586 -37.21452806
OS 36.5315627 -37.19788598
OS 36.53294954 -37.1812439
OS 36.53294954 -37.17847022
OS 36.53294954 -37.17292286
OS 36.5315627 -37.16182814
OS 36.52878902 -37.14934658
OS 36.52601534 -37.13547818
OS 36.52046798 -37.12022294
OS 36.51353378 -37.1049677
OS 36.5038259 -37.08971246
OS 36.50243906 -37.08832562
OS 36.49827854 -37.08277826
OS 36.49273118 -37.07584406
OS 36.48441014 -37.06752302
OS 36.47331542 -37.05781514
OS 36.45944702 -37.04810726
OS 36.44419178 -37.03978622
OS 36.42616286 -37.03285202
OS 36.42338918 -37.03146518
OS 36.41784182 -37.03007834
OS 36.40536026 -37.02730466
OS 36.39010502 -37.02453098
OS 36.37068926 -37.0217573
OS 36.34711298 -37.01898362
OS 36.31798934 -37.01620994
OE
SE
S P 0
OB 40.9056459 -38.32112732 I
OS 40.92136342 -38.32205188
OS 40.9380055 -38.32297644
OS 40.95372302 -38.32482556
OS 40.96759142 -38.32667468
OS 40.96944054 -38.32667468
OS 40.97591246 -38.3285238
OS 40.9842335 -38.33037292
OS 40.99532822 -38.3331466
OS 41.0073475 -38.3377694
OS 41.02029134 -38.34331676
OS 41.03415974 -38.34978868
OS 41.04617902 -38.35718516
OS 41.04802814 -38.35810972
OS 41.05172638 -38.3608834
OS 41.05727374 -38.36643076
OS 41.06467022 -38.37290268
OS 41.07299126 -38.38122372
OS 41.0813123 -38.39231844
OS 41.0905579 -38.40433772
OS 41.09795438 -38.41820612
OS 41.09887894 -38.42005524
OS 41.10072806 -38.42467804
OS 41.1044263 -38.43299908
OS 41.10812454 -38.4440938
OS 41.11089822 -38.45703764
OS 41.11459646 -38.4718306
OS 41.11644558 -38.48847268
OS 41.11737014 -38.50603932
OS 41.11737014 -38.50696388
OS 41.11737014 -38.50973756
OS 41.11737014 -38.5134358
OS 41.11644558 -38.51990772
OS 41.11552102 -38.52637964
OS 41.11459646 -38.53470068
OS 41.11274734 -38.54394628
OS 41.11089822 -38.55411644
OS 41.1044263 -38.57538132
OS 41.10072806 -38.58647604
OS 41.0951807 -38.59849532
OS 41.08870878 -38.6105146
OS 41.08223686 -38.62160932
OS 41.07391582 -38.63270404
OS 41.06467022 -38.64379876
OS 41.06374566 -38.64472332
OS 41.06189654 -38.64657244
OS 41.05912286 -38.64934612
OS 41.05450006 -38.6521198
OS 41.0489527 -38.6567426
OS 41.04155622 -38.6613654
OS 41.03231062 -38.66691276
OS 41.02214046 -38.67153556
OS 41.01012118 -38.67708292
OS 40.99625278 -38.68263028
OS 40.98145982 -38.68725308
OS 40.96389318 -38.69095132
OS 40.94540198 -38.69464956
OS 40.92506166 -38.69742324
OS 40.90194766 -38.69927236
OS 40.8779091 -38.70019692
OS 40.71426198 -38.70019692
OS 40.71426198 -38.95999828
OS 40.62920246 -38.95999828
OS 40.62920246 -38.32020276
OS 40.8917775 -38.32020276
OS 40.9056459 -38.32112732
OE
OB 40.49791494 -38.98403684 I
OS 40.49791494 -38.9849614
OS 40.49791494 -38.98773508
OS 40.49791494 -38.99235788
OS 40.49791494 -38.99790524
OS 40.49699038 -39.00530172
OS 40.49699038 -39.0126982
OS 40.49514126 -39.0311894
OS 40.49236758 -39.05060516
OS 40.48866934 -39.07094548
OS 40.48312198 -39.08851212
OS 40.47942374 -39.09683316
OS 40.4757255 -39.10330508
OS 40.4757255 -39.10422964
OS 40.47480094 -39.1051542
OS 40.47017814 -39.109777
OS 40.46278166 -39.11717348
OS 40.45353606 -39.12549452
OS 40.44059222 -39.13381556
OS 40.42395014 -39.14028748
OS 40.40453438 -39.14583484
OS 40.39343966 -39.1467594
OS 40.38142038 -39.14768396
OS 40.37587302 -39.14768396
OS 40.37032566 -39.1467594
OS 40.36200462 -39.1467594
OS 40.35275902 -39.14583484
OS 40.34258886 -39.14398572
OS 40.32039942 -39.13843836
OS 40.33519238 -39.07187004
OS 40.33611694 -39.07187004
OS 40.33889062 -39.0727946
OS 40.34351342 -39.07371916
OS 40.34813622 -39.07464372
OS 40.3601555 -39.0774174
OS 40.36570286 -39.07834196
OS 40.37494846 -39.07834196
OS 40.37957126 -39.0774174
OS 40.38511862 -39.07649284
OS 40.39066598 -39.07464372
OS 40.39621334 -39.07094548
OS 40.40268526 -39.06724724
OS 40.40730806 -39.06169988
OS 40.40823262 -39.06077532
OS 40.40915718 -39.05800164
OS 40.4110063 -39.05337884
OS 40.41377998 -39.04598236
OS 40.4156291 -39.0358122
OS 40.41655366 -39.02841572
OS 40.41747822 -39.0219438
OS 40.41840278 -39.01362276
OS 40.41840278 -39.0034526
OS 40.41932734 -38.99328244
OS 40.41932734 -38.98218772
OS 40.41932734 -38.49586916
OS 40.49791494 -38.49586916
OS 40.49791494 -38.98403684
OE
OB 41.51770462 -38.3100326 I
OS 41.52602566 -38.31095716
OS 41.53619582 -38.31188172
OS 41.54636598 -38.31280628
OS 41.55838526 -38.31557996
OS 41.58334838 -38.32112732
OS 41.61108518 -38.32944836
OS 41.62495358 -38.33499572
OS 41.63789742 -38.34146764
OS 41.65084126 -38.34978868
OS 41.6637851 -38.35810972
OS 41.66470966 -38.35903428
OS 41.66655878 -38.35995884
OS 41.67025702 -38.36273252
OS 41.67487982 -38.36735532
OS 41.67950262 -38.37197812
OS 41.68597454 -38.37845004
OS 41.69244646 -38.38584652
OS 41.69984294 -38.393243
OS 41.70723942 -38.4024886
OS 41.7146359 -38.41358332
OS 41.72295694 -38.42467804
OS 41.73035342 -38.43669732
OS 41.73682534 -38.45056572
OS 41.74422182 -38.46443412
OS 41.74976918 -38.47922708
OS 41.75531654 -38.49586916
OS 41.67210614 -38.51528492
OS 41.67210614 -38.51436036
OS 41.67118158 -38.51251124
OS 41.66933246 -38.508813
OS 41.66748334 -38.5041902
OS 41.66563422 -38.49864284
OS 41.66286054 -38.49124636
OS 41.65546406 -38.4764534
OS 41.64621846 -38.45981132
OS 41.63512374 -38.44316924
OS 41.62125534 -38.42745172
OS 41.60646238 -38.41358332
OS 41.60461326 -38.4117342
OS 41.5990659 -38.40803596
OS 41.5898203 -38.40341316
OS 41.57780102 -38.39694124
OS 41.5620835 -38.39139388
OS 41.54451686 -38.38584652
OS 41.52325198 -38.38214828
OS 41.50013798 -38.38122372
OS 41.4927415 -38.38122372
OS 41.4881187 -38.38214828
OS 41.48164678 -38.38214828
OS 41.4742503 -38.38307284
OS 41.45668366 -38.38584652
OS 41.4372679 -38.38954476
OS 41.41692758 -38.39601668
OS 41.3956627 -38.40526228
OS 41.37624694 -38.41728156
OS 41.37532238 -38.41728156
OS 41.37439782 -38.41913068
OS 41.3679259 -38.42375348
OS 41.35960486 -38.43114996
OS 41.3494347 -38.44224468
OS 41.33741542 -38.45611308
OS 41.3263207 -38.4718306
OS 41.31615054 -38.49124636
OS 41.30690494 -38.51251124
OS 41.30690494 -38.5134358
OS 41.30598038 -38.51528492
OS 41.30505582 -38.5180586
OS 41.30413126 -38.5226814
OS 41.30228214 -38.52822876
OS 41.30043302 -38.53470068
OS 41.29765934 -38.5504182
OS 41.2939611 -38.5689094
OS 41.29026286 -38.58924972
OS 41.28841374 -38.61143916
OS 41.28748918 -38.63547772
OS 41.28748918 -38.63640228
OS 41.28748918 -38.63917596
OS 41.28748918 -38.64379876
OS 41.28748918 -38.64934612
OS 41.28841374 -38.65581804
OS 41.28841374 -38.66413908
OS 41.2893383 -38.67338468
OS 41.29026286 -38.68355484
OS 41.29303654 -38.70574428
OS 41.29765934 -38.72978284
OS 41.3032067 -38.7538214
OS 41.31060318 -38.77785996
OS 41.31060318 -38.77878452
OS 41.31152774 -38.78063364
OS 41.31337686 -38.78340732
OS 41.31522598 -38.78803012
OS 41.32077334 -38.79912484
OS 41.32909438 -38.81206868
OS 41.33926454 -38.82686164
OS 41.35220838 -38.84257916
OS 41.36700134 -38.85644756
OS 41.38456798 -38.8693914
OS 41.38549254 -38.8693914
OS 41.38734166 -38.87031596
OS 41.39011534 -38.87216508
OS 41.39381358 -38.8740142
OS 41.39843638 -38.87586332
OS 41.40398374 -38.878637
OS 41.41692758 -38.88418436
OS 41.43356966 -38.88973172
OS 41.45206086 -38.89435452
OS 41.47240118 -38.89805276
OS 41.49366606 -38.89897732
OS 41.50013798 -38.89897732
OS 41.50568534 -38.89805276
OS 41.51215726 -38.89805276
OS 41.51862918 -38.8971282
OS 41.53527126 -38.89342996
OS 41.55468702 -38.88880716
OS 41.57410278 -38.88141068
OS 41.5944431 -38.87124052
OS 41.60461326 -38.86569316
OS 41.61385886 -38.85829668
OS 41.61478342 -38.85737212
OS 41.61570798 -38.85644756
OS 41.61848166 -38.85367388
OS 41.6221799 -38.8509002
OS 41.62587814 -38.8462774
OS 41.63050094 -38.84073004
OS 41.6360483 -38.83518268
OS 41.6406711 -38.8277862
OS 41.64621846 -38.81946516
OS 41.65269038 -38.81021956
OS 41.65823774 -38.80097396
OS 41.6637851 -38.78987924
OS 41.6684079 -38.77785996
OS 41.6730307 -38.76491612
OS 41.6776535 -38.75104772
OS 41.68135174 -38.73625476
OS 41.76641126 -38.75751964
OS 41.76641126 -38.7584442
OS 41.7654867 -38.76214244
OS 41.76363758 -38.7676898
OS 41.7608639 -38.77508628
OS 41.75809022 -38.78340732
OS 41.75439198 -38.79357748
OS 41.74976918 -38.8046722
OS 41.74422182 -38.81669148
OS 41.73127798 -38.84257916
OS 41.7146359 -38.86846684
OS 41.70446574 -38.88141068
OS 41.69429558 -38.89435452
OS 41.68320086 -38.90544924
OS 41.67025702 -38.91654396
OS 41.66933246 -38.91746852
OS 41.66748334 -38.91931764
OS 41.66286054 -38.92116676
OS 41.65823774 -38.924865
OS 41.65084126 -38.9294878
OS 41.64344478 -38.9341106
OS 41.63327462 -38.9387334
OS 41.62310446 -38.9433562
OS 41.61108518 -38.94890356
OS 41.59814134 -38.95352636
OS 41.58427294 -38.95814916
OS 41.56947998 -38.96277196
OS 41.55376246 -38.9664702
OS 41.53712038 -38.96831932
OS 41.51955374 -38.97016844
OS 41.50106254 -38.971093
OS 41.49089238 -38.971093
OS 41.4834959 -38.97016844
OS 41.47517486 -38.97016844
OS 41.4650047 -38.96924388
OS 41.45390998 -38.96739476
OS 41.44096614 -38.96554564
OS 41.4141539 -38.96092284
OS 41.3864171 -38.95352636
OS 41.3586803 -38.9433562
OS 41.34573646 -38.93688428
OS 41.33279262 -38.9294878
OS 41.33186806 -38.92856324
OS 41.33001894 -38.92763868
OS 41.3263207 -38.924865
OS 41.32262246 -38.92116676
OS 41.3170751 -38.91746852
OS 41.31060318 -38.91192116
OS 41.3032067 -38.90544924
OS 41.29581022 -38.89805276
OS 41.28841374 -38.88973172
OS 41.2800927 -38.88141068
OS 41.26345062 -38.8601458
OS 41.2477331 -38.83518268
OS 41.2338647 -38.80744588
OS 41.2338647 -38.80652132
OS 41.23201558 -38.80374764
OS 41.23109102 -38.79912484
OS 41.22831734 -38.79357748
OS 41.22646822 -38.786181
OS 41.22369454 -38.7769354
OS 41.2199963 -38.76676524
OS 41.21722262 -38.75567052
OS 41.21444894 -38.74365124
OS 41.2107507 -38.72978284
OS 41.2061279 -38.70112148
OS 41.20242966 -38.66876188
OS 41.20058054 -38.63547772
OS 41.20058054 -38.63455316
OS 41.20058054 -38.63085492
OS 41.20058054 -38.62530756
OS 41.2015051 -38.61883564
OS 41.2015051 -38.60959004
OS 41.20242966 -38.60034444
OS 41.20335422 -38.58832516
OS 41.20520334 -38.57630588
OS 41.20982614 -38.54949364
OS 41.21629806 -38.51990772
OS 41.22554366 -38.4903218
OS 41.2384875 -38.46166044
OS 41.23941206 -38.46073588
OS 41.24033662 -38.4579622
OS 41.24218574 -38.45426396
OS 41.24588398 -38.44964116
OS 41.24958222 -38.44316924
OS 41.25420502 -38.43577276
OS 41.2662243 -38.41913068
OS 41.28194182 -38.40063948
OS 41.30043302 -38.38214828
OS 41.3216979 -38.36365708
OS 41.34666102 -38.34793956
OS 41.34758558 -38.347015
OS 41.35035926 -38.34609044
OS 41.3540575 -38.34424132
OS 41.3586803 -38.34146764
OS 41.36607678 -38.33869396
OS 41.37347326 -38.33592028
OS 41.38271886 -38.33222204
OS 41.39288902 -38.3285238
OS 41.40398374 -38.32482556
OS 41.41600302 -38.32112732
OS 41.4418907 -38.31557996
OS 41.47147662 -38.31095716
OS 41.5019871 -38.30910804
OS 41.5112327 -38.30910804
OS 41.51770462 -38.3100326
OE
OB 42.90454462 -39.1375138 I
OS 42.38401734 -39.1375138
OS 42.38401734 -39.08111564
OS 42.90454462 -39.08111564
OS 42.90454462 -39.1375138
OE
OB 42.12514054 -38.32112732 I
OS 42.13253702 -38.32112732
OS 42.1491791 -38.32297644
OS 42.1676703 -38.32482556
OS 42.18708606 -38.3285238
OS 42.20650182 -38.3331466
OS 42.22406846 -38.33961852
OS 42.22499302 -38.33961852
OS 42.22591758 -38.34054308
OS 42.23146494 -38.34331676
OS 42.23978598 -38.34793956
OS 42.24903158 -38.35441148
OS 42.2601263 -38.36273252
OS 42.27214558 -38.37290268
OS 42.2832403 -38.38584652
OS 42.29341046 -38.39971492
OS 42.29433502 -38.40156404
OS 42.2971087 -38.4071114
OS 42.3017315 -38.41450788
OS 42.3063543 -38.4256026
OS 42.3109771 -38.43854644
OS 42.3155999 -38.45241484
OS 42.31837358 -38.46813236
OS 42.31929814 -38.48384988
OS 42.31929814 -38.485699
OS 42.31929814 -38.4903218
OS 42.31837358 -38.49864284
OS 42.31652446 -38.508813
OS 42.31375078 -38.52083228
OS 42.30912798 -38.53377612
OS 42.30358062 -38.54671996
OS 42.29618414 -38.56058836
OS 42.29525958 -38.56243748
OS 42.2924859 -38.56613572
OS 42.28693854 -38.5735322
OS 42.27954206 -38.58092868
OS 42.27029646 -38.59017428
OS 42.25920174 -38.60034444
OS 42.24533334 -38.60959004
OS 42.22961582 -38.61883564
OS 42.23054038 -38.61883564
OS 42.2323895 -38.6197602
OS 42.23516318 -38.62068476
OS 42.23886142 -38.62253388
OS 42.24995614 -38.62623212
OS 42.26289998 -38.63270404
OS 42.27676838 -38.64102508
OS 42.2924859 -38.65119524
OS 42.3063543 -38.66321452
OS 42.31929814 -38.67800748
OS 42.3202227 -38.6798566
OS 42.32392094 -38.68540396
OS 42.3294683 -38.693725
OS 42.33501566 -38.70481972
OS 42.34056302 -38.71961268
OS 42.34611038 -38.7353302
OS 42.34980862 -38.7538214
OS 42.35073318 -38.77416172
OS 42.35073318 -38.77508628
OS 42.35073318 -38.77601084
OS 42.35073318 -38.7815582
OS 42.34980862 -38.7908038
OS 42.3479595 -38.80189852
OS 42.34611038 -38.81484236
OS 42.34241214 -38.82871076
OS 42.33778934 -38.84350372
OS 42.33131742 -38.85829668
OS 42.33039286 -38.8601458
OS 42.32761918 -38.8647686
OS 42.32392094 -38.87124052
OS 42.31837358 -38.88048612
OS 42.3109771 -38.88973172
OS 42.30358062 -38.89990188
OS 42.29433502 -38.91007204
OS 42.28416486 -38.91839308
OS 42.2832403 -38.91931764
OS 42.27954206 -38.92209132
OS 42.27307014 -38.92578956
OS 42.2647491 -38.9294878
OS 42.25457894 -38.93503516
OS 42.24255966 -38.94058252
OS 42.22961582 -38.94520532
OS 42.2138983 -38.94982812
OS 42.21204918 -38.94982812
OS 42.20650182 -38.95167724
OS 42.19725622 -38.9526018
OS 42.18523694 -38.95445092
OS 42.17044398 -38.95630004
OS 42.15287734 -38.95814916
OS 42.13346158 -38.95907372
OS 42.11127214 -38.95999828
OS 41.8671883 -38.95999828
OS 41.8671883 -38.32020276
OS 42.11866862 -38.32020276
OS 42.12514054 -38.32112732
OE
OB 40.30745558 -38.48662356 I
OS 40.31762574 -38.48847268
OS 40.32964502 -38.49217092
OS 40.34258886 -38.49679372
OS 40.35738182 -38.50326564
OS 40.37309934 -38.51158668
OS 40.34443798 -38.58370236
OS 40.34351342 -38.5827778
OS 40.33981518 -38.58092868
OS 40.33426782 -38.578155
OS 40.32687134 -38.57538132
OS 40.3185503 -38.57260764
OS 40.30838014 -38.56983396
OS 40.29820998 -38.56798484
OS 40.28803982 -38.56706028
OS 40.28341702 -38.56706028
OS 40.27879422 -38.56798484
OS 40.2723223 -38.5689094
OS 40.26585038 -38.57075852
OS 40.25752934 -38.5735322
OS 40.2492083 -38.57723044
OS 40.24181182 -38.5827778
OS 40.24088726 -38.58370236
OS 40.23811358 -38.58555148
OS 40.2353399 -38.58924972
OS 40.2307171 -38.59387252
OS 40.2260943 -38.60034444
OS 40.2214715 -38.60774092
OS 40.2168487 -38.61606196
OS 40.21315046 -38.62623212
OS 40.2122259 -38.62808124
OS 40.21130134 -38.6336286
OS 40.20945222 -38.64194964
OS 40.20667854 -38.65304436
OS 40.20390486 -38.66691276
OS 40.20205574 -38.68263028
OS 40.20113118 -38.69927236
OS 40.20020662 -38.71776356
OS 40.20020662 -38.95999828
OS 40.12161902 -38.95999828
OS 40.12161902 -38.49586916
OS 40.19281014 -38.49586916
OS 40.19281014 -38.56613572
OS 40.1937347 -38.56521116
OS 40.19743294 -38.55873924
OS 40.20205574 -38.5504182
OS 40.20945222 -38.54024804
OS 40.2168487 -38.53007788
OS 40.22516974 -38.51898316
OS 40.23349078 -38.50973756
OS 40.24181182 -38.50234108
OS 40.24273638 -38.50141652
OS 40.24551006 -38.4995674
OS 40.25105742 -38.49679372
OS 40.25660478 -38.49402004
OS 40.26400126 -38.49124636
OS 40.27324686 -38.48847268
OS 40.28249246 -38.48662356
OS 40.29266262 -38.485699
OS 40.29913454 -38.485699
OS 40.30745558 -38.48662356
OE
OB 39.48829542 -38.95999828 I
OS 39.3986131 -38.95999828
OS 39.3986131 -38.87031596
OS 39.48829542 -38.87031596
OS 39.48829542 -38.95999828
OE
OB 38.6404739 -38.95999828 I
OS 38.55171614 -38.95999828
OS 38.30393406 -38.32020276
OS 38.39639006 -38.32020276
OS 38.56281086 -38.78525644
OS 38.56281086 -38.786181
OS 38.56373542 -38.78803012
OS 38.56465998 -38.7908038
OS 38.5665091 -38.79450204
OS 38.56743366 -38.8000494
OS 38.56928278 -38.80559676
OS 38.57390558 -38.81946516
OS 38.57945294 -38.83518268
OS 38.5850003 -38.85274932
OS 38.59609502 -38.88973172
OS 38.59609502 -38.88880716
OS 38.59701958 -38.88695804
OS 38.59794414 -38.88418436
OS 38.5988687 -38.88048612
OS 38.60164238 -38.87031596
OS 38.60626518 -38.85644756
OS 38.61088798 -38.84073004
OS 38.61643534 -38.8231634
OS 38.62290726 -38.8046722
OS 38.63030374 -38.78525644
OS 38.80412102 -38.32020276
OS 38.8901051 -38.32020276
OS 38.6404739 -38.95999828
OE
OB 39.27564662 -38.42745172 I
OS 39.25438174 -38.54671996
OS 39.20538006 -38.54671996
OS 39.1859643 -38.42745172
OS 39.1859643 -38.32020276
OS 39.27564662 -38.32020276
OS 39.27564662 -38.42745172
OE
OB 40.49791494 -38.4117342 I
OS 40.41932734 -38.4117342
OS 40.41932734 -38.32020276
OS 40.49791494 -38.32020276
OS 40.49791494 -38.4117342
OE
OB 39.84517558 -38.48662356 I
OS 39.8516475 -38.48754812
OS 39.8655159 -38.48939724
OS 39.88215798 -38.49309548
OS 39.89972462 -38.49864284
OS 39.91729126 -38.50696388
OS 39.9348579 -38.51713404
OS 39.93578246 -38.51713404
OS 39.93670702 -38.51898316
OS 39.94225438 -38.5226814
OS 39.95057542 -38.53007788
OS 39.96074558 -38.53932348
OS 39.9718403 -38.55134276
OS 39.98293502 -38.56613572
OS 39.99402974 -38.58370236
OS 40.00327534 -38.60311812
OS 40.00327534 -38.60404268
OS 40.0041999 -38.6058918
OS 40.00512446 -38.60866548
OS 40.00697358 -38.61236372
OS 40.0088227 -38.61791108
OS 40.01067182 -38.624383
OS 40.01529462 -38.63917596
OS 40.01991742 -38.65766716
OS 40.02361566 -38.67800748
OS 40.02638934 -38.70112148
OS 40.0273139 -38.72516004
OS 40.0273139 -38.7260846
OS 40.0273139 -38.72793372
OS 40.0273139 -38.73163196
OS 40.0273139 -38.73717932
OS 40.02638934 -38.74365124
OS 40.02638934 -38.75104772
OS 40.02454022 -38.7676898
OS 40.02084198 -38.78803012
OS 40.01621918 -38.809295
OS 40.00974726 -38.83148444
OS 40.00142622 -38.85367388
OS 40.00142622 -38.85459844
OS 40.00050166 -38.85644756
OS 39.99865254 -38.85922124
OS 39.99680342 -38.86291948
OS 39.9903315 -38.87308964
OS 39.98201046 -38.88603348
OS 39.9718403 -38.89990188
OS 39.95889646 -38.91377028
OS 39.9441035 -38.92763868
OS 39.92653686 -38.94058252
OS 39.9256123 -38.94058252
OS 39.92468774 -38.94150708
OS 39.92191406 -38.9433562
OS 39.91821582 -38.94520532
OS 39.90897022 -38.94982812
OS 39.89602638 -38.95537548
OS 39.88030886 -38.96092284
OS 39.86366678 -38.96554564
OS 39.84425102 -38.96924388
OS 39.82483526 -38.97016844
OS 39.81836334 -38.97016844
OS 39.81096686 -38.96924388
OS 39.80172126 -38.96831932
OS 39.79062654 -38.9664702
OS 39.77860726 -38.96369652
OS 39.76658798 -38.95999828
OS 39.7545687 -38.95445092
OS 39.75364414 -38.95352636
OS 39.74902134 -38.95167724
OS 39.74347398 -38.947979
OS 39.7360775 -38.94243164
OS 39.72868102 -38.93688428
OS 39.71943542 -38.9294878
OS 39.71111438 -38.92116676
OS 39.7037179 -38.91192116
OS 39.7037179 -39.1375138
OS 39.6251303 -39.1375138
OS 39.6251303 -38.49586916
OS 39.69632142 -38.49586916
OS 39.69632142 -38.55689012
OS 39.69724598 -38.555041
OS 39.70094422 -38.55134276
OS 39.70556702 -38.54487084
OS 39.7129635 -38.53747436
OS 39.72128454 -38.52822876
OS 39.73053014 -38.51990772
OS 39.74162486 -38.51158668
OS 39.75271958 -38.5041902
OS 39.7545687 -38.50326564
OS 39.75826694 -38.50141652
OS 39.76566342 -38.49864284
OS 39.77490902 -38.4949446
OS 39.78600374 -38.49124636
OS 39.79894758 -38.48847268
OS 39.81374054 -38.48662356
OS 39.83038262 -38.485699
OS 39.84055278 -38.485699
OS 39.84517558 -38.48662356
OE
OB 44.92193454 -38.40988508 I
OS 44.84334694 -38.40988508
OS 44.84334694 -38.32020276
OS 44.92193454 -38.32020276
OS 44.92193454 -38.40988508
OE
OB 45.24553054 -38.48662356 I
OS 45.25385158 -38.48754812
OS 45.26309718 -38.48939724
OS 45.27326734 -38.49124636
OS 45.28528662 -38.49309548
OS 45.31024974 -38.50141652
OS 45.32319358 -38.50603932
OS 45.33613742 -38.51251124
OS 45.34908126 -38.51898316
OS 45.3620251 -38.52822876
OS 45.37404438 -38.53747436
OS 45.38606366 -38.54856908
OS 45.38698822 -38.54949364
OS 45.38883734 -38.55134276
OS 45.39161102 -38.555041
OS 45.39530926 -38.5596638
OS 45.39993206 -38.56613572
OS 45.40547942 -38.57445676
OS 45.41102678 -38.58370236
OS 45.41657414 -38.59387252
OS 45.4221215 -38.60496724
OS 45.42766886 -38.61883564
OS 45.43321622 -38.63270404
OS 45.43783902 -38.64842156
OS 45.44153726 -38.66506364
OS 45.44431094 -38.68263028
OS 45.44616006 -38.70112148
OS 45.44708462 -38.7214618
OS 45.44708462 -38.72238636
OS 45.44708462 -38.72516004
OS 45.44708462 -38.72978284
OS 45.44708462 -38.73625476
OS 45.44616006 -38.74365124
OS 45.4452355 -38.75289684
OS 45.4452355 -38.76214244
OS 45.44338638 -38.7723126
OS 45.4406127 -38.7954266
OS 45.43506534 -38.8185406
OS 45.42859342 -38.8416546
OS 45.41934782 -38.86291948
OS 45.41934782 -38.86384404
OS 45.41842326 -38.8647686
OS 45.41657414 -38.86754228
OS 45.41472502 -38.87124052
OS 45.4082531 -38.88048612
OS 45.39993206 -38.89158084
OS 45.38883734 -38.90452468
OS 45.37496894 -38.91746852
OS 45.35925142 -38.93041236
OS 45.34076022 -38.94243164
OS 45.33983566 -38.94243164
OS 45.3389111 -38.9433562
OS 45.33613742 -38.94520532
OS 45.33151462 -38.94705444
OS 45.32689182 -38.94890356
OS 45.32134446 -38.95075268
OS 45.30747606 -38.95630004
OS 45.29175854 -38.96092284
OS 45.27234278 -38.96554564
OS 45.25200246 -38.96924388
OS 45.22981302 -38.97016844
OS 45.22056742 -38.97016844
OS 45.21317094 -38.96924388
OS 45.2048499 -38.96831932
OS 45.1956043 -38.9664702
OS 45.18450958 -38.96462108
OS 45.17341486 -38.96277196
OS 45.14845174 -38.95537548
OS 45.13458334 -38.94982812
OS 45.1216395 -38.94428076
OS 45.10869566 -38.93688428
OS 45.09575182 -38.92856324
OS 45.08373254 -38.91931764
OS 45.07171326 -38.90822292
OS 45.0707887 -38.90729836
OS 45.06893958 -38.90544924
OS 45.0661659 -38.901751
OS 45.06246766 -38.89620364
OS 45.05784486 -38.88973172
OS 45.05322206 -38.88233524
OS 45.0476747 -38.87308964
OS 45.04212734 -38.86199492
OS 45.03657998 -38.84997564
OS 45.03103262 -38.83610724
OS 45.02640982 -38.82131428
OS 45.02178702 -38.80559676
OS 45.01808878 -38.78803012
OS 45.0153151 -38.76953892
OS 45.01346598 -38.7491986
OS 45.01254142 -38.72793372
OS 45.01254142 -38.7260846
OS 45.01254142 -38.72238636
OS 45.01346598 -38.71591444
OS 45.01346598 -38.70666884
OS 45.01439054 -38.69649868
OS 45.01623966 -38.68355484
OS 45.01808878 -38.670611
OS 45.02178702 -38.65581804
OS 45.02548526 -38.64102508
OS 45.03010806 -38.62530756
OS 45.03565542 -38.60866548
OS 45.0430519 -38.59294796
OS 45.05044838 -38.578155
OS 45.06061854 -38.56336204
OS 45.0707887 -38.54949364
OS 45.08373254 -38.53747436
OS 45.0846571 -38.5365498
OS 45.08650622 -38.53562524
OS 45.09020446 -38.53285156
OS 45.09482726 -38.52915332
OS 45.10037462 -38.52545508
OS 45.1077711 -38.52083228
OS 45.11516758 -38.51620948
OS 45.12441318 -38.51158668
OS 45.13458334 -38.50696388
OS 45.14567806 -38.50234108
OS 45.17064118 -38.49402004
OS 45.19930254 -38.48754812
OS 45.2140955 -38.48662356
OS 45.22981302 -38.485699
OS 45.23905862 -38.485699
OS 45.24553054 -38.48662356
OE
OB 44.92193454 -38.95999828 I
OS 44.84334694 -38.95999828
OS 44.84334694 -38.49586916
OS 44.92193454 -38.49586916
OS 44.92193454 -38.95999828
OE
OB 46.10722046 -38.42745172 I
OS 46.08595558 -38.54671996
OS 46.0369539 -38.54671996
OS 46.01753814 -38.42745172
OS 46.01753814 -38.32020276
OS 46.10722046 -38.32020276
OS 46.10722046 -38.42745172
OE
OB 45.77160518 -38.48662356 I
OS 45.78177534 -38.48754812
OS 45.79379462 -38.48939724
OS 45.80673846 -38.49217092
OS 45.82060686 -38.49586916
OS 45.8335507 -38.50141652
OS 45.83539982 -38.50234108
OS 45.83909806 -38.5041902
OS 45.84556998 -38.50696388
OS 45.85296646 -38.51158668
OS 45.86221206 -38.51713404
OS 45.8705331 -38.52453052
OS 45.87885414 -38.531927
OS 45.88625062 -38.5411726
OS 45.88717518 -38.54209716
OS 45.8890243 -38.5457954
OS 45.89179798 -38.5504182
OS 45.89642078 -38.55689012
OS 45.90011902 -38.56613572
OS 45.90381726 -38.57538132
OS 45.90844006 -38.58647604
OS 45.91121374 -38.59849532
OS 45.91121374 -38.59941988
OS 45.9121383 -38.60311812
OS 45.91306286 -38.60866548
OS 45.91398742 -38.61606196
OS 45.91398742 -38.62715668
OS 45.91491198 -38.64010052
OS 45.91583654 -38.65581804
OS 45.91583654 -38.6752338
OS 45.91583654 -38.95999828
OS 45.83724894 -38.95999828
OS 45.83724894 -38.67893204
OS 45.83724894 -38.67800748
OS 45.83724894 -38.67708292
OS 45.83724894 -38.670611
OS 45.83724894 -38.66228996
OS 45.83632438 -38.6521198
OS 45.83539982 -38.64010052
OS 45.8335507 -38.62808124
OS 45.83077702 -38.61698652
OS 45.82800334 -38.60681636
OS 45.82800334 -38.6058918
OS 45.82615422 -38.60311812
OS 45.82338054 -38.59849532
OS 45.82060686 -38.59294796
OS 45.81598406 -38.5874006
OS 45.8104367 -38.58092868
OS 45.80304022 -38.57445676
OS 45.79471918 -38.5689094
OS 45.79379462 -38.56798484
OS 45.79102094 -38.56613572
OS 45.78547358 -38.5642866
OS 45.77900166 -38.56151292
OS 45.77160518 -38.55873924
OS 45.76235958 -38.55596556
OS 45.75126486 -38.555041
OS 45.74017014 -38.55411644
OS 45.73554734 -38.55411644
OS 45.7318491 -38.555041
OS 45.7226035 -38.55596556
OS 45.71058422 -38.55781468
OS 45.69764038 -38.56243748
OS 45.68284742 -38.56798484
OS 45.66805446 -38.57538132
OS 45.65418606 -38.58647604
OS 45.65233694 -38.58832516
OS 45.6486387 -38.59294796
OS 45.64586502 -38.5966462
OS 45.64309134 -38.601269
OS 45.6393931 -38.60681636
OS 45.63661942 -38.61328828
OS 45.63292118 -38.62068476
OS 45.62922294 -38.62993036
OS 45.62644926 -38.64010052
OS 45.62367558 -38.65119524
OS 45.62182646 -38.66321452
OS 45.61997734 -38.67615836
OS 45.61812822 -38.69187588
OS 45.61812822 -38.7075934
OS 45.61812822 -38.95999828
OS 45.53954062 -38.95999828
OS 45.53954062 -38.49586916
OS 45.60980718 -38.49586916
OS 45.60980718 -38.56243748
OS 45.61073174 -38.56151292
OS 45.61258086 -38.55873924
OS 45.61535454 -38.555041
OS 45.61905278 -38.5504182
OS 45.62460014 -38.54487084
OS 45.63107206 -38.53839892
OS 45.63846854 -38.53100244
OS 45.64771414 -38.52360596
OS 45.65695974 -38.51713404
OS 45.66805446 -38.50973756
OS 45.68007374 -38.50326564
OS 45.69301758 -38.49771828
OS 45.70781054 -38.49309548
OS 45.7226035 -38.48939724
OS 45.73924558 -38.48662356
OS 45.75681222 -38.485699
OS 45.7642087 -38.485699
OS 45.77160518 -38.48662356
OE
OB 44.2756671 -38.95999828 I
OS 44.1970795 -38.95999828
OS 44.1970795 -38.49586916
OS 44.2756671 -38.49586916
OS 44.2756671 -38.95999828
OE
OB 43.4574315 -38.48662356 I
OS 43.46482798 -38.48754812
OS 43.47407358 -38.48939724
OS 43.48424374 -38.49124636
OS 43.49626302 -38.49402004
OS 43.50735774 -38.49679372
OS 43.52030158 -38.50141652
OS 43.53232086 -38.50603932
OS 43.5452647 -38.51251124
OS 43.55820854 -38.51990772
OS 43.57115238 -38.52822876
OS 43.58317166 -38.53839892
OS 43.59426638 -38.54949364
OS 43.59519094 -38.5504182
OS 43.59704006 -38.55226732
OS 43.59981374 -38.55596556
OS 43.60351198 -38.56151292
OS 43.60813478 -38.56798484
OS 43.61275758 -38.57538132
OS 43.61830494 -38.58462692
OS 43.6238523 -38.59572164
OS 43.62939966 -38.60774092
OS 43.63494702 -38.62068476
OS 43.63956982 -38.63547772
OS 43.64419262 -38.65119524
OS 43.64789086 -38.66876188
OS 43.65066454 -38.68725308
OS 43.65251366 -38.70666884
OS 43.65343822 -38.72793372
OS 43.65343822 -38.72885828
OS 43.65343822 -38.73255652
OS 43.65343822 -38.73902844
OS 43.65251366 -38.74827404
OS 43.30580366 -38.74827404
OS 43.30580366 -38.7491986
OS 43.30580366 -38.75197228
OS 43.30672822 -38.75567052
OS 43.30672822 -38.76121788
OS 43.30765278 -38.7676898
OS 43.3095019 -38.77508628
OS 43.31227558 -38.79172836
OS 43.31782294 -38.81021956
OS 43.32521942 -38.83055988
OS 43.33538958 -38.84905108
OS 43.34833342 -38.86569316
OS 43.34925798 -38.86569316
OS 43.35018254 -38.86754228
OS 43.3557299 -38.87216508
OS 43.36405094 -38.878637
OS 43.37514566 -38.88510892
OS 43.38993862 -38.8925054
OS 43.4065807 -38.89897732
OS 43.4250719 -38.90360012
OS 43.43524206 -38.90452468
OS 43.44633678 -38.90544924
OS 43.45373326 -38.90544924
OS 43.4620543 -38.90452468
OS 43.47222446 -38.90267556
OS 43.48331918 -38.89990188
OS 43.49626302 -38.89620364
OS 43.5082823 -38.89065628
OS 43.52030158 -38.8832598
OS 43.52122614 -38.88233524
OS 43.52584894 -38.878637
OS 43.5313963 -38.87308964
OS 43.53786822 -38.86569316
OS 43.5452647 -38.855523
OS 43.55358574 -38.84257916
OS 43.56190678 -38.8277862
OS 43.56930326 -38.81021956
OS 43.65066454 -38.82038972
OS 43.65066454 -38.82131428
OS 43.64973998 -38.8231634
OS 43.64881542 -38.82686164
OS 43.6469663 -38.832409
OS 43.64419262 -38.83795636
OS 43.64141894 -38.84535284
OS 43.63402246 -38.86107036
OS 43.62477686 -38.878637
OS 43.61183302 -38.8971282
OS 43.59704006 -38.91469484
OS 43.57854886 -38.93133692
OS 43.5776243 -38.93133692
OS 43.57577518 -38.93318604
OS 43.5730015 -38.93503516
OS 43.56930326 -38.93780884
OS 43.5637559 -38.94058252
OS 43.55820854 -38.9433562
OS 43.55081206 -38.94705444
OS 43.54249102 -38.95075268
OS 43.53324542 -38.95445092
OS 43.52399982 -38.95814916
OS 43.50088582 -38.96369652
OS 43.47499814 -38.96831932
OS 43.44633678 -38.97016844
OS 43.43616662 -38.97016844
OS 43.4296947 -38.96924388
OS 43.42137366 -38.96831932
OS 43.4112035 -38.9664702
OS 43.40010878 -38.96462108
OS 43.3880895 -38.96277196
OS 43.36220182 -38.95537548
OS 43.34833342 -38.94982812
OS 43.33538958 -38.94428076
OS 43.32152118 -38.93688428
OS 43.30857734 -38.92856324
OS 43.29655806 -38.91931764
OS 43.28453878 -38.90822292
OS 43.28361422 -38.90729836
OS 43.2817651 -38.90544924
OS 43.27899142 -38.901751
OS 43.27529318 -38.89620364
OS 43.27067038 -38.88973172
OS 43.26604758 -38.88233524
OS 43.26050022 -38.87308964
OS 43.25495286 -38.86291948
OS 43.2494055 -38.8509002
OS 43.24385814 -38.83795636
OS 43.23923534 -38.8231634
OS 43.23461254 -38.80744588
OS 43.2309143 -38.7908038
OS 43.22814062 -38.7723126
OS 43.2262915 -38.75289684
OS 43.22536694 -38.73255652
OS 43.22536694 -38.73163196
OS 43.22536694 -38.72700916
OS 43.22536694 -38.7214618
OS 43.2262915 -38.71314076
OS 43.22721606 -38.7029706
OS 43.22814062 -38.69187588
OS 43.22998974 -38.67893204
OS 43.23276342 -38.6659882
OS 43.2401599 -38.63640228
OS 43.2447827 -38.62160932
OS 43.25033006 -38.6058918
OS 43.25772654 -38.59109884
OS 43.26604758 -38.57723044
OS 43.27529318 -38.56336204
OS 43.28546334 -38.5504182
OS 43.2863879 -38.54949364
OS 43.28823702 -38.54764452
OS 43.29193526 -38.54487084
OS 43.29655806 -38.54024804
OS 43.30210542 -38.53562524
OS 43.3095019 -38.53007788
OS 43.31782294 -38.52360596
OS 43.3279931 -38.5180586
OS 43.33816326 -38.51158668
OS 43.35018254 -38.50603932
OS 43.36312638 -38.50049196
OS 43.37699478 -38.49586916
OS 43.39178774 -38.49124636
OS 43.40750526 -38.48847268
OS 43.42414734 -38.48662356
OS 43.44171398 -38.485699
OS 43.45095958 -38.485699
OS 43.4574315 -38.48662356
OE
OB 43.13938286 -38.48662356 I
OS 43.14955302 -38.48847268
OS 43.1615723 -38.49217092
OS 43.17451614 -38.49679372
OS 43.1893091 -38.50326564
OS 43.20502662 -38.51158668
OS 43.17636526 -38.58370236
OS 43.1754407 -38.5827778
OS 43.17174246 -38.58092868
OS 43.1661951 -38.578155
OS 43.15879862 -38.57538132
OS 43.15047758 -38.57260764
OS 43.14030742 -38.56983396
OS 43.13013726 -38.56798484
OS 43.1199671 -38.56706028
OS 43.1153443 -38.56706028
OS 43.1107215 -38.56798484
OS 43.10424958 -38.5689094
OS 43.09777766 -38.57075852
OS 43.08945662 -38.5735322
OS 43.08113558 -38.57723044
OS 43.0737391 -38.5827778
OS 43.07281454 -38.58370236
OS 43.07004086 -38.58555148
OS 43.06726718 -38.58924972
OS 43.06264438 -38.59387252
OS 43.05802158 -38.60034444
OS 43.05339878 -38.60774092
OS 43.04877598 -38.61606196
OS 43.04507774 -38.62623212
OS 43.04415318 -38.62808124
OS 43.04322862 -38.6336286
OS 43.0413795 -38.64194964
OS 43.03860582 -38.65304436
OS 43.03583214 -38.66691276
OS 43.03398302 -38.68263028
OS 43.03305846 -38.69927236
OS 43.0321339 -38.71776356
OS 43.0321339 -38.95999828
OS 42.9535463 -38.95999828
OS 42.9535463 -38.49586916
OS 43.02473742 -38.49586916
OS 43.02473742 -38.56613572
OS 43.02566198 -38.56521116
OS 43.02936022 -38.55873924
OS 43.03398302 -38.5504182
OS 43.0413795 -38.54024804
OS 43.04877598 -38.53007788
OS 43.05709702 -38.51898316
OS 43.06541806 -38.50973756
OS 43.0737391 -38.50234108
OS 43.07466366 -38.50141652
OS 43.07743734 -38.4995674
OS 43.0829847 -38.49679372
OS 43.08853206 -38.49402004
OS 43.09592854 -38.49124636
OS 43.10517414 -38.48847268
OS 43.11441974 -38.48662356
OS 43.1245899 -38.485699
OS 43.13106182 -38.485699
OS 43.13938286 -38.48662356
OE
OB 43.95022198 -38.95999828 I
OS 43.87533262 -38.95999828
OS 43.70059078 -38.49586916
OS 43.78380118 -38.49586916
OS 43.88365366 -38.77416172
OS 43.88365366 -38.77508628
OS 43.88457822 -38.77601084
OS 43.88550278 -38.77878452
OS 43.88642734 -38.7815582
OS 43.88920102 -38.7908038
OS 43.89289926 -38.80282308
OS 43.89752206 -38.81669148
OS 43.90306942 -38.832409
OS 43.90769222 -38.84997564
OS 43.91323958 -38.86754228
OS 43.91416414 -38.86569316
OS 43.9150887 -38.86107036
OS 43.91786238 -38.85367388
OS 43.92063606 -38.84257916
OS 43.92525886 -38.83055988
OS 43.92988166 -38.81484236
OS 43.93635358 -38.79820028
OS 43.9428255 -38.77970908
OS 44.04545166 -38.49586916
OS 44.12681294 -38.49586916
OS 43.95022198 -38.95999828
OE
OB 44.2756671 -38.40988508 I
OS 44.1970795 -38.40988508
OS 44.1970795 -38.32020276
OS 44.2756671 -38.32020276
OS 44.2756671 -38.40988508
OE
OB 44.5669035 -38.48662356 I
OS 44.5807719 -38.48754812
OS 44.59556486 -38.48939724
OS 44.61128238 -38.49309548
OS 44.62792446 -38.49679372
OS 44.64364198 -38.50234108
OS 44.64456654 -38.50234108
OS 44.6454911 -38.50326564
OS 44.6501139 -38.50511476
OS 44.65751038 -38.508813
OS 44.66675598 -38.5134358
OS 44.67692614 -38.51990772
OS 44.6870963 -38.5273042
OS 44.6963419 -38.53562524
OS 44.70466294 -38.54487084
OS 44.7055875 -38.5457954
OS 44.70743662 -38.54949364
OS 44.71113486 -38.55596556
OS 44.71575766 -38.56336204
OS 44.72038046 -38.57445676
OS 44.72500326 -38.58647604
OS 44.7287015 -38.60034444
OS 44.73239974 -38.61606196
OS 44.65566126 -38.62623212
OS 44.65566126 -38.624383
OS 44.6547367 -38.62068476
OS 44.65288758 -38.61421284
OS 44.6501139 -38.6058918
OS 44.6454911 -38.59757076
OS 44.63994374 -38.58832516
OS 44.63347182 -38.57907956
OS 44.62422622 -38.57075852
OS 44.62330166 -38.56983396
OS 44.61960342 -38.56798484
OS 44.61405606 -38.5642866
OS 44.60573502 -38.56058836
OS 44.59648942 -38.55689012
OS 44.58447014 -38.55319188
OS 44.56967718 -38.55134276
OS 44.55395966 -38.5504182
OS 44.54471406 -38.5504182
OS 44.53546846 -38.55134276
OS 44.52344918 -38.55226732
OS 44.5114299 -38.555041
OS 44.49848606 -38.55781468
OS 44.48646678 -38.56243748
OS 44.47629662 -38.5689094
OS 44.47537206 -38.56983396
OS 44.47259838 -38.57168308
OS 44.46890014 -38.57538132
OS 44.4652019 -38.58092868
OS 44.4605791 -38.58647604
OS 44.45688086 -38.59387252
OS 44.45410718 -38.60219356
OS 44.45318262 -38.6105146
OS 44.45318262 -38.61143916
OS 44.45318262 -38.61328828
OS 44.45410718 -38.61606196
OS 44.45410718 -38.6197602
OS 44.45688086 -38.6290058
OS 44.46242822 -38.6382514
OS 44.46335278 -38.63917596
OS 44.46427734 -38.64010052
OS 44.46612646 -38.6428742
OS 44.4698247 -38.64564788
OS 44.47352294 -38.64842156
OS 44.4790703 -38.6521198
OS 44.48554222 -38.65489348
OS 44.4929387 -38.65859172
OS 44.49386326 -38.65859172
OS 44.49571238 -38.65951628
OS 44.49941062 -38.66044084
OS 44.50588254 -38.66321452
OS 44.51512814 -38.6659882
OS 44.52714742 -38.66876188
OS 44.5345439 -38.67153556
OS 44.54286494 -38.67338468
OS 44.55211054 -38.67615836
OS 44.5622807 -38.67893204
OS 44.56320526 -38.67893204
OS 44.56597894 -38.6798566
OS 44.57060174 -38.68078116
OS 44.5761491 -38.68263028
OS 44.58262102 -38.6844794
OS 44.59094206 -38.68632852
OS 44.6085087 -38.69187588
OS 44.62792446 -38.69742324
OS 44.64734022 -38.70389516
OS 44.66490686 -38.71036708
OS 44.67230334 -38.71314076
OS 44.67877526 -38.71591444
OS 44.68062438 -38.716839
OS 44.68432262 -38.71868812
OS 44.68986998 -38.7214618
OS 44.69819102 -38.7260846
OS 44.70651206 -38.73163196
OS 44.7148331 -38.73902844
OS 44.72315414 -38.74734948
OS 44.73055062 -38.75659508
OS 44.73147518 -38.75751964
OS 44.7333243 -38.76121788
OS 44.73702254 -38.76676524
OS 44.74072078 -38.77508628
OS 44.74349446 -38.78525644
OS 44.7471927 -38.79635116
OS 44.74904182 -38.809295
OS 44.74996638 -38.82408796
OS 44.74996638 -38.82593708
OS 44.74996638 -38.83055988
OS 44.74904182 -38.83795636
OS 44.7471927 -38.84812652
OS 44.74441902 -38.85922124
OS 44.73979622 -38.87124052
OS 44.73424886 -38.88510892
OS 44.72685238 -38.89805276
OS 44.72592782 -38.89990188
OS 44.72222958 -38.90360012
OS 44.71760678 -38.91007204
OS 44.7102103 -38.91746852
OS 44.70004014 -38.92578956
OS 44.68894542 -38.93503516
OS 44.67600158 -38.9433562
OS 44.66028406 -38.95167724
OS 44.6593595 -38.95167724
OS 44.65843494 -38.9526018
OS 44.65288758 -38.95445092
OS 44.64364198 -38.9572246
OS 44.6316227 -38.96092284
OS 44.61682974 -38.96462108
OS 44.60018766 -38.96739476
OS 44.58262102 -38.96924388
OS 44.5622807 -38.97016844
OS 44.55395966 -38.97016844
OS 44.54748774 -38.96924388
OS 44.54009126 -38.96924388
OS 44.53084566 -38.96831932
OS 44.52160006 -38.96739476
OS 44.5114299 -38.96554564
OS 44.48924046 -38.96092284
OS 44.46612646 -38.95445092
OS 44.44393702 -38.94520532
OS 44.43376686 -38.93965796
OS 44.42452126 -38.93318604
OS 44.4235967 -38.93226148
OS 44.42267214 -38.93133692
OS 44.41712478 -38.92578956
OS 44.40880374 -38.91746852
OS 44.39955814 -38.90452468
OS 44.38938798 -38.88880716
OS 44.37921782 -38.87031596
OS 44.37089678 -38.84720196
OS 44.36442486 -38.82131428
OS 44.4420879 -38.809295
OS 44.4420879 -38.81021956
OS 44.4420879 -38.81114412
OS 44.44393702 -38.81669148
OS 44.44578614 -38.82593708
OS 44.44948438 -38.83610724
OS 44.45410718 -38.84720196
OS 44.45965454 -38.85922124
OS 44.46797558 -38.87124052
OS 44.47814574 -38.88141068
OS 44.47999486 -38.88233524
OS 44.4836931 -38.88510892
OS 44.49108958 -38.88880716
OS 44.50033518 -38.89342996
OS 44.51235446 -38.89805276
OS 44.52622286 -38.901751
OS 44.54286494 -38.90452468
OS 44.5622807 -38.90544924
OS 44.5715263 -38.90544924
OS 44.5807719 -38.90452468
OS 44.59279118 -38.90267556
OS 44.60573502 -38.89990188
OS 44.61960342 -38.89620364
OS 44.6316227 -38.89158084
OS 44.64271742 -38.88418436
OS 44.64364198 -38.8832598
OS 44.64734022 -38.88048612
OS 44.65103846 -38.87586332
OS 44.65658582 -38.8693914
OS 44.66120862 -38.86199492
OS 44.66583142 -38.85274932
OS 44.6686051 -38.84350372
OS 44.66952966 -38.832409
OS 44.66952966 -38.83148444
OS 44.66952966 -38.8277862
OS 44.6686051 -38.8231634
OS 44.66675598 -38.81669148
OS 44.6639823 -38.81021956
OS 44.6593595 -38.80374764
OS 44.65381214 -38.79635116
OS 44.6454911 -38.7908038
OS 44.64456654 -38.78987924
OS 44.64179286 -38.78895468
OS 44.63717006 -38.786181
OS 44.62977358 -38.78340732
OS 44.61867886 -38.77970908
OS 44.61220694 -38.7769354
OS 44.60481046 -38.77508628
OS 44.59648942 -38.7723126
OS 44.58724382 -38.76953892
OS 44.57707366 -38.76676524
OS 44.56505438 -38.76399156
OS 44.56412982 -38.76399156
OS 44.56135614 -38.763067
OS 44.55673334 -38.76214244
OS 44.55118598 -38.76029332
OS 44.5437895 -38.7584442
OS 44.53546846 -38.75567052
OS 44.51790182 -38.75104772
OS 44.4975615 -38.7445758
OS 44.47814574 -38.73902844
OS 44.45965454 -38.73255652
OS 44.4513335 -38.72885828
OS 44.44486158 -38.7260846
OS 44.44301246 -38.72516004
OS 44.43931422 -38.72331092
OS 44.43376686 -38.71961268
OS 44.42637038 -38.71498988
OS 44.41804934 -38.70851796
OS 44.4097283 -38.70112148
OS 44.40140726 -38.69280044
OS 44.39401078 -38.68263028
OS 44.39308622 -38.68170572
OS 44.3912371 -38.67800748
OS 44.38846342 -38.67153556
OS 44.38568974 -38.66413908
OS 44.38291606 -38.65489348
OS 44.38014238 -38.64379876
OS 44.37829326 -38.63270404
OS 44.3773687 -38.6197602
OS 44.3773687 -38.61791108
OS 44.3773687 -38.61421284
OS 44.37829326 -38.60866548
OS 44.37921782 -38.60034444
OS 44.38106694 -38.5920234
OS 44.38291606 -38.58185324
OS 44.3866143 -38.57260764
OS 44.3912371 -38.56243748
OS 44.39216166 -38.56151292
OS 44.39401078 -38.55781468
OS 44.39678446 -38.55319188
OS 44.40140726 -38.54671996
OS 44.40695462 -38.54024804
OS 44.41342654 -38.531927
OS 44.42082302 -38.52453052
OS 44.43006862 -38.5180586
OS 44.43099318 -38.51713404
OS 44.43376686 -38.51620948
OS 44.4374651 -38.5134358
OS 44.44301246 -38.51066212
OS 44.45040894 -38.50696388
OS 44.45872998 -38.50326564
OS 44.46890014 -38.4995674
OS 44.47999486 -38.49586916
OS 44.48184398 -38.4949446
OS 44.48554222 -38.49402004
OS 44.49201414 -38.49217092
OS 44.50033518 -38.4903218
OS 44.51050534 -38.48847268
OS 44.52160006 -38.48754812
OS 44.5345439 -38.485699
OS 44.55673334 -38.485699
OS 44.5669035 -38.48662356
OE
OB 33.15968222 -38.32112732 I
OS 33.17539974 -38.32205188
OS 33.19204182 -38.32297644
OS 33.20775934 -38.32482556
OS 33.22162774 -38.32667468
OS 33.22347686 -38.32667468
OS 33.22994878 -38.3285238
OS 33.23826982 -38.33037292
OS 33.24936454 -38.3331466
OS 33.26138382 -38.3377694
OS 33.27432766 -38.34331676
OS 33.28819606 -38.34978868
OS 33.30021534 -38.35718516
OS 33.30206446 -38.35810972
OS 33.3057627 -38.3608834
OS 33.31131006 -38.36643076
OS 33.31870654 -38.37290268
OS 33.32702758 -38.38122372
OS 33.33534862 -38.39231844
OS 33.34459422 -38.40433772
OS 33.3519907 -38.41820612
OS 33.35291526 -38.42005524
OS 33.35476438 -38.42467804
OS 33.35846262 -38.43299908
OS 33.36216086 -38.4440938
OS 33.36493454 -38.45703764
OS 33.36863278 -38.4718306
OS 33.3704819 -38.48847268
OS 33.37140646 -38.50603932
OS 33.37140646 -38.50696388
OS 33.37140646 -38.50973756
OS 33.37140646 -38.5134358
OS 33.3704819 -38.51990772
OS 33.36955734 -38.52637964
OS 33.36863278 -38.53470068
OS 33.36678366 -38.54394628
OS 33.36493454 -38.55411644
OS 33.35846262 -38.57538132
OS 33.35476438 -38.58647604
OS 33.34921702 -38.59849532
OS 33.3427451 -38.6105146
OS 33.33627318 -38.62160932
OS 33.32795214 -38.63270404
OS 33.31870654 -38.64379876
OS 33.31778198 -38.64472332
OS 33.31593286 -38.64657244
OS 33.31315918 -38.64934612
OS 33.30853638 -38.6521198
OS 33.30298902 -38.6567426
OS 33.29559254 -38.6613654
OS 33.28634694 -38.66691276
OS 33.27617678 -38.67153556
OS 33.2641575 -38.67708292
OS 33.2502891 -38.68263028
OS 33.23549614 -38.68725308
OS 33.2179295 -38.69095132
OS 33.1994383 -38.69464956
OS 33.17909798 -38.69742324
OS 33.15598398 -38.69927236
OS 33.13194542 -38.70019692
OS 32.9682983 -38.70019692
OS 32.9682983 -38.95999828
OS 32.88323878 -38.95999828
OS 32.88323878 -38.32020276
OS 33.14581382 -38.32020276
OS 33.15968222 -38.32112732
OE
OB 32.75195126 -38.98403684 I
OS 32.75195126 -38.9849614
OS 32.75195126 -38.98773508
OS 32.75195126 -38.99235788
OS 32.75195126 -38.99790524
OS 32.7510267 -39.00530172
OS 32.7510267 -39.0126982
OS 32.74917758 -39.0311894
OS 32.7464039 -39.05060516
OS 32.74270566 -39.07094548
OS 32.7371583 -39.08851212
OS 32.73346006 -39.09683316
OS 32.72976182 -39.10330508
OS 32.72976182 -39.10422964
OS 32.72883726 -39.1051542
OS 32.72421446 -39.109777
OS 32.71681798 -39.11717348
OS 32.70757238 -39.12549452
OS 32.69462854 -39.13381556
OS 32.67798646 -39.14028748
OS 32.6585707 -39.14583484
OS 32.64747598 -39.1467594
OS 32.6354567 -39.14768396
OS 32.62990934 -39.14768396
OS 32.62436198 -39.1467594
OS 32.61604094 -39.1467594
OS 32.60679534 -39.14583484
OS 32.59662518 -39.14398572
OS 32.57443574 -39.13843836
OS 32.5892287 -39.07187004
OS 32.59015326 -39.07187004
OS 32.59292694 -39.0727946
OS 32.59754974 -39.07371916
OS 32.60217254 -39.07464372
OS 32.61419182 -39.0774174
OS 32.61973918 -39.07834196
OS 32.62898478 -39.07834196
OS 32.63360758 -39.0774174
OS 32.63915494 -39.07649284
OS 32.6447023 -39.07464372
OS 32.65024966 -39.07094548
OS 32.65672158 -39.06724724
OS 32.66134438 -39.06169988
OS 32.66226894 -39.06077532
OS 32.6631935 -39.05800164
OS 32.66504262 -39.05337884
OS 32.6678163 -39.04598236
OS 32.66966542 -39.0358122
OS 32.67058998 -39.02841572
OS 32.67151454 -39.0219438
OS 32.6724391 -39.01362276
OS 32.6724391 -39.0034526
OS 32.67336366 -38.99328244
OS 32.67336366 -38.98218772
OS 32.67336366 -38.49586916
OS 32.75195126 -38.49586916
OS 32.75195126 -38.98403684
OE
OB 33.77174094 -38.3100326 I
OS 33.78006198 -38.31095716
OS 33.79023214 -38.31188172
OS 33.8004023 -38.31280628
OS 33.81242158 -38.31557996
OS 33.8373847 -38.32112732
OS 33.8651215 -38.32944836
OS 33.8789899 -38.33499572
OS 33.89193374 -38.34146764
OS 33.90487758 -38.34978868
OS 33.91782142 -38.35810972
OS 33.91874598 -38.35903428
OS 33.9205951 -38.35995884
OS 33.92429334 -38.36273252
OS 33.92891614 -38.36735532
OS 33.93353894 -38.37197812
OS 33.94001086 -38.37845004
OS 33.94648278 -38.38584652
OS 33.95387926 -38.393243
OS 33.96127574 -38.4024886
OS 33.96867222 -38.41358332
OS 33.97699326 -38.42467804
OS 33.98438974 -38.43669732
OS 33.99086166 -38.45056572
OS 33.99825814 -38.46443412
OS 34.0038055 -38.47922708
OS 34.00935286 -38.49586916
OS 33.92614246 -38.51528492
OS 33.92614246 -38.51436036
OS 33.9252179 -38.51251124
OS 33.92336878 -38.508813
OS 33.92151966 -38.5041902
OS 33.91967054 -38.49864284
OS 33.91689686 -38.49124636
OS 33.90950038 -38.4764534
OS 33.90025478 -38.45981132
OS 33.88916006 -38.44316924
OS 33.87529166 -38.42745172
OS 33.8604987 -38.41358332
OS 33.85864958 -38.4117342
OS 33.85310222 -38.40803596
OS 33.84385662 -38.40341316
OS 33.83183734 -38.39694124
OS 33.81611982 -38.39139388
OS 33.79855318 -38.38584652
OS 33.7772883 -38.38214828
OS 33.7541743 -38.38122372
OS 33.74677782 -38.38122372
OS 33.74215502 -38.38214828
OS 33.7356831 -38.38214828
OS 33.72828662 -38.38307284
OS 33.71071998 -38.38584652
OS 33.69130422 -38.38954476
OS 33.6709639 -38.39601668
OS 33.64969902 -38.40526228
OS 33.63028326 -38.41728156
OS 33.6293587 -38.41728156
OS 33.62843414 -38.41913068
OS 33.62196222 -38.42375348
OS 33.61364118 -38.43114996
OS 33.60347102 -38.44224468
OS 33.59145174 -38.45611308
OS 33.58035702 -38.4718306
OS 33.57018686 -38.49124636
OS 33.56094126 -38.51251124
OS 33.56094126 -38.5134358
OS 33.5600167 -38.51528492
OS 33.55909214 -38.5180586
OS 33.55816758 -38.5226814
OS 33.55631846 -38.52822876
OS 33.55446934 -38.53470068
OS 33.55169566 -38.5504182
OS 33.54799742 -38.5689094
OS 33.54429918 -38.58924972
OS 33.54245006 -38.61143916
OS 33.5415255 -38.63547772
OS 33.5415255 -38.63640228
OS 33.5415255 -38.63917596
OS 33.5415255 -38.64379876
OS 33.5415255 -38.64934612
OS 33.54245006 -38.65581804
OS 33.54245006 -38.66413908
OS 33.54337462 -38.67338468
OS 33.54429918 -38.68355484
OS 33.54707286 -38.70574428
OS 33.55169566 -38.72978284
OS 33.55724302 -38.7538214
OS 33.5646395 -38.77785996
OS 33.5646395 -38.77878452
OS 33.56556406 -38.78063364
OS 33.56741318 -38.78340732
OS 33.5692623 -38.78803012
OS 33.57480966 -38.79912484
OS 33.5831307 -38.81206868
OS 33.59330086 -38.82686164
OS 33.6062447 -38.84257916
OS 33.62103766 -38.85644756
OS 33.6386043 -38.8693914
OS 33.63952886 -38.8693914
OS 33.64137798 -38.87031596
OS 33.64415166 -38.87216508
OS 33.6478499 -38.8740142
OS 33.6524727 -38.87586332
OS 33.65802006 -38.878637
OS 33.6709639 -38.88418436
OS 33.68760598 -38.88973172
OS 33.70609718 -38.89435452
OS 33.7264375 -38.89805276
OS 33.74770238 -38.89897732
OS 33.7541743 -38.89897732
OS 33.75972166 -38.89805276
OS 33.76619358 -38.89805276
OS 33.7726655 -38.8971282
OS 33.78930758 -38.89342996
OS 33.80872334 -38.88880716
OS 33.8281391 -38.88141068
OS 33.84847942 -38.87124052
OS 33.85864958 -38.86569316
OS 33.86789518 -38.85829668
OS 33.86881974 -38.85737212
OS 33.8697443 -38.85644756
OS 33.87251798 -38.85367388
OS 33.87621622 -38.8509002
OS 33.87991446 -38.8462774
OS 33.88453726 -38.84073004
OS 33.89008462 -38.83518268
OS 33.89470742 -38.8277862
OS 33.90025478 -38.81946516
OS 33.9067267 -38.81021956
OS 33.91227406 -38.80097396
OS 33.91782142 -38.78987924
OS 33.92244422 -38.77785996
OS 33.92706702 -38.76491612
OS 33.93168982 -38.75104772
OS 33.93538806 -38.73625476
OS 34.02044758 -38.75751964
OS 34.02044758 -38.7584442
OS 34.01952302 -38.76214244
OS 34.0176739 -38.7676898
OS 34.01490022 -38.77508628
OS 34.01212654 -38.78340732
OS 34.0084283 -38.79357748
OS 34.0038055 -38.8046722
OS 33.99825814 -38.81669148
OS 33.9853143 -38.84257916
OS 33.96867222 -38.86846684
OS 33.95850206 -38.88141068
OS 33.9483319 -38.89435452
OS 33.93723718 -38.90544924
OS 33.92429334 -38.91654396
OS 33.92336878 -38.91746852
OS 33.92151966 -38.91931764
OS 33.91689686 -38.92116676
OS 33.91227406 -38.924865
OS 33.90487758 -38.9294878
OS 33.8974811 -38.9341106
OS 33.88731094 -38.9387334
OS 33.87714078 -38.9433562
OS 33.8651215 -38.94890356
OS 33.85217766 -38.95352636
OS 33.83830926 -38.95814916
OS 33.8235163 -38.96277196
OS 33.80779878 -38.9664702
OS 33.7911567 -38.96831932
OS 33.77359006 -38.97016844
OS 33.75509886 -38.971093
OS 33.7449287 -38.971093
OS 33.73753222 -38.97016844
OS 33.72921118 -38.97016844
OS 33.71904102 -38.96924388
OS 33.7079463 -38.96739476
OS 33.69500246 -38.96554564
OS 33.66819022 -38.96092284
OS 33.64045342 -38.95352636
OS 33.61271662 -38.9433562
OS 33.59977278 -38.93688428
OS 33.58682894 -38.9294878
OS 33.58590438 -38.92856324
OS 33.58405526 -38.92763868
OS 33.58035702 -38.924865
OS 33.57665878 -38.92116676
OS 33.57111142 -38.91746852
OS 33.5646395 -38.91192116
OS 33.55724302 -38.90544924
OS 33.54984654 -38.89805276
OS 33.54245006 -38.88973172
OS 33.53412902 -38.88141068
OS 33.51748694 -38.8601458
OS 33.50176942 -38.83518268
OS 33.48790102 -38.80744588
OS 33.48790102 -38.80652132
OS 33.4860519 -38.80374764
OS 33.48512734 -38.79912484
OS 33.48235366 -38.79357748
OS 33.48050454 -38.786181
OS 33.47773086 -38.7769354
OS 33.47403262 -38.76676524
OS 33.47125894 -38.75567052
OS 33.46848526 -38.74365124
OS 33.46478702 -38.72978284
OS 33.46016422 -38.70112148
OS 33.45646598 -38.66876188
OS 33.45461686 -38.63547772
OS 33.45461686 -38.63455316
OS 33.45461686 -38.63085492
OS 33.45461686 -38.62530756
OS 33.45554142 -38.61883564
OS 33.45554142 -38.60959004
OS 33.45646598 -38.60034444
OS 33.45739054 -38.58832516
OS 33.45923966 -38.57630588
OS 33.46386246 -38.54949364
OS 33.47033438 -38.51990772
OS 33.47957998 -38.4903218
OS 33.49252382 -38.46166044
OS 33.49344838 -38.46073588
OS 33.49437294 -38.4579622
OS 33.49622206 -38.45426396
OS 33.4999203 -38.44964116
OS 33.50361854 -38.44316924
OS 33.50824134 -38.43577276
OS 33.52026062 -38.41913068
OS 33.53597814 -38.40063948
OS 33.55446934 -38.38214828
OS 33.57573422 -38.36365708
OS 33.60069734 -38.34793956
OS 33.6016219 -38.347015
OS 33.60439558 -38.34609044
OS 33.60809382 -38.34424132
OS 33.61271662 -38.34146764
OS 33.6201131 -38.33869396
OS 33.62750958 -38.33592028
OS 33.63675518 -38.33222204
OS 33.64692534 -38.3285238
OS 33.65802006 -38.32482556
OS 33.67003934 -38.32112732
OS 33.69592702 -38.31557996
OS 33.72551294 -38.31095716
OS 33.75602342 -38.30910804
OS 33.76526902 -38.30910804
OS 33.77174094 -38.3100326
OE
OB 35.15858094 -39.1375138 I
OS 34.63805366 -39.1375138
OS 34.63805366 -39.08111564
OS 35.15858094 -39.08111564
OS 35.15858094 -39.1375138
OE
OB 34.37917686 -38.32112732 I
OS 34.38657334 -38.32112732
OS 34.40321542 -38.32297644
OS 34.42170662 -38.32482556
OS 34.44112238 -38.3285238
OS 34.46053814 -38.3331466
OS 34.47810478 -38.33961852
OS 34.47902934 -38.33961852
OS 34.4799539 -38.34054308
OS 34.48550126 -38.34331676
OS 34.4938223 -38.34793956
OS 34.5030679 -38.35441148
OS 34.51416262 -38.36273252
OS 34.5261819 -38.37290268
OS 34.53727662 -38.38584652
OS 34.54744678 -38.39971492
OS 34.54837134 -38.40156404
OS 34.55114502 -38.4071114
OS 34.55576782 -38.41450788
OS 34.56039062 -38.4256026
OS 34.56501342 -38.43854644
OS 34.56963622 -38.45241484
OS 34.5724099 -38.46813236
OS 34.57333446 -38.48384988
OS 34.57333446 -38.485699
OS 34.57333446 -38.4903218
OS 34.5724099 -38.49864284
OS 34.57056078 -38.508813
OS 34.5677871 -38.52083228
OS 34.5631643 -38.53377612
OS 34.55761694 -38.54671996
OS 34.55022046 -38.56058836
OS 34.5492959 -38.56243748
OS 34.54652222 -38.56613572
OS 34.54097486 -38.5735322
OS 34.53357838 -38.58092868
OS 34.52433278 -38.59017428
OS 34.51323806 -38.60034444
OS 34.49936966 -38.60959004
OS 34.48365214 -38.61883564
OS 34.4845767 -38.61883564
OS 34.48642582 -38.6197602
OS 34.4891995 -38.62068476
OS 34.49289774 -38.62253388
OS 34.50399246 -38.62623212
OS 34.5169363 -38.63270404
OS 34.5308047 -38.64102508
OS 34.54652222 -38.65119524
OS 34.56039062 -38.66321452
OS 34.57333446 -38.67800748
OS 34.57425902 -38.6798566
OS 34.57795726 -38.68540396
OS 34.58350462 -38.693725
OS 34.58905198 -38.70481972
OS 34.59459934 -38.71961268
OS 34.6001467 -38.7353302
OS 34.60384494 -38.7538214
OS 34.6047695 -38.77416172
OS 34.6047695 -38.77508628
OS 34.6047695 -38.77601084
OS 34.6047695 -38.7815582
OS 34.60384494 -38.7908038
OS 34.60199582 -38.80189852
OS 34.6001467 -38.81484236
OS 34.59644846 -38.82871076
OS 34.59182566 -38.84350372
OS 34.58535374 -38.85829668
OS 34.58442918 -38.8601458
OS 34.5816555 -38.8647686
OS 34.57795726 -38.87124052
OS 34.5724099 -38.88048612
OS 34.56501342 -38.88973172
OS 34.55761694 -38.89990188
OS 34.54837134 -38.91007204
OS 34.53820118 -38.91839308
OS 34.53727662 -38.91931764
OS 34.53357838 -38.92209132
OS 34.52710646 -38.92578956
OS 34.51878542 -38.9294878
OS 34.50861526 -38.93503516
OS 34.49659598 -38.94058252
OS 34.48365214 -38.94520532
OS 34.46793462 -38.94982812
OS 34.4660855 -38.94982812
OS 34.46053814 -38.95167724
OS 34.45129254 -38.9526018
OS 34.43927326 -38.95445092
OS 34.4244803 -38.95630004
OS 34.40691366 -38.95814916
OS 34.3874979 -38.95907372
OS 34.36530846 -38.95999828
OS 34.12122462 -38.95999828
OS 34.12122462 -38.32020276
OS 34.37270494 -38.32020276
OS 34.37917686 -38.32112732
OE
OB 31.74233174 -38.95999828 I
OS 31.65264942 -38.95999828
OS 31.65264942 -38.87031596
OS 31.74233174 -38.87031596
OS 31.74233174 -38.95999828
OE
OB 31.52968294 -38.42745172 I
OS 31.50841806 -38.54671996
OS 31.45941638 -38.54671996
OS 31.44000062 -38.42745172
OS 31.44000062 -38.32020276
OS 31.52968294 -38.32020276
OS 31.52968294 -38.42745172
OE
OB 32.0992119 -38.48662356 I
OS 32.10568382 -38.48754812
OS 32.11955222 -38.48939724
OS 32.1361943 -38.49309548
OS 32.15376094 -38.49864284
OS 32.17132758 -38.50696388
OS 32.18889422 -38.51713404
OS 32.18981878 -38.51713404
OS 32.19074334 -38.51898316
OS 32.1962907 -38.5226814
OS 32.20461174 -38.53007788
OS 32.2147819 -38.53932348
OS 32.22587662 -38.55134276
OS 32.23697134 -38.56613572
OS 32.24806606 -38.58370236
OS 32.25731166 -38.60311812
OS 32.25731166 -38.60404268
OS 32.25823622 -38.6058918
OS 32.25916078 -38.60866548
OS 32.2610099 -38.61236372
OS 32.26285902 -38.61791108
OS 32.26470814 -38.624383
OS 32.26933094 -38.63917596
OS 32.27395374 -38.65766716
OS 32.27765198 -38.67800748
OS 32.28042566 -38.70112148
OS 32.28135022 -38.72516004
OS 32.28135022 -38.7260846
OS 32.28135022 -38.72793372
OS 32.28135022 -38.73163196
OS 32.28135022 -38.73717932
OS 32.28042566 -38.74365124
OS 32.28042566 -38.75104772
OS 32.27857654 -38.7676898
OS 32.2748783 -38.78803012
OS 32.2702555 -38.809295
OS 32.26378358 -38.83148444
OS 32.25546254 -38.85367388
OS 32.25546254 -38.85459844
OS 32.25453798 -38.85644756
OS 32.25268886 -38.85922124
OS 32.25083974 -38.86291948
OS 32.24436782 -38.87308964
OS 32.23604678 -38.88603348
OS 32.22587662 -38.89990188
OS 32.21293278 -38.91377028
OS 32.19813982 -38.92763868
OS 32.18057318 -38.94058252
OS 32.17964862 -38.94058252
OS 32.17872406 -38.94150708
OS 32.17595038 -38.9433562
OS 32.17225214 -38.94520532
OS 32.16300654 -38.94982812
OS 32.1500627 -38.95537548
OS 32.13434518 -38.96092284
OS 32.1177031 -38.96554564
OS 32.09828734 -38.96924388
OS 32.07887158 -38.97016844
OS 32.07239966 -38.97016844
OS 32.06500318 -38.96924388
OS 32.05575758 -38.96831932
OS 32.04466286 -38.9664702
OS 32.03264358 -38.96369652
OS 32.0206243 -38.95999828
OS 32.00860502 -38.95445092
OS 32.00768046 -38.95352636
OS 32.00305766 -38.95167724
OS 31.9975103 -38.947979
OS 31.99011382 -38.94243164
OS 31.98271734 -38.93688428
OS 31.97347174 -38.9294878
OS 31.9651507 -38.92116676
OS 31.95775422 -38.91192116
OS 31.95775422 -39.1375138
OS 31.87916662 -39.1375138
OS 31.87916662 -38.49586916
OS 31.95035774 -38.49586916
OS 31.95035774 -38.55689012
OS 31.9512823 -38.555041
OS 31.95498054 -38.55134276
OS 31.95960334 -38.54487084
OS 31.96699982 -38.53747436
OS 31.97532086 -38.52822876
OS 31.98456646 -38.51990772
OS 31.99566118 -38.51158668
OS 32.0067559 -38.5041902
OS 32.00860502 -38.50326564
OS 32.01230326 -38.50141652
OS 32.01969974 -38.49864284
OS 32.02894534 -38.4949446
OS 32.04004006 -38.49124636
OS 32.0529839 -38.48847268
OS 32.06777686 -38.48662356
OS 32.08441894 -38.485699
OS 32.0945891 -38.485699
OS 32.0992119 -38.48662356
OE
OB 32.5614919 -38.48662356 I
OS 32.57166206 -38.48847268
OS 32.58368134 -38.49217092
OS 32.59662518 -38.49679372
OS 32.61141814 -38.50326564
OS 32.62713566 -38.51158668
OS 32.5984743 -38.58370236
OS 32.59754974 -38.5827778
OS 32.5938515 -38.58092868
OS 32.58830414 -38.578155
OS 32.58090766 -38.57538132
OS 32.57258662 -38.57260764
OS 32.56241646 -38.56983396
OS 32.5522463 -38.56798484
OS 32.54207614 -38.56706028
OS 32.53745334 -38.56706028
OS 32.53283054 -38.56798484
OS 32.52635862 -38.5689094
OS 32.5198867 -38.57075852
OS 32.51156566 -38.5735322
OS 32.50324462 -38.57723044
OS 32.49584814 -38.5827778
OS 32.49492358 -38.58370236
OS 32.4921499 -38.58555148
OS 32.48937622 -38.58924972
OS 32.48475342 -38.59387252
OS 32.48013062 -38.60034444
OS 32.47550782 -38.60774092
OS 32.47088502 -38.61606196
OS 32.46718678 -38.62623212
OS 32.46626222 -38.62808124
OS 32.46533766 -38.6336286
OS 32.46348854 -38.64194964
OS 32.46071486 -38.65304436
OS 32.45794118 -38.66691276
OS 32.45609206 -38.68263028
OS 32.4551675 -38.69927236
OS 32.45424294 -38.71776356
OS 32.45424294 -38.95999828
OS 32.37565534 -38.95999828
OS 32.37565534 -38.49586916
OS 32.44684646 -38.49586916
OS 32.44684646 -38.56613572
OS 32.44777102 -38.56521116
OS 32.45146926 -38.55873924
OS 32.45609206 -38.5504182
OS 32.46348854 -38.54024804
OS 32.47088502 -38.53007788
OS 32.47920606 -38.51898316
OS 32.4875271 -38.50973756
OS 32.49584814 -38.50234108
OS 32.4967727 -38.50141652
OS 32.49954638 -38.4995674
OS 32.50509374 -38.49679372
OS 32.5106411 -38.49402004
OS 32.51803758 -38.49124636
OS 32.52728318 -38.48847268
OS 32.53652878 -38.48662356
OS 32.54669894 -38.485699
OS 32.55317086 -38.485699
OS 32.5614919 -38.48662356
OE
OB 32.75195126 -38.4117342 I
OS 32.67336366 -38.4117342
OS 32.67336366 -38.32020276
OS 32.75195126 -38.32020276
OS 32.75195126 -38.4117342
OE
OB 36.56668582 -38.95999828 I
OS 36.47885262 -38.95999828
OS 36.1441619 -38.4579622
OS 36.1441619 -38.95999828
OS 36.06280062 -38.95999828
OS 36.06280062 -38.32020276
OS 36.14970926 -38.32020276
OS 36.48532454 -38.8231634
OS 36.48532454 -38.32020276
OS 36.56668582 -38.32020276
OS 36.56668582 -38.95999828
OE
OB 35.74382742 -38.32112732 I
OS 35.75954494 -38.32205188
OS 35.77618702 -38.32297644
OS 35.79190454 -38.32482556
OS 35.80577294 -38.32667468
OS 35.80762206 -38.32667468
OS 35.81409398 -38.3285238
OS 35.82241502 -38.33037292
OS 35.83350974 -38.3331466
OS 35.84552902 -38.3377694
OS 35.85847286 -38.34331676
OS 35.87234126 -38.34978868
OS 35.88436054 -38.35718516
OS 35.88620966 -38.35810972
OS 35.8899079 -38.3608834
OS 35.89545526 -38.36643076
OS 35.90285174 -38.37290268
OS 35.91117278 -38.38122372
OS 35.91949382 -38.39231844
OS 35.92873942 -38.40433772
OS 35.9361359 -38.41820612
OS 35.93706046 -38.42005524
OS 35.93890958 -38.42467804
OS 35.94260782 -38.43299908
OS 35.94630606 -38.4440938
OS 35.94907974 -38.45703764
OS 35.95277798 -38.4718306
OS 35.9546271 -38.48847268
OS 35.95555166 -38.50603932
OS 35.95555166 -38.50696388
OS 35.95555166 -38.50973756
OS 35.95555166 -38.5134358
OS 35.9546271 -38.51990772
OS 35.95370254 -38.52637964
OS 35.95277798 -38.53470068
OS 35.95092886 -38.54394628
OS 35.94907974 -38.55411644
OS 35.94260782 -38.57538132
OS 35.93890958 -38.58647604
OS 35.93336222 -38.59849532
OS 35.9268903 -38.6105146
OS 35.92041838 -38.62160932
OS 35.91209734 -38.63270404
OS 35.90285174 -38.64379876
OS 35.90192718 -38.64472332
OS 35.90007806 -38.64657244
OS 35.89730438 -38.64934612
OS 35.89268158 -38.6521198
OS 35.88713422 -38.6567426
OS 35.87973774 -38.6613654
OS 35.87049214 -38.66691276
OS 35.86032198 -38.67153556
OS 35.8483027 -38.67708292
OS 35.8344343 -38.68263028
OS 35.81964134 -38.68725308
OS 35.8020747 -38.69095132
OS 35.7835835 -38.69464956
OS 35.76324318 -38.69742324
OS 35.74012918 -38.69927236
OS 35.71609062 -38.70019692
OS 35.5524435 -38.70019692
OS 35.5524435 -38.95999828
OS 35.46738398 -38.95999828
OS 35.46738398 -38.32020276
OS 35.72995902 -38.32020276
OS 35.74382742 -38.32112732
OE
OB 36.76916446 -38.42745172 I
OS 36.74789958 -38.54671996
OS 36.6988979 -38.54671996
OS 36.67948214 -38.42745172
OS 36.67948214 -38.32020276
OS 36.76916446 -38.32020276
OS 36.76916446 -38.42745172
OE
OB 38.2382903 -38.39601668 I
OS 37.86014526 -38.39601668
OS 37.86014526 -38.59109884
OS 38.21425174 -38.59109884
OS 38.21425174 -38.66691276
OS 37.86014526 -38.66691276
OS 37.86014526 -38.88418436
OS 38.25308326 -38.88418436
OS 38.25308326 -38.95999828
OS 37.77508574 -38.95999828
OS 37.77508574 -38.32020276
OS 38.2382903 -38.32020276
OS 38.2382903 -38.39601668
OE
OB 37.4339231 -38.32112732 I
OS 37.44224414 -38.32112732
OS 37.4616599 -38.32205188
OS 37.48200022 -38.32482556
OS 37.50418966 -38.32759924
OS 37.52452998 -38.33222204
OS 37.53470014 -38.33499572
OS 37.54302118 -38.3377694
OS 37.54394574 -38.3377694
OS 37.5448703 -38.33869396
OS 37.55041766 -38.34146764
OS 37.5587387 -38.34516588
OS 37.56890886 -38.3516378
OS 37.58000358 -38.35995884
OS 37.59202286 -38.37105356
OS 37.60311758 -38.3839974
OS 37.6142123 -38.39879036
OS 37.6142123 -38.39971492
OS 37.61513686 -38.40063948
OS 37.6188351 -38.40618684
OS 37.62253334 -38.41543244
OS 37.6280807 -38.42745172
OS 37.6327035 -38.44132012
OS 37.6373263 -38.4579622
OS 37.64009998 -38.47552884
OS 37.64102454 -38.4949446
OS 37.64102454 -38.49586916
OS 37.64102454 -38.49771828
OS 37.64102454 -38.50141652
OS 37.64009998 -38.50603932
OS 37.64009998 -38.51251124
OS 37.63917542 -38.51898316
OS 37.63547718 -38.53470068
OS 37.62992982 -38.55319188
OS 37.62253334 -38.57260764
OS 37.61143862 -38.5920234
OS 37.60404214 -38.601269
OS 37.59664566 -38.6105146
OS 37.5957211 -38.61143916
OS 37.59479654 -38.61236372
OS 37.59202286 -38.6151374
OS 37.58832462 -38.61791108
OS 37.58370182 -38.62160932
OS 37.57815446 -38.62530756
OS 37.57075798 -38.62993036
OS 37.5633615 -38.63547772
OS 37.5541159 -38.64010052
OS 37.54394574 -38.64472332
OS 37.53285102 -38.65027068
OS 37.52083174 -38.65489348
OS 37.50696334 -38.65859172
OS 37.49309494 -38.66321452
OS 37.47737742 -38.6659882
OS 37.46073534 -38.66876188
OS 37.46258446 -38.66968644
OS 37.4662827 -38.67153556
OS 37.47183006 -38.6752338
OS 37.47922654 -38.67893204
OS 37.49586862 -38.6891022
OS 37.50418966 -38.69557412
OS 37.51158614 -38.70112148
OS 37.51343526 -38.7029706
OS 37.51805806 -38.7075934
OS 37.52545454 -38.71498988
OS 37.53470014 -38.72423548
OS 37.5448703 -38.73717932
OS 37.55688958 -38.75104772
OS 37.56890886 -38.7676898
OS 37.5818527 -38.786181
OS 37.69187534 -38.95999828
OS 37.5864755 -38.95999828
OS 37.50234054 -38.82686164
OS 37.50234054 -38.82593708
OS 37.50049142 -38.82408796
OS 37.4986423 -38.82131428
OS 37.49586862 -38.81761604
OS 37.4893967 -38.80744588
OS 37.48107566 -38.79450204
OS 37.4709055 -38.78063364
OS 37.46073534 -38.76584068
OS 37.45056518 -38.75197228
OS 37.44131958 -38.73902844
OS 37.44039502 -38.73810388
OS 37.43762134 -38.73440564
OS 37.43299854 -38.72885828
OS 37.42652662 -38.72238636
OS 37.41265822 -38.70851796
OS 37.40526174 -38.70204604
OS 37.39786526 -38.69649868
OS 37.3969407 -38.69557412
OS 37.39509158 -38.69464956
OS 37.39139334 -38.69280044
OS 37.38584598 -38.69002676
OS 37.38029862 -38.68725308
OS 37.3738267 -38.6844794
OS 37.35903374 -38.6798566
OS 37.35810918 -38.6798566
OS 37.35626006 -38.67893204
OS 37.35256182 -38.67893204
OS 37.34793902 -38.67800748
OS 37.3414671 -38.67708292
OS 37.33407062 -38.67708292
OS 37.32390046 -38.67615836
OS 37.21480238 -38.67615836
OS 37.21480238 -38.95999828
OS 37.12974286 -38.95999828
OS 37.12974286 -38.32020276
OS 37.42652662 -38.32020276
OS 37.4339231 -38.32112732
OE
OB 35.31760526 -38.95999828 I
OS 35.23254574 -38.95999828
OS 35.23254574 -38.32020276
OS 35.31760526 -38.32020276
OS 35.31760526 -38.95999828
OE
OB 42.12051774 -38.66413908 H
OS 41.95224782 -38.66413908
OS 41.95224782 -38.88418436
OS 42.13438614 -38.88418436
OS 42.1538019 -38.8832598
OS 42.16212294 -38.88233524
OS 42.16951942 -38.88141068
OS 42.17044398 -38.88141068
OS 42.17414222 -38.88048612
OS 42.17968958 -38.87956156
OS 42.1861615 -38.87771244
OS 42.20187902 -38.87216508
OS 42.21759654 -38.8647686
OS 42.2185211 -38.86384404
OS 42.22129478 -38.86199492
OS 42.22499302 -38.85922124
OS 42.22961582 -38.855523
OS 42.23423862 -38.84997564
OS 42.24071054 -38.84442828
OS 42.24533334 -38.8370318
OS 42.2508807 -38.82871076
OS 42.25180526 -38.8277862
OS 42.25272982 -38.82501252
OS 42.25457894 -38.81946516
OS 42.25735262 -38.81299324
OS 42.2601263 -38.80559676
OS 42.26197542 -38.79635116
OS 42.26289998 -38.78525644
OS 42.26382454 -38.77416172
OS 42.26382454 -38.7723126
OS 42.26382454 -38.76861436
OS 42.26289998 -38.76121788
OS 42.26105086 -38.75289684
OS 42.25920174 -38.74365124
OS 42.2555035 -38.73348108
OS 42.2508807 -38.72331092
OS 42.24440878 -38.71314076
OS 42.24348422 -38.7122162
OS 42.24071054 -38.70851796
OS 42.2370123 -38.70389516
OS 42.23146494 -38.6983478
OS 42.22406846 -38.69187588
OS 42.21482286 -38.68540396
OS 42.2046527 -38.6798566
OS 42.19263342 -38.6752338
OS 42.1907843 -38.67430924
OS 42.18708606 -38.67338468
OS 42.17876502 -38.67153556
OS 42.16859486 -38.66968644
OS 42.15565102 -38.66783732
OS 42.1399335 -38.6659882
OS 42.12051774 -38.66413908
OE
OB 45.22981302 -38.5504182 H
OS 45.22426566 -38.5504182
OS 45.21964286 -38.55134276
OS 45.2094727 -38.55226732
OS 45.1956043 -38.55596556
OS 45.17988678 -38.56151292
OS 45.1632447 -38.5689094
OS 45.14752718 -38.58000412
OS 45.13920614 -38.5874006
OS 45.13180966 -38.59479708
OS 45.13180966 -38.59572164
OS 45.12996054 -38.5966462
OS 45.12811142 -38.59941988
OS 45.12533774 -38.60311812
OS 45.12256406 -38.60774092
OS 45.11979038 -38.61328828
OS 45.11609214 -38.62068476
OS 45.1123939 -38.62808124
OS 45.10869566 -38.63732684
OS 45.10499742 -38.64657244
OS 45.10222374 -38.65766716
OS 45.09945006 -38.66968644
OS 45.09667638 -38.68263028
OS 45.09482726 -38.69649868
OS 45.0939027 -38.7122162
OS 45.09297814 -38.72793372
OS 45.09297814 -38.72885828
OS 45.09297814 -38.73163196
OS 45.09297814 -38.73625476
OS 45.0939027 -38.74272668
OS 45.0939027 -38.75012316
OS 45.09482726 -38.7584442
OS 45.09760094 -38.77785996
OS 45.10222374 -38.8000494
OS 45.10962022 -38.82223884
OS 45.11886582 -38.84350372
OS 45.12533774 -38.85274932
OS 45.13180966 -38.86199492
OS 45.13273422 -38.86199492
OS 45.13365878 -38.86384404
OS 45.13920614 -38.86846684
OS 45.14752718 -38.87586332
OS 45.1586219 -38.8832598
OS 45.1724903 -38.89158084
OS 45.18913238 -38.89897732
OS 45.20854814 -38.90360012
OS 45.2187183 -38.90452468
OS 45.22981302 -38.90544924
OS 45.23536038 -38.90544924
OS 45.23998318 -38.90452468
OS 45.25015334 -38.90267556
OS 45.26402174 -38.89990188
OS 45.2788147 -38.89435452
OS 45.29545678 -38.88695804
OS 45.3111743 -38.87586332
OS 45.31949534 -38.86846684
OS 45.32689182 -38.86107036
OS 45.32781638 -38.8601458
OS 45.32874094 -38.85922124
OS 45.33059006 -38.85644756
OS 45.33336374 -38.85274932
OS 45.33613742 -38.84812652
OS 45.33983566 -38.84257916
OS 45.3435339 -38.83518268
OS 45.34723214 -38.8277862
OS 45.35093038 -38.8185406
OS 45.35370406 -38.80837044
OS 45.3574023 -38.79727572
OS 45.36017598 -38.78525644
OS 45.36294966 -38.77138804
OS 45.36479878 -38.75751964
OS 45.3666479 -38.74180212
OS 45.3666479 -38.72516004
OS 45.3666479 -38.72423548
OS 45.3666479 -38.7214618
OS 45.3666479 -38.716839
OS 45.36572334 -38.71129164
OS 45.36572334 -38.70389516
OS 45.36479878 -38.69557412
OS 45.3620251 -38.67615836
OS 45.3574023 -38.65581804
OS 45.35000582 -38.6336286
OS 45.33983566 -38.61328828
OS 45.3342883 -38.60311812
OS 45.32689182 -38.59479708
OS 45.32689182 -38.59387252
OS 45.3250427 -38.59294796
OS 45.31949534 -38.5874006
OS 45.3111743 -38.58092868
OS 45.30007958 -38.57260764
OS 45.28621118 -38.5642866
OS 45.2695691 -38.55689012
OS 45.2510779 -38.55226732
OS 45.24090774 -38.55134276
OS 45.22981302 -38.5504182
OE
OB 32.07702246 -38.54764452 H
OS 32.07239966 -38.54764452
OS 32.06870142 -38.54856908
OS 32.05945582 -38.5504182
OS 32.04743654 -38.55319188
OS 32.03356814 -38.55873924
OS 32.01877518 -38.56706028
OS 32.01045414 -38.57260764
OS 32.00305766 -38.57907956
OS 31.99566118 -38.58647604
OS 31.9882647 -38.59479708
OS 31.9882647 -38.59572164
OS 31.98641558 -38.5966462
OS 31.98456646 -38.59941988
OS 31.98271734 -38.60311812
OS 31.97994366 -38.60866548
OS 31.97624542 -38.61421284
OS 31.97254718 -38.62160932
OS 31.9697735 -38.6290058
OS 31.96607526 -38.6382514
OS 31.96237702 -38.64842156
OS 31.95960334 -38.65951628
OS 31.9559051 -38.67153556
OS 31.95405598 -38.68540396
OS 31.95220686 -38.69927236
OS 31.95035774 -38.71406532
OS 31.95035774 -38.7307074
OS 31.95035774 -38.73163196
OS 31.95035774 -38.73440564
OS 31.95035774 -38.73902844
OS 31.9512823 -38.74550036
OS 31.9512823 -38.75289684
OS 31.95220686 -38.76121788
OS 31.95498054 -38.78063364
OS 31.95960334 -38.80282308
OS 31.9651507 -38.82408796
OS 31.9743963 -38.84535284
OS 31.97994366 -38.85459844
OS 31.98641558 -38.86291948
OS 31.9882647 -38.8647686
OS 31.9928875 -38.8693914
OS 32.00028398 -38.87678788
OS 32.01045414 -38.88418436
OS 32.02339798 -38.89158084
OS 32.03819094 -38.89897732
OS 32.05483302 -38.90360012
OS 32.06407862 -38.90452468
OS 32.07332422 -38.90544924
OS 32.07887158 -38.90544924
OS 32.08256982 -38.90452468
OS 32.09181542 -38.90267556
OS 32.10475926 -38.89990188
OS 32.11862766 -38.89435452
OS 32.13342062 -38.88695804
OS 32.14821358 -38.87586332
OS 32.15561006 -38.8693914
OS 32.16300654 -38.86199492
OS 32.16300654 -38.86107036
OS 32.16485566 -38.8601458
OS 32.16670478 -38.85737212
OS 32.1685539 -38.85367388
OS 32.17225214 -38.84905108
OS 32.17502582 -38.84257916
OS 32.17872406 -38.83610724
OS 32.1824223 -38.8277862
OS 32.18519598 -38.81946516
OS 32.18889422 -38.80837044
OS 32.19259246 -38.79727572
OS 32.19536614 -38.78525644
OS 32.19721526 -38.77138804
OS 32.19906438 -38.75659508
OS 32.2009135 -38.74087756
OS 32.2009135 -38.72423548
OS 32.2009135 -38.72331092
OS 32.2009135 -38.72053724
OS 32.2009135 -38.71591444
OS 32.19998894 -38.70944252
OS 32.19998894 -38.70204604
OS 32.19906438 -38.693725
OS 32.1962907 -38.67430924
OS 32.1916679 -38.65304436
OS 32.18519598 -38.63177948
OS 32.17595038 -38.6105146
OS 32.17040302 -38.60034444
OS 32.1639311 -38.5920234
OS 32.1639311 -38.59109884
OS 32.16208198 -38.59017428
OS 32.15745918 -38.58462692
OS 32.1500627 -38.578155
OS 32.13989254 -38.56983396
OS 32.1269487 -38.56151292
OS 32.11215574 -38.55411644
OS 32.09551366 -38.54949364
OS 32.08626806 -38.54856908
OS 32.07702246 -38.54764452
OE
OB 42.10387566 -38.39601668 H
OS 41.95224782 -38.39601668
OS 41.95224782 -38.58832516
OS 42.10942302 -38.58832516
OS 42.1214423 -38.5874006
OS 42.13438614 -38.58647604
OS 42.14732998 -38.58555148
OS 42.16027382 -38.58370236
OS 42.17044398 -38.58185324
OS 42.1722931 -38.58092868
OS 42.17599134 -38.58000412
OS 42.1815387 -38.57723044
OS 42.18893518 -38.5735322
OS 42.19633166 -38.56983396
OS 42.2046527 -38.5642866
OS 42.21297374 -38.55689012
OS 42.21944566 -38.54949364
OS 42.22037022 -38.54856908
OS 42.22221934 -38.5457954
OS 42.22499302 -38.54024804
OS 42.2277667 -38.53377612
OS 42.23054038 -38.52637964
OS 42.23331406 -38.51713404
OS 42.23516318 -38.50603932
OS 42.23608774 -38.49402004
OS 42.23608774 -38.49217092
OS 42.23608774 -38.48847268
OS 42.23516318 -38.48292532
OS 42.23423862 -38.47552884
OS 42.2323895 -38.46628324
OS 42.22961582 -38.45703764
OS 42.22591758 -38.44779204
OS 42.22037022 -38.43854644
OS 42.21944566 -38.43762188
OS 42.21759654 -38.4348482
OS 42.2138983 -38.4302254
OS 42.2092755 -38.4256026
OS 42.20280358 -38.42005524
OS 42.1954071 -38.41450788
OS 42.1861615 -38.40896052
OS 42.17599134 -38.40526228
OS 42.17506678 -38.40526228
OS 42.17044398 -38.40341316
OS 42.16397206 -38.4024886
OS 42.1538019 -38.40063948
OS 42.1399335 -38.39879036
OS 42.12421598 -38.3978658
OS 42.10387566 -38.39601668
OE
OB 37.41635646 -38.39139388 H
OS 37.21480238 -38.39139388
OS 37.21480238 -38.60311812
OS 37.40526174 -38.60311812
OS 37.41635646 -38.60219356
OS 37.4293003 -38.601269
OS 37.44409326 -38.60034444
OS 37.45888622 -38.59849532
OS 37.47367918 -38.59572164
OS 37.48662302 -38.5920234
OS 37.48847214 -38.59109884
OS 37.49217038 -38.58924972
OS 37.49771774 -38.58647604
OS 37.50511422 -38.5827778
OS 37.51343526 -38.57723044
OS 37.5217563 -38.57075852
OS 37.53007734 -38.56243748
OS 37.53654926 -38.55319188
OS 37.53747382 -38.55226732
OS 37.53932294 -38.54856908
OS 37.54209662 -38.54302172
OS 37.54579486 -38.53562524
OS 37.54856854 -38.5273042
OS 37.55134222 -38.5180586
OS 37.55319134 -38.50696388
OS 37.5541159 -38.49586916
OS 37.5541159 -38.4949446
OS 37.5541159 -38.49402004
OS 37.55319134 -38.48847268
OS 37.55226678 -38.48015164
OS 37.55041766 -38.46905692
OS 37.54579486 -38.4579622
OS 37.5402475 -38.44501836
OS 37.53192646 -38.43299908
OS 37.52083174 -38.4209798
OS 37.51898262 -38.42005524
OS 37.51435982 -38.416357
OS 37.50696334 -38.4117342
OS 37.49494406 -38.40618684
OS 37.48107566 -38.40063948
OS 37.46258446 -38.39601668
OS 37.44131958 -38.39231844
OS 37.41635646 -38.39139388
OE
OB 39.82298614 -38.54764452 H
OS 39.81836334 -38.54764452
OS 39.8146651 -38.54856908
OS 39.8054195 -38.5504182
OS 39.79340022 -38.55319188
OS 39.77953182 -38.55873924
OS 39.76473886 -38.56706028
OS 39.75641782 -38.57260764
OS 39.74902134 -38.57907956
OS 39.74162486 -38.58647604
OS 39.73422838 -38.59479708
OS 39.73422838 -38.59572164
OS 39.73237926 -38.5966462
OS 39.73053014 -38.59941988
OS 39.72868102 -38.60311812
OS 39.72590734 -38.60866548
OS 39.7222091 -38.61421284
OS 39.71851086 -38.62160932
OS 39.71573718 -38.6290058
OS 39.71203894 -38.6382514
OS 39.7083407 -38.64842156
OS 39.70556702 -38.65951628
OS 39.70186878 -38.67153556
OS 39.70001966 -38.68540396
OS 39.69817054 -38.69927236
OS 39.69632142 -38.71406532
OS 39.69632142 -38.7307074
OS 39.69632142 -38.73163196
OS 39.69632142 -38.73440564
OS 39.69632142 -38.73902844
OS 39.69724598 -38.74550036
OS 39.69724598 -38.75289684
OS 39.69817054 -38.76121788
OS 39.70094422 -38.78063364
OS 39.70556702 -38.80282308
OS 39.71111438 -38.82408796
OS 39.72035998 -38.84535284
OS 39.72590734 -38.85459844
OS 39.73237926 -38.86291948
OS 39.73422838 -38.8647686
OS 39.73885118 -38.8693914
OS 39.74624766 -38.87678788
OS 39.75641782 -38.88418436
OS 39.76936166 -38.89158084
OS 39.78415462 -38.89897732
OS 39.8007967 -38.90360012
OS 39.8100423 -38.90452468
OS 39.8192879 -38.90544924
OS 39.82483526 -38.90544924
OS 39.8285335 -38.90452468
OS 39.8377791 -38.90267556
OS 39.85072294 -38.89990188
OS 39.86459134 -38.89435452
OS 39.8793843 -38.88695804
OS 39.89417726 -38.87586332
OS 39.90157374 -38.8693914
OS 39.90897022 -38.86199492
OS 39.90897022 -38.86107036
OS 39.91081934 -38.8601458
OS 39.91266846 -38.85737212
OS 39.91451758 -38.85367388
OS 39.91821582 -38.84905108
OS 39.9209895 -38.84257916
OS 39.92468774 -38.83610724
OS 39.92838598 -38.8277862
OS 39.93115966 -38.81946516
OS 39.9348579 -38.80837044
OS 39.93855614 -38.79727572
OS 39.94132982 -38.78525644
OS 39.94317894 -38.77138804
OS 39.94502806 -38.75659508
OS 39.94687718 -38.74087756
OS 39.94687718 -38.72423548
OS 39.94687718 -38.72331092
OS 39.94687718 -38.72053724
OS 39.94687718 -38.71591444
OS 39.94595262 -38.70944252
OS 39.94595262 -38.70204604
OS 39.94502806 -38.693725
OS 39.94225438 -38.67430924
OS 39.93763158 -38.65304436
OS 39.93115966 -38.63177948
OS 39.92191406 -38.6105146
OS 39.9163667 -38.60034444
OS 39.90989478 -38.5920234
OS 39.90989478 -38.59109884
OS 39.90804566 -38.59017428
OS 39.90342286 -38.58462692
OS 39.89602638 -38.578155
OS 39.88585622 -38.56983396
OS 39.87291238 -38.56151292
OS 39.85811942 -38.55411644
OS 39.84147734 -38.54949364
OS 39.83223174 -38.54856908
OS 39.82298614 -38.54764452
OE
OB 35.73550638 -38.39601668 H
OS 35.5524435 -38.39601668
OS 35.5524435 -38.624383
OS 35.72441166 -38.624383
OS 35.73088358 -38.62345844
OS 35.7373555 -38.62345844
OS 35.74475198 -38.62253388
OS 35.76231862 -38.62068476
OS 35.78173438 -38.61698652
OS 35.80115014 -38.61143916
OS 35.81871678 -38.60404268
OS 35.82703782 -38.59941988
OS 35.83350974 -38.59387252
OS 35.83535886 -38.5920234
OS 35.8390571 -38.58832516
OS 35.84460446 -38.58092868
OS 35.85107638 -38.57168308
OS 35.8575483 -38.5596638
OS 35.86309566 -38.54487084
OS 35.8667939 -38.52822876
OS 35.86864302 -38.508813
OS 35.86864302 -38.50788844
OS 35.86864302 -38.50696388
OS 35.86864302 -38.50234108
OS 35.86771846 -38.49402004
OS 35.86586934 -38.48477444
OS 35.86402022 -38.47460428
OS 35.86032198 -38.462585
OS 35.85477462 -38.45149028
OS 35.8483027 -38.44039556
OS 35.84737814 -38.439471
OS 35.84460446 -38.43577276
OS 35.83998166 -38.43114996
OS 35.8344343 -38.42467804
OS 35.82611326 -38.41820612
OS 35.81686766 -38.41265876
OS 35.8066975 -38.4071114
OS 35.79467822 -38.4024886
OS 35.79375366 -38.4024886
OS 35.79005542 -38.40156404
OS 35.78450806 -38.40063948
OS 35.77711158 -38.39879036
OS 35.76601686 -38.3978658
OS 35.75214846 -38.39694124
OS 35.73550638 -38.39601668
OE
OB 43.44263854 -38.5504182 H
OS 43.43709118 -38.5504182
OS 43.43339294 -38.55134276
OS 43.42322278 -38.55226732
OS 43.4112035 -38.555041
OS 43.39641054 -38.5596638
OS 43.38069302 -38.56613572
OS 43.36590006 -38.57538132
OS 43.3511071 -38.5874006
OS 43.34925798 -38.58924972
OS 43.34555974 -38.59387252
OS 43.33908782 -38.60219356
OS 43.3326159 -38.61328828
OS 43.32521942 -38.62623212
OS 43.3187475 -38.6428742
OS 43.31320014 -38.66228996
OS 43.31042646 -38.68355484
OS 43.57022782 -38.68355484
OS 43.57022782 -38.68263028
OS 43.57022782 -38.68078116
OS 43.56930326 -38.67800748
OS 43.56930326 -38.67430924
OS 43.56745414 -38.66321452
OS 43.56468046 -38.65119524
OS 43.56005766 -38.63640228
OS 43.55543486 -38.62253388
OS 43.54803838 -38.60866548
OS 43.53971734 -38.5966462
OS 43.53971734 -38.59572164
OS 43.53786822 -38.59479708
OS 43.53324542 -38.58924972
OS 43.52492438 -38.58185324
OS 43.51382966 -38.5735322
OS 43.49996126 -38.56521116
OS 43.48331918 -38.55781468
OS 43.46390342 -38.55226732
OS 43.45373326 -38.55134276
OS 43.44263854 -38.5504182
OE
OB 34.35791198 -38.39601668 H
OS 34.20628414 -38.39601668
OS 34.20628414 -38.58832516
OS 34.36345934 -38.58832516
OS 34.37547862 -38.5874006
OS 34.38842246 -38.58647604
OS 34.4013663 -38.58555148
OS 34.41431014 -38.58370236
OS 34.4244803 -38.58185324
OS 34.42632942 -38.58092868
OS 34.43002766 -38.58000412
OS 34.43557502 -38.57723044
OS 34.4429715 -38.5735322
OS 34.45036798 -38.56983396
OS 34.45868902 -38.5642866
OS 34.46701006 -38.55689012
OS 34.47348198 -38.54949364
OS 34.47440654 -38.54856908
OS 34.47625566 -38.5457954
OS 34.47902934 -38.54024804
OS 34.48180302 -38.53377612
OS 34.4845767 -38.52637964
OS 34.48735038 -38.51713404
OS 34.4891995 -38.50603932
OS 34.49012406 -38.49402004
OS 34.49012406 -38.49217092
OS 34.49012406 -38.48847268
OS 34.4891995 -38.48292532
OS 34.48827494 -38.47552884
OS 34.48642582 -38.46628324
OS 34.48365214 -38.45703764
OS 34.4799539 -38.44779204
OS 34.47440654 -38.43854644
OS 34.47348198 -38.43762188
OS 34.47163286 -38.4348482
OS 34.46793462 -38.4302254
OS 34.46331182 -38.4256026
OS 34.4568399 -38.42005524
OS 34.44944342 -38.41450788
OS 34.44019782 -38.40896052
OS 34.43002766 -38.40526228
OS 34.4291031 -38.40526228
OS 34.4244803 -38.40341316
OS 34.41800838 -38.4024886
OS 34.40783822 -38.40063948
OS 34.39396982 -38.39879036
OS 34.3782523 -38.3978658
OS 34.35791198 -38.39601668
OE
OB 40.89732486 -38.39601668 H
OS 40.71426198 -38.39601668
OS 40.71426198 -38.624383
OS 40.88623014 -38.624383
OS 40.89270206 -38.62345844
OS 40.89917398 -38.62345844
OS 40.90657046 -38.62253388
OS 40.9241371 -38.62068476
OS 40.94355286 -38.61698652
OS 40.96296862 -38.61143916
OS 40.98053526 -38.60404268
OS 40.9888563 -38.59941988
OS 40.99532822 -38.59387252
OS 40.99717734 -38.5920234
OS 41.00087558 -38.58832516
OS 41.00642294 -38.58092868
OS 41.01289486 -38.57168308
OS 41.01936678 -38.5596638
OS 41.02491414 -38.54487084
OS 41.02861238 -38.52822876
OS 41.0304615 -38.508813
OS 41.0304615 -38.50788844
OS 41.0304615 -38.50696388
OS 41.0304615 -38.50234108
OS 41.02953694 -38.49402004
OS 41.02768782 -38.48477444
OS 41.0258387 -38.47460428
OS 41.02214046 -38.462585
OS 41.0165931 -38.45149028
OS 41.01012118 -38.44039556
OS 41.00919662 -38.439471
OS 41.00642294 -38.43577276
OS 41.00180014 -38.43114996
OS 40.99625278 -38.42467804
OS 40.98793174 -38.41820612
OS 40.97868614 -38.41265876
OS 40.96851598 -38.4071114
OS 40.9564967 -38.4024886
OS 40.95557214 -38.4024886
OS 40.9518739 -38.40156404
OS 40.94632654 -38.40063948
OS 40.93893006 -38.39879036
OS 40.92783534 -38.3978658
OS 40.91396694 -38.39694124
OS 40.89732486 -38.39601668
OE
OB 33.15136118 -38.39601668 H
OS 32.9682983 -38.39601668
OS 32.9682983 -38.624383
OS 33.14026646 -38.624383
OS 33.14673838 -38.62345844
OS 33.1532103 -38.62345844
OS 33.16060678 -38.62253388
OS 33.17817342 -38.62068476
OS 33.19758918 -38.61698652
OS 33.21700494 -38.61143916
OS 33.23457158 -38.60404268
OS 33.24289262 -38.59941988
OS 33.24936454 -38.59387252
OS 33.25121366 -38.5920234
OS 33.2549119 -38.58832516
OS 33.26045926 -38.58092868
OS 33.26693118 -38.57168308
OS 33.2734031 -38.5596638
OS 33.27895046 -38.54487084
OS 33.2826487 -38.52822876
OS 33.28449782 -38.508813
OS 33.28449782 -38.50788844
OS 33.28449782 -38.50696388
OS 33.28449782 -38.50234108
OS 33.28357326 -38.49402004
OS 33.28172414 -38.48477444
OS 33.27987502 -38.47460428
OS 33.27617678 -38.462585
OS 33.27062942 -38.45149028
OS 33.2641575 -38.44039556
OS 33.26323294 -38.439471
OS 33.26045926 -38.43577276
OS 33.25583646 -38.43114996
OS 33.2502891 -38.42467804
OS 33.24196806 -38.41820612
OS 33.23272246 -38.41265876
OS 33.2225523 -38.4071114
OS 33.21053302 -38.4024886
OS 33.20960846 -38.4024886
OS 33.20591022 -38.40156404
OS 33.20036286 -38.40063948
OS 33.19296638 -38.39879036
OS 33.18187166 -38.3978658
OS 33.16800326 -38.39694124
OS 33.15136118 -38.39601668
OE
OB 34.37455406 -38.66413908 H
OS 34.20628414 -38.66413908
OS 34.20628414 -38.88418436
OS 34.38842246 -38.88418436
OS 34.40783822 -38.8832598
OS 34.41615926 -38.88233524
OS 34.42355574 -38.88141068
OS 34.4244803 -38.88141068
OS 34.42817854 -38.88048612
OS 34.4337259 -38.87956156
OS 34.44019782 -38.87771244
OS 34.45591534 -38.87216508
OS 34.47163286 -38.8647686
OS 34.47255742 -38.86384404
OS 34.4753311 -38.86199492
OS 34.47902934 -38.85922124
OS 34.48365214 -38.855523
OS 34.48827494 -38.84997564
OS 34.49474686 -38.84442828
OS 34.49936966 -38.8370318
OS 34.50491702 -38.82871076
OS 34.50584158 -38.8277862
OS 34.50676614 -38.82501252
OS 34.50861526 -38.81946516
OS 34.51138894 -38.81299324
OS 34.51416262 -38.80559676
OS 34.51601174 -38.79635116
OS 34.5169363 -38.78525644
OS 34.51786086 -38.77416172
OS 34.51786086 -38.7723126
OS 34.51786086 -38.76861436
OS 34.5169363 -38.76121788
OS 34.51508718 -38.75289684
OS 34.51323806 -38.74365124
OS 34.50953982 -38.73348108
OS 34.50491702 -38.72331092
OS 34.4984451 -38.71314076
OS 34.49752054 -38.7122162
OS 34.49474686 -38.70851796
OS 34.49104862 -38.70389516
OS 34.48550126 -38.6983478
OS 34.47810478 -38.69187588
OS 34.46885918 -38.68540396
OS 34.45868902 -38.6798566
OS 34.44666974 -38.6752338
OS 34.44482062 -38.67430924
OS 34.44112238 -38.67338468
OS 34.43280134 -38.67153556
OS 34.42263118 -38.66968644
OS 34.40968734 -38.66783732
OS 34.39396982 -38.6659882
OS 34.37455406 -38.66413908
OE
SE
S P 0
OB 48.49040086 -36.61402634 I
OS 48.17420134 -36.61402634
OS 48.17420134 -37.45999874
OS 48.04661206 -37.45999874
OS 48.04661206 -36.61402634
OS 47.73041254 -36.61402634
OS 47.73041254 -36.50030546
OS 48.49040086 -36.50030546
OS 48.49040086 -36.61402634
OE
OB 47.69990206 -37.45999874 I
OS 47.5556707 -37.45999874
OS 47.44333666 -37.16876234
OS 47.04115306 -37.16876234
OS 46.93714006 -37.45999874
OS 46.80261658 -37.45999874
OS 47.16874234 -36.50030546
OS 47.30742634 -36.50030546
OS 47.69990206 -37.45999874
OE
OB 49.31834434 -36.61402634 I
OS 48.75112678 -36.61402634
OS 48.75112678 -36.90664958
OS 49.2822865 -36.90664958
OS 49.2822865 -37.02037046
OS 48.75112678 -37.02037046
OS 48.75112678 -37.34627786
OS 49.34053378 -37.34627786
OS 49.34053378 -37.45999874
OS 48.6235375 -37.45999874
OS 48.6235375 -36.50030546
OS 49.31834434 -36.50030546
OS 49.31834434 -36.61402634
OE
OB 46.33386466 -36.5016923 I
OS 46.36160146 -36.50307914
OS 46.38933826 -36.50585282
OS 46.41707506 -36.51001334
OS 46.44065134 -36.51417386
OS 46.44203818 -36.51417386
OS 46.44481186 -36.5155607
OS 46.44897238 -36.5155607
OS 46.45451974 -36.51833438
OS 46.46977498 -36.5224949
OS 46.48919074 -36.5294291
OS 46.51138018 -36.53913698
OS 46.53495646 -36.55161854
OS 46.55853274 -36.56548694
OS 46.58072218 -36.58351586
OS 46.58210902 -36.5849027
OS 46.58349586 -36.58628954
OS 46.58765638 -36.59045006
OS 46.59320374 -36.59461058
OS 46.60707214 -36.60847898
OS 46.62371422 -36.62789474
OS 46.64174314 -36.65147102
OS 46.6611589 -36.67920782
OS 46.67918782 -36.71110514
OS 46.69444306 -36.74716298
OS 46.69444306 -36.74854982
OS 46.6958299 -36.7513235
OS 46.69860358 -36.75687086
OS 46.69999042 -36.7651919
OS 46.70415094 -36.77489978
OS 46.70692462 -36.7859945
OS 46.7096983 -36.79847606
OS 46.71385882 -36.8137313
OS 46.71801934 -36.82898654
OS 46.72079302 -36.84701546
OS 46.72772722 -36.88584698
OS 46.73188774 -36.92883902
OS 46.73327458 -36.97599158
OS 46.73327458 -36.97737842
OS 46.73327458 -36.9801521
OS 46.73327458 -36.9870863
OS 46.73327458 -36.9940205
OS 46.73188774 -37.00372838
OS 46.73188774 -37.0148231
OS 46.7305009 -37.04117306
OS 46.72634038 -37.07168354
OS 46.72217986 -37.10358086
OS 46.71524566 -37.13686502
OS 46.70692462 -37.17014918
OS 46.70692462 -37.17153602
OS 46.70553778 -37.1743097
OS 46.70415094 -37.17847022
OS 46.7027641 -37.18401758
OS 46.69721674 -37.19927282
OS 46.6888957 -37.21868858
OS 46.68057466 -37.24087802
OS 46.66947994 -37.26306746
OS 46.65561154 -37.28664374
OS 46.64174314 -37.30883318
OS 46.6403563 -37.31160686
OS 46.63480894 -37.31854106
OS 46.6264879 -37.32824894
OS 46.61539318 -37.3407305
OS 46.60291162 -37.3545989
OS 46.58765638 -37.3684673
OS 46.57240114 -37.38372254
OS 46.55437222 -37.3962041
OS 46.55159854 -37.39759094
OS 46.54605118 -37.40175146
OS 46.5363433 -37.40729882
OS 46.5224749 -37.41423302
OS 46.50583282 -37.42255406
OS 46.48641706 -37.42948826
OS 46.46422762 -37.4378093
OS 46.4392645 -37.4447435
OS 46.43649082 -37.4447435
OS 46.4323303 -37.44613034
OS 46.42816978 -37.44751718
OS 46.41430138 -37.44890402
OS 46.39488562 -37.4516777
OS 46.37269618 -37.45445138
OS 46.34634622 -37.45722506
OS 46.31722258 -37.4586119
OS 46.28532526 -37.45999874
OS 45.9400021 -37.45999874
OS 45.9400021 -36.50030546
OS 46.30890154 -36.50030546
OS 46.33386466 -36.5016923
OE
OB 46.28948578 -36.61402634 H
OS 46.06759138 -36.61402634
OS 46.06759138 -37.34627786
OS 46.29503314 -37.34627786
OS 46.30474102 -37.34489102
OS 46.32554362 -37.34350418
OS 46.3491199 -37.34211734
OS 46.37408302 -37.33934366
OS 46.39904614 -37.33518314
OS 46.41984874 -37.32963578
OS 46.42262242 -37.32824894
OS 46.42955662 -37.3268621
OS 46.4392645 -37.32270158
OS 46.45174606 -37.31715422
OS 46.46561446 -37.30883318
OS 46.47948286 -37.30051214
OS 46.49335126 -37.29080426
OS 46.50721966 -37.27970954
OS 46.5086065 -37.27693586
OS 46.51415386 -37.2713885
OS 46.5224749 -37.26168062
OS 46.53218278 -37.24781222
OS 46.5432775 -37.2297833
OS 46.55575906 -37.2089807
OS 46.56685378 -37.18540442
OS 46.57656166 -37.15905446
OS 46.57656166 -37.15766762
OS 46.5779485 -37.15489394
OS 46.57933534 -37.15073342
OS 46.58072218 -37.14518606
OS 46.58210902 -37.13825186
OS 46.5848827 -37.12854398
OS 46.58765638 -37.1188361
OS 46.59043006 -37.10774138
OS 46.59459058 -37.08000458
OS 46.5987511 -37.04810726
OS 46.60152478 -37.01204942
OS 46.60291162 -36.9732179
OS 46.60291162 -36.97183106
OS 46.60291162 -36.9662837
OS 46.60291162 -36.9593495
OS 46.60152478 -36.94825478
OS 46.60152478 -36.93577322
OS 46.60013794 -36.92190482
OS 46.5987511 -36.90526274
OS 46.59736426 -36.88862066
OS 46.59043006 -36.85117598
OS 46.58210902 -36.81234446
OS 46.56962746 -36.77628662
OS 46.56130642 -36.7582577
OS 46.55298538 -36.74300246
OS 46.55298538 -36.74161562
OS 46.5502117 -36.73884194
OS 46.54743802 -36.73468142
OS 46.54466434 -36.72913406
OS 46.53356962 -36.71526566
OS 46.51970122 -36.69862358
OS 46.5016723 -36.68059466
OS 46.4808697 -36.66256574
OS 46.45729342 -36.6473105
OS 46.4323303 -36.63482894
OS 46.42955662 -36.6334421
OS 46.42262242 -36.63205526
OS 46.41014086 -36.62789474
OS 46.39211194 -36.62373422
OS 46.3699225 -36.62096054
OS 46.3421857 -36.61680002
OS 46.32554362 -36.61541318
OS 46.3075147 -36.61541318
OS 46.28948578 -36.61402634
OE
OB 47.23531066 -36.60015794 H
OS 47.23531066 -36.60154478
OS 47.23392382 -36.60431846
OS 47.23392382 -36.60986582
OS 47.23115014 -36.61541318
OS 47.2297633 -36.62512106
OS 47.22698962 -36.63482894
OS 47.22144226 -36.65840522
OS 47.21450806 -36.68614202
OS 47.20480018 -36.7166525
OS 47.1950923 -36.74993666
OS 47.18261074 -36.78460766
OS 47.07859774 -37.06474934
OS 47.4031183 -37.06474934
OS 47.30326582 -36.80124974
OS 47.30326582 -36.7998629
OS 47.30187898 -36.79570238
OS 47.2991053 -36.78876818
OS 47.29633162 -36.78044714
OS 47.2921711 -36.77073926
OS 47.28801058 -36.7582577
OS 47.28385006 -36.7443893
OS 47.2783027 -36.7305209
OS 47.26720798 -36.69862358
OS 47.25611326 -36.66533942
OS 47.24501854 -36.63205526
OS 47.23531066 -36.60015794
OE
SE
S P 0
OB 53.57408132 -38.30725892 I
OS 53.5861006 -38.30910804
OS 53.60089356 -38.31188172
OS 53.61753564 -38.31650452
OS 53.63417772 -38.32205188
OS 53.6508198 -38.32944836
OS 53.65174436 -38.32944836
OS 53.65266892 -38.33037292
OS 53.65821628 -38.3331466
OS 53.66653732 -38.33869396
OS 53.67578292 -38.34516588
OS 53.68687764 -38.35441148
OS 53.69797236 -38.36458164
OS 53.70906708 -38.37660092
OS 53.71831268 -38.39046932
OS 53.71923724 -38.39231844
OS 53.72201092 -38.39694124
OS 53.72570916 -38.40526228
OS 53.73033196 -38.41543244
OS 53.73495476 -38.42745172
OS 53.738653 -38.44132012
OS 53.74142668 -38.45703764
OS 53.74235124 -38.47275516
OS 53.74235124 -38.47460428
OS 53.74235124 -38.48015164
OS 53.74142668 -38.48754812
OS 53.73957756 -38.49771828
OS 53.73680388 -38.50973756
OS 53.73218108 -38.5226814
OS 53.72663372 -38.53562524
OS 53.71923724 -38.54856908
OS 53.71831268 -38.5504182
OS 53.715539 -38.55411644
OS 53.70999164 -38.56058836
OS 53.70259516 -38.56798484
OS 53.69334956 -38.57630588
OS 53.68225484 -38.58555148
OS 53.669311 -38.59387252
OS 53.65359348 -38.60219356
OS 53.65451804 -38.60219356
OS 53.65636716 -38.60311812
OS 53.65914084 -38.60404268
OS 53.66283908 -38.60496724
OS 53.67300924 -38.60866548
OS 53.68595308 -38.61421284
OS 53.70074604 -38.62160932
OS 53.715539 -38.63085492
OS 53.7294074 -38.6428742
OS 53.74235124 -38.6567426
OS 53.7432758 -38.65859172
OS 53.74697404 -38.66413908
OS 53.7525214 -38.67338468
OS 53.75806876 -38.68540396
OS 53.76361612 -38.70019692
OS 53.76916348 -38.71776356
OS 53.77286172 -38.73810388
OS 53.77378628 -38.76029332
OS 53.77378628 -38.76121788
OS 53.77378628 -38.76399156
OS 53.77378628 -38.76861436
OS 53.77286172 -38.77416172
OS 53.77193716 -38.7815582
OS 53.77008804 -38.78987924
OS 53.76823892 -38.79912484
OS 53.7663898 -38.809295
OS 53.75899332 -38.83148444
OS 53.75344596 -38.84350372
OS 53.7478986 -38.85459844
OS 53.74050212 -38.86661772
OS 53.73218108 -38.878637
OS 53.72293548 -38.89065628
OS 53.71184076 -38.901751
OS 53.7109162 -38.90267556
OS 53.70906708 -38.90452468
OS 53.70536884 -38.90729836
OS 53.70074604 -38.9109966
OS 53.69519868 -38.9156194
OS 53.6878022 -38.9202422
OS 53.67948116 -38.92578956
OS 53.669311 -38.93041236
OS 53.65914084 -38.93595972
OS 53.64712156 -38.94150708
OS 53.63510228 -38.94612988
OS 53.62123388 -38.95075268
OS 53.60644092 -38.95445092
OS 53.5907234 -38.9572246
OS 53.57500588 -38.95907372
OS 53.55743924 -38.95999828
OS 53.5491182 -38.95999828
OS 53.54357084 -38.95907372
OS 53.53617436 -38.95814916
OS 53.52785332 -38.9572246
OS 53.51860772 -38.95537548
OS 53.50843756 -38.95352636
OS 53.48624812 -38.947979
OS 53.46313412 -38.9387334
OS 53.45111484 -38.93318604
OS 53.44002012 -38.92671412
OS 53.4289254 -38.91839308
OS 53.41783068 -38.91007204
OS 53.41690612 -38.90914748
OS 53.415057 -38.90729836
OS 53.41228332 -38.90452468
OS 53.40950964 -38.90082644
OS 53.40488684 -38.89620364
OS 53.40026404 -38.88973172
OS 53.39471668 -38.8832598
OS 53.38916932 -38.87493876
OS 53.38362196 -38.86569316
OS 53.3780746 -38.85644756
OS 53.36790444 -38.83425812
OS 53.3595834 -38.80837044
OS 53.35680972 -38.79450204
OS 53.3549606 -38.77970908
OS 53.4335482 -38.76953892
OS 53.4335482 -38.77046348
OS 53.43447276 -38.7723126
OS 53.43539732 -38.77601084
OS 53.43632188 -38.78063364
OS 53.43724644 -38.786181
OS 53.43909556 -38.79265292
OS 53.44371836 -38.80652132
OS 53.45019028 -38.8231634
OS 53.45851132 -38.83888092
OS 53.46775692 -38.85367388
OS 53.47885164 -38.86661772
OS 53.48070076 -38.86754228
OS 53.484399 -38.87124052
OS 53.49179548 -38.87586332
OS 53.50104108 -38.88048612
OS 53.5121358 -38.88603348
OS 53.5260042 -38.89065628
OS 53.54172172 -38.89435452
OS 53.5583638 -38.89527908
OS 53.56391116 -38.89527908
OS 53.5676094 -38.89435452
OS 53.57777956 -38.89342996
OS 53.5907234 -38.89065628
OS 53.60551636 -38.88603348
OS 53.62123388 -38.87956156
OS 53.6369514 -38.87031596
OS 53.65174436 -38.85737212
OS 53.65359348 -38.855523
OS 53.65821628 -38.84997564
OS 53.66376364 -38.8416546
OS 53.67116012 -38.83055988
OS 53.6785566 -38.81669148
OS 53.68410396 -38.80097396
OS 53.68872676 -38.78248276
OS 53.69057588 -38.76214244
OS 53.69057588 -38.76121788
OS 53.69057588 -38.75936876
OS 53.69057588 -38.75659508
OS 53.68965132 -38.75289684
OS 53.68872676 -38.74272668
OS 53.68595308 -38.7307074
OS 53.68225484 -38.71591444
OS 53.67578292 -38.70112148
OS 53.66653732 -38.68632852
OS 53.65451804 -38.67246012
OS 53.65266892 -38.670611
OS 53.64804612 -38.66691276
OS 53.64064964 -38.6613654
OS 53.63047948 -38.65489348
OS 53.61753564 -38.64842156
OS 53.60181812 -38.6428742
OS 53.58425148 -38.63917596
OS 53.56483572 -38.63732684
OS 53.55651468 -38.63732684
OS 53.55004276 -38.6382514
OS 53.54172172 -38.63917596
OS 53.53247612 -38.64102508
OS 53.5213814 -38.6428742
OS 53.50936212 -38.64564788
OS 53.51860772 -38.57630588
OS 53.52323052 -38.57630588
OS 53.52692876 -38.57723044
OS 53.53894804 -38.57723044
OS 53.5491182 -38.57538132
OS 53.56113748 -38.5735322
OS 53.57500588 -38.57075852
OS 53.5907234 -38.56613572
OS 53.60551636 -38.5596638
OS 53.62123388 -38.55134276
OS 53.62215844 -38.55134276
OS 53.623083 -38.5504182
OS 53.6277058 -38.54671996
OS 53.63417772 -38.54024804
OS 53.6415742 -38.531927
OS 53.64897068 -38.51990772
OS 53.6554426 -38.50603932
OS 53.6600654 -38.4903218
OS 53.66191452 -38.4810762
OS 53.66191452 -38.47090604
OS 53.66191452 -38.46998148
OS 53.66191452 -38.46905692
OS 53.66191452 -38.46350956
OS 53.6600654 -38.45611308
OS 53.65821628 -38.44594292
OS 53.65451804 -38.4348482
OS 53.64989524 -38.42282892
OS 53.64249876 -38.41080964
OS 53.6323286 -38.39971492
OS 53.63140404 -38.39879036
OS 53.62678124 -38.39509212
OS 53.62030932 -38.39046932
OS 53.61198828 -38.38492196
OS 53.60089356 -38.38029916
OS 53.58794972 -38.37567636
OS 53.57315676 -38.37197812
OS 53.55651468 -38.37105356
OS 53.5491182 -38.37105356
OS 53.54079716 -38.37290268
OS 53.52970244 -38.3747518
OS 53.51768316 -38.37845004
OS 53.50566388 -38.38307284
OS 53.49272004 -38.39046932
OS 53.48070076 -38.39971492
OS 53.4797762 -38.40063948
OS 53.47607796 -38.40526228
OS 53.4705306 -38.4117342
OS 53.46405868 -38.4209798
OS 53.45758676 -38.43299908
OS 53.45111484 -38.44779204
OS 53.44556748 -38.46535868
OS 53.44186924 -38.485699
OS 53.36328164 -38.4718306
OS 53.36328164 -38.47090604
OS 53.3642062 -38.46813236
OS 53.36513076 -38.46443412
OS 53.36605532 -38.45888676
OS 53.36790444 -38.45241484
OS 53.37067812 -38.44501836
OS 53.37622548 -38.42745172
OS 53.38547108 -38.4071114
OS 53.3965658 -38.38677108
OS 53.4104342 -38.36735532
OS 53.42800084 -38.34978868
OS 53.4289254 -38.34886412
OS 53.43077452 -38.34793956
OS 53.4335482 -38.34609044
OS 53.43724644 -38.34331676
OS 53.44186924 -38.33961852
OS 53.44834116 -38.33592028
OS 53.45481308 -38.33222204
OS 53.46313412 -38.32759924
OS 53.48162532 -38.32020276
OS 53.5028902 -38.31280628
OS 53.52785332 -38.30818348
OS 53.54079716 -38.30633436
OS 53.56391116 -38.30633436
OS 53.57408132 -38.30725892
OE
OB 54.07889108 -38.30725892 I
OS 54.09091036 -38.30910804
OS 54.10477876 -38.31188172
OS 54.11957172 -38.31557996
OS 54.13528924 -38.32020276
OS 54.1500822 -38.32759924
OS 54.15100676 -38.32759924
OS 54.15193132 -38.3285238
OS 54.15655412 -38.33129748
OS 54.1639506 -38.33592028
OS 54.1731962 -38.3423922
OS 54.18336636 -38.3516378
OS 54.19446108 -38.36180796
OS 54.20463124 -38.37382724
OS 54.2148014 -38.38769564
OS 54.21572596 -38.38954476
OS 54.2194242 -38.39416756
OS 54.22312244 -38.4024886
OS 54.22959436 -38.41450788
OS 54.23514172 -38.42837628
OS 54.2425382 -38.4440938
OS 54.24901012 -38.462585
OS 54.25455748 -38.48292532
OS 54.25455748 -38.48384988
OS 54.25548204 -38.485699
OS 54.2564066 -38.48847268
OS 54.25733116 -38.49309548
OS 54.25825572 -38.49864284
OS 54.25918028 -38.50511476
OS 54.2610294 -38.5134358
OS 54.26195396 -38.5226814
OS 54.26380308 -38.53285156
OS 54.26472764 -38.54394628
OS 54.2656522 -38.55689012
OS 54.26750132 -38.56983396
OS 54.26842588 -38.58462692
OS 54.26842588 -38.59941988
OS 54.26935044 -38.61606196
OS 54.26935044 -38.6336286
OS 54.26935044 -38.63455316
OS 54.26935044 -38.6382514
OS 54.26935044 -38.64472332
OS 54.26935044 -38.6521198
OS 54.26842588 -38.66228996
OS 54.26842588 -38.67338468
OS 54.26750132 -38.68540396
OS 54.26657676 -38.6983478
OS 54.26380308 -38.72793372
OS 54.25918028 -38.7584442
OS 54.25363292 -38.78803012
OS 54.24993468 -38.80189852
OS 54.24531188 -38.81576692
OS 54.24531188 -38.81669148
OS 54.24438732 -38.8185406
OS 54.2425382 -38.82223884
OS 54.24068908 -38.82686164
OS 54.23883996 -38.83333356
OS 54.23514172 -38.83980548
OS 54.22774524 -38.855523
OS 54.21849964 -38.87216508
OS 54.20648036 -38.89065628
OS 54.19261196 -38.90729836
OS 54.17596988 -38.92301588
OS 54.17504532 -38.92301588
OS 54.17412076 -38.924865
OS 54.17134708 -38.92671412
OS 54.16764884 -38.92856324
OS 54.16302604 -38.93133692
OS 54.15840324 -38.93503516
OS 54.14453484 -38.94150708
OS 54.12789276 -38.947979
OS 54.108477 -38.95445092
OS 54.085363 -38.95814916
OS 54.06039988 -38.95999828
OS 54.05115428 -38.95999828
OS 54.04468236 -38.95907372
OS 54.03728588 -38.95814916
OS 54.02804028 -38.95630004
OS 54.01787012 -38.95445092
OS 54.0067754 -38.95167724
OS 53.99568068 -38.947979
OS 53.9836614 -38.94428076
OS 53.97164212 -38.9387334
OS 53.95962284 -38.93226148
OS 53.94760356 -38.924865
OS 53.93558428 -38.9156194
OS 53.92448956 -38.90544924
OS 53.9143194 -38.89435452
OS 53.91339484 -38.89342996
OS 53.91154572 -38.89065628
OS 53.90877204 -38.88603348
OS 53.90414924 -38.878637
OS 53.89952644 -38.87031596
OS 53.89490364 -38.85922124
OS 53.88843172 -38.8462774
OS 53.88288436 -38.83148444
OS 53.877337 -38.81484236
OS 53.87178964 -38.7954266
OS 53.86624228 -38.77416172
OS 53.86161948 -38.75012316
OS 53.85699668 -38.72423548
OS 53.854223 -38.69649868
OS 53.85237388 -38.6659882
OS 53.85144932 -38.6336286
OS 53.85144932 -38.63270404
OS 53.85144932 -38.6290058
OS 53.85144932 -38.62253388
OS 53.85144932 -38.6151374
OS 53.85237388 -38.60496724
OS 53.85237388 -38.59387252
OS 53.85329844 -38.58185324
OS 53.854223 -38.56798484
OS 53.85699668 -38.53932348
OS 53.86161948 -38.508813
OS 53.86716684 -38.47830252
OS 53.87086508 -38.46443412
OS 53.87456332 -38.45056572
OS 53.87456332 -38.44964116
OS 53.87548788 -38.44779204
OS 53.877337 -38.4440938
OS 53.87918612 -38.439471
OS 53.88103524 -38.43299908
OS 53.88473348 -38.42652716
OS 53.89212996 -38.41080964
OS 53.90137556 -38.39416756
OS 53.91339484 -38.37660092
OS 53.92726324 -38.35903428
OS 53.94390532 -38.34424132
OS 53.94482988 -38.34424132
OS 53.94575444 -38.3423922
OS 53.94852812 -38.34054308
OS 53.95222636 -38.33869396
OS 53.95684916 -38.33499572
OS 53.96239652 -38.33222204
OS 53.97626492 -38.32482556
OS 53.992907 -38.31835364
OS 54.01232276 -38.31188172
OS 54.03543676 -38.30818348
OS 54.06039988 -38.30633436
OS 54.06872092 -38.30633436
OS 54.07889108 -38.30725892
OE
OB 53.23846604 -38.94890356 I
OS 53.14878372 -38.94890356
OS 53.14878372 -38.85922124
OS 53.23846604 -38.85922124
OS 53.23846604 -38.94890356
OE
OB 53.00177868 -38.39231844 I
OS 52.74567556 -38.39231844
OS 52.71146684 -38.56521116
OS 52.7123914 -38.5642866
OS 52.71424052 -38.56336204
OS 52.7170142 -38.56151292
OS 52.721637 -38.55873924
OS 52.72718436 -38.55596556
OS 52.73365628 -38.55226732
OS 52.74844924 -38.54487084
OS 52.76694044 -38.53747436
OS 52.78728076 -38.53100244
OS 52.8094702 -38.52637964
OS 52.82056492 -38.52453052
OS 52.84090524 -38.52453052
OS 52.8464526 -38.52545508
OS 52.85384908 -38.52637964
OS 52.86217012 -38.5273042
OS 52.87141572 -38.52915332
OS 52.88158588 -38.531927
OS 52.90377532 -38.53839892
OS 52.9157946 -38.54302172
OS 52.92781388 -38.54949364
OS 52.93983316 -38.55596556
OS 52.95185244 -38.56336204
OS 52.96294716 -38.57260764
OS 52.97404188 -38.5827778
OS 52.97496644 -38.58370236
OS 52.97681556 -38.58555148
OS 52.97958924 -38.58832516
OS 52.98328748 -38.59294796
OS 52.98791028 -38.59941988
OS 52.99253308 -38.6058918
OS 52.99808044 -38.61421284
OS 53.0036278 -38.62345844
OS 53.0082506 -38.6336286
OS 53.01379796 -38.64472332
OS 53.01842076 -38.65766716
OS 53.02304356 -38.670611
OS 53.0267418 -38.6844794
OS 53.02951548 -38.70019692
OS 53.0313646 -38.71591444
OS 53.03228916 -38.73255652
OS 53.03228916 -38.73348108
OS 53.03228916 -38.73625476
OS 53.03228916 -38.74087756
OS 53.0313646 -38.74734948
OS 53.03044004 -38.75474596
OS 53.02951548 -38.763067
OS 53.02766636 -38.77323716
OS 53.02581724 -38.78340732
OS 53.02026988 -38.80744588
OS 53.01102428 -38.832409
OS 53.00547692 -38.84535284
OS 52.99808044 -38.85737212
OS 52.99068396 -38.87031596
OS 52.98143836 -38.88233524
OS 52.9805138 -38.8832598
OS 52.97866468 -38.88603348
OS 52.97496644 -38.88973172
OS 52.97034364 -38.89435452
OS 52.96387172 -38.89990188
OS 52.95647524 -38.90729836
OS 52.94722964 -38.91377028
OS 52.93705948 -38.92116676
OS 52.92596476 -38.92856324
OS 52.91302092 -38.93503516
OS 52.89915252 -38.94150708
OS 52.88435956 -38.947979
OS 52.86864204 -38.9526018
OS 52.8510754 -38.95630004
OS 52.8325842 -38.95907372
OS 52.81316844 -38.95999828
OS 52.8048474 -38.95999828
OS 52.79837548 -38.95907372
OS 52.790979 -38.95814916
OS 52.78265796 -38.9572246
OS 52.7724878 -38.95630004
OS 52.76231764 -38.95352636
OS 52.73920364 -38.947979
OS 52.71608964 -38.93965796
OS 52.70407036 -38.9341106
OS 52.69205108 -38.92763868
OS 52.68095636 -38.9202422
OS 52.66986164 -38.91192116
OS 52.66893708 -38.9109966
OS 52.66708796 -38.91007204
OS 52.66523884 -38.9063738
OS 52.6615406 -38.90267556
OS 52.6569178 -38.89805276
OS 52.652295 -38.8925054
OS 52.64674764 -38.88510892
OS 52.64212484 -38.87678788
OS 52.63657748 -38.86846684
OS 52.63103012 -38.85829668
OS 52.62085996 -38.83610724
OS 52.61253892 -38.81021956
OS 52.60976524 -38.79635116
OS 52.60791612 -38.7815582
OS 52.69020196 -38.77508628
OS 52.69020196 -38.77601084
OS 52.69020196 -38.77785996
OS 52.69112652 -38.78063364
OS 52.69205108 -38.78525644
OS 52.69482476 -38.7954266
OS 52.698523 -38.809295
OS 52.70407036 -38.8231634
OS 52.71146684 -38.83888092
OS 52.72071244 -38.85274932
OS 52.73180716 -38.86569316
OS 52.73365628 -38.86661772
OS 52.73735452 -38.87031596
OS 52.744751 -38.87493876
OS 52.75492116 -38.88048612
OS 52.76601588 -38.88603348
OS 52.77988428 -38.89065628
OS 52.7956018 -38.89435452
OS 52.81316844 -38.89527908
OS 52.8187158 -38.89527908
OS 52.82241404 -38.89435452
OS 52.83350876 -38.89342996
OS 52.8464526 -38.88973172
OS 52.86217012 -38.88510892
OS 52.87788764 -38.87771244
OS 52.89452972 -38.86661772
OS 52.9019262 -38.8601458
OS 52.90932268 -38.85274932
OS 52.91024724 -38.85182476
OS 52.9111718 -38.8509002
OS 52.91302092 -38.84812652
OS 52.9157946 -38.84535284
OS 52.92226652 -38.83518268
OS 52.929663 -38.82223884
OS 52.93613492 -38.80652132
OS 52.94260684 -38.78710556
OS 52.94722964 -38.76399156
OS 52.94907876 -38.75197228
OS 52.94907876 -38.73902844
OS 52.94907876 -38.73810388
OS 52.94907876 -38.73625476
OS 52.94907876 -38.73255652
OS 52.9481542 -38.72793372
OS 52.9481542 -38.72238636
OS 52.94722964 -38.71591444
OS 52.94445596 -38.70112148
OS 52.93983316 -38.68355484
OS 52.93336124 -38.6659882
OS 52.92411564 -38.64934612
OS 52.9111718 -38.6336286
OS 52.9111718 -38.63270404
OS 52.90932268 -38.63177948
OS 52.90469988 -38.62715668
OS 52.89637884 -38.62068476
OS 52.88528412 -38.61328828
OS 52.87049116 -38.60681636
OS 52.85384908 -38.60034444
OS 52.83443332 -38.59572164
OS 52.8233386 -38.59387252
OS 52.80577196 -38.59387252
OS 52.79837548 -38.59479708
OS 52.78912988 -38.59572164
OS 52.77803516 -38.59849532
OS 52.76694044 -38.601269
OS 52.75492116 -38.6058918
OS 52.74290188 -38.61143916
OS 52.74197732 -38.61236372
OS 52.73827908 -38.61421284
OS 52.73273172 -38.61883564
OS 52.72533524 -38.62345844
OS 52.71793876 -38.62993036
OS 52.71054228 -38.6382514
OS 52.70222124 -38.64657244
OS 52.69574932 -38.6567426
OS 52.62178452 -38.64657244
OS 52.68373004 -38.31742908
OS 53.00177868 -38.31742908
OS 53.00177868 -38.39231844
OE
OB 53.23846604 -38.57445676 I
OS 53.14878372 -38.57445676
OS 53.14878372 -38.48477444
OS 53.23846604 -38.48477444
OS 53.23846604 -38.57445676
OE
OB 54.48199924 -38.57445676 I
OS 54.39231692 -38.57445676
OS 54.39231692 -38.48477444
OS 54.48199924 -38.48477444
OS 54.48199924 -38.57445676
OE
OB 56.14990548 -38.3100326 I
OS 56.165623 -38.31095716
OS 56.18226508 -38.31188172
OS 56.1979826 -38.31373084
OS 56.211851 -38.31557996
OS 56.21370012 -38.31557996
OS 56.22017204 -38.31742908
OS 56.22849308 -38.3192782
OS 56.2395878 -38.32205188
OS 56.25160708 -38.32667468
OS 56.26455092 -38.33222204
OS 56.27841932 -38.33869396
OS 56.2904386 -38.34609044
OS 56.29228772 -38.347015
OS 56.29598596 -38.34978868
OS 56.30153332 -38.35533604
OS 56.3089298 -38.36180796
OS 56.31725084 -38.370129
OS 56.32557188 -38.38122372
OS 56.33481748 -38.393243
OS 56.34221396 -38.4071114
OS 56.34313852 -38.40896052
OS 56.34498764 -38.41358332
OS 56.34868588 -38.42190436
OS 56.35238412 -38.43299908
OS 56.3551578 -38.44594292
OS 56.35885604 -38.46073588
OS 56.36070516 -38.47737796
OS 56.36162972 -38.4949446
OS 56.36162972 -38.49586916
OS 56.36162972 -38.49864284
OS 56.36162972 -38.50234108
OS 56.36070516 -38.508813
OS 56.3597806 -38.51528492
OS 56.35885604 -38.52360596
OS 56.35700692 -38.53285156
OS 56.3551578 -38.54302172
OS 56.34868588 -38.5642866
OS 56.34498764 -38.57538132
OS 56.33944028 -38.5874006
OS 56.33296836 -38.59941988
OS 56.32649644 -38.6105146
OS 56.3181754 -38.62160932
OS 56.3089298 -38.63270404
OS 56.30800524 -38.6336286
OS 56.30615612 -38.63547772
OS 56.30338244 -38.6382514
OS 56.29875964 -38.64102508
OS 56.29321228 -38.64564788
OS 56.2858158 -38.65027068
OS 56.2765702 -38.65581804
OS 56.26640004 -38.66044084
OS 56.25438076 -38.6659882
OS 56.24051236 -38.67153556
OS 56.2257194 -38.67615836
OS 56.20815276 -38.6798566
OS 56.18966156 -38.68355484
OS 56.16932124 -38.68632852
OS 56.14620724 -38.68817764
OS 56.12216868 -38.6891022
OS 55.95852156 -38.6891022
OS 55.95852156 -38.94890356
OS 55.87346204 -38.94890356
OS 55.87346204 -38.30910804
OS 56.13603708 -38.30910804
OS 56.14990548 -38.3100326
OE
OB 57.07723916 -38.94890356 I
OS 56.99587788 -38.94890356
OS 56.99587788 -38.41358332
OS 56.80911676 -38.94890356
OS 56.73330284 -38.94890356
OS 56.54839084 -38.40433772
OS 56.54839084 -38.94890356
OS 56.46702956 -38.94890356
OS 56.46702956 -38.30910804
OS 56.59369428 -38.30910804
OS 56.74532212 -38.763067
OS 56.74532212 -38.76399156
OS 56.74624668 -38.76584068
OS 56.74717124 -38.76861436
OS 56.74902036 -38.77323716
OS 56.7527186 -38.78433188
OS 56.7573414 -38.79820028
OS 56.7619642 -38.8139178
OS 56.76751156 -38.82963532
OS 56.77213436 -38.84442828
OS 56.7758326 -38.85737212
OS 56.77675716 -38.855523
OS 56.77768172 -38.8509002
OS 56.7804554 -38.84257916
OS 56.78415364 -38.83148444
OS 56.78877644 -38.81669148
OS 56.79524836 -38.79912484
OS 56.80172028 -38.77878452
OS 56.81004132 -38.75474596
OS 56.96351828 -38.30910804
OS 57.07723916 -38.30910804
OS 57.07723916 -38.94890356
OE
OB 55.3150278 -38.30725892 I
OS 55.32704708 -38.30910804
OS 55.34184004 -38.31188172
OS 55.35848212 -38.31650452
OS 55.3751242 -38.32205188
OS 55.39176628 -38.32944836
OS 55.39269084 -38.32944836
OS 55.3936154 -38.33037292
OS 55.39916276 -38.3331466
OS 55.4074838 -38.33869396
OS 55.4167294 -38.34516588
OS 55.42782412 -38.35441148
OS 55.43891884 -38.36458164
OS 55.45001356 -38.37660092
OS 55.45925916 -38.39046932
OS 55.46018372 -38.39231844
OS 55.4629574 -38.39694124
OS 55.46665564 -38.40526228
OS 55.47127844 -38.41543244
OS 55.47590124 -38.42745172
OS 55.47959948 -38.44132012
OS 55.48237316 -38.45703764
OS 55.48329772 -38.47275516
OS 55.48329772 -38.47460428
OS 55.48329772 -38.48015164
OS 55.48237316 -38.48754812
OS 55.48052404 -38.49771828
OS 55.47775036 -38.50973756
OS 55.47312756 -38.5226814
OS 55.4675802 -38.53562524
OS 55.46018372 -38.54856908
OS 55.45925916 -38.5504182
OS 55.45648548 -38.55411644
OS 55.45093812 -38.56058836
OS 55.44354164 -38.56798484
OS 55.43429604 -38.57630588
OS 55.42320132 -38.58555148
OS 55.41025748 -38.59387252
OS 55.39453996 -38.60219356
OS 55.39546452 -38.60219356
OS 55.39731364 -38.60311812
OS 55.40008732 -38.60404268
OS 55.40378556 -38.60496724
OS 55.41395572 -38.60866548
OS 55.42689956 -38.61421284
OS 55.44169252 -38.62160932
OS 55.45648548 -38.63085492
OS 55.47035388 -38.6428742
OS 55.48329772 -38.6567426
OS 55.48422228 -38.65859172
OS 55.48792052 -38.66413908
OS 55.49346788 -38.67338468
OS 55.49901524 -38.68540396
OS 55.5045626 -38.70019692
OS 55.51010996 -38.71776356
OS 55.5138082 -38.73810388
OS 55.51473276 -38.76029332
OS 55.51473276 -38.76121788
OS 55.51473276 -38.76399156
OS 55.51473276 -38.76861436
OS 55.5138082 -38.77416172
OS 55.51288364 -38.7815582
OS 55.51103452 -38.78987924
OS 55.5091854 -38.79912484
OS 55.50733628 -38.809295
OS 55.4999398 -38.83148444
OS 55.49439244 -38.84350372
OS 55.48884508 -38.85459844
OS 55.4814486 -38.86661772
OS 55.47312756 -38.878637
OS 55.46388196 -38.89065628
OS 55.45278724 -38.901751
OS 55.45186268 -38.90267556
OS 55.45001356 -38.90452468
OS 55.44631532 -38.90729836
OS 55.44169252 -38.9109966
OS 55.43614516 -38.9156194
OS 55.42874868 -38.9202422
OS 55.42042764 -38.92578956
OS 55.41025748 -38.93041236
OS 55.40008732 -38.93595972
OS 55.38806804 -38.94150708
OS 55.37604876 -38.94612988
OS 55.36218036 -38.95075268
OS 55.3473874 -38.95445092
OS 55.33166988 -38.9572246
OS 55.31595236 -38.95907372
OS 55.29838572 -38.95999828
OS 55.29006468 -38.95999828
OS 55.28451732 -38.95907372
OS 55.27712084 -38.95814916
OS 55.2687998 -38.9572246
OS 55.2595542 -38.95537548
OS 55.24938404 -38.95352636
OS 55.2271946 -38.947979
OS 55.2040806 -38.9387334
OS 55.19206132 -38.93318604
OS 55.1809666 -38.92671412
OS 55.16987188 -38.91839308
OS 55.15877716 -38.91007204
OS 55.1578526 -38.90914748
OS 55.15600348 -38.90729836
OS 55.1532298 -38.90452468
OS 55.15045612 -38.90082644
OS 55.14583332 -38.89620364
OS 55.14121052 -38.88973172
OS 55.13566316 -38.8832598
OS 55.1301158 -38.87493876
OS 55.12456844 -38.86569316
OS 55.11902108 -38.85644756
OS 55.10885092 -38.83425812
OS 55.10052988 -38.80837044
OS 55.0977562 -38.79450204
OS 55.09590708 -38.77970908
OS 55.17449468 -38.76953892
OS 55.17449468 -38.77046348
OS 55.17541924 -38.7723126
OS 55.1763438 -38.77601084
OS 55.17726836 -38.78063364
OS 55.17819292 -38.786181
OS 55.18004204 -38.79265292
OS 55.18466484 -38.80652132
OS 55.19113676 -38.8231634
OS 55.1994578 -38.83888092
OS 55.2087034 -38.85367388
OS 55.21979812 -38.86661772
OS 55.22164724 -38.86754228
OS 55.22534548 -38.87124052
OS 55.23274196 -38.87586332
OS 55.24198756 -38.88048612
OS 55.25308228 -38.88603348
OS 55.26695068 -38.89065628
OS 55.2826682 -38.89435452
OS 55.29931028 -38.89527908
OS 55.30485764 -38.89527908
OS 55.30855588 -38.89435452
OS 55.31872604 -38.89342996
OS 55.33166988 -38.89065628
OS 55.34646284 -38.88603348
OS 55.36218036 -38.87956156
OS 55.37789788 -38.87031596
OS 55.39269084 -38.85737212
OS 55.39453996 -38.855523
OS 55.39916276 -38.84997564
OS 55.40471012 -38.8416546
OS 55.4121066 -38.83055988
OS 55.41950308 -38.81669148
OS 55.42505044 -38.80097396
OS 55.42967324 -38.78248276
OS 55.43152236 -38.76214244
OS 55.43152236 -38.76121788
OS 55.43152236 -38.75936876
OS 55.43152236 -38.75659508
OS 55.4305978 -38.75289684
OS 55.42967324 -38.74272668
OS 55.42689956 -38.7307074
OS 55.42320132 -38.71591444
OS 55.4167294 -38.70112148
OS 55.4074838 -38.68632852
OS 55.39546452 -38.67246012
OS 55.3936154 -38.670611
OS 55.3889926 -38.66691276
OS 55.38159612 -38.6613654
OS 55.37142596 -38.65489348
OS 55.35848212 -38.64842156
OS 55.3427646 -38.6428742
OS 55.32519796 -38.63917596
OS 55.3057822 -38.63732684
OS 55.29746116 -38.63732684
OS 55.29098924 -38.6382514
OS 55.2826682 -38.63917596
OS 55.2734226 -38.64102508
OS 55.26232788 -38.6428742
OS 55.2503086 -38.64564788
OS 55.2595542 -38.57630588
OS 55.264177 -38.57630588
OS 55.26787524 -38.57723044
OS 55.27989452 -38.57723044
OS 55.29006468 -38.57538132
OS 55.30208396 -38.5735322
OS 55.31595236 -38.57075852
OS 55.33166988 -38.56613572
OS 55.34646284 -38.5596638
OS 55.36218036 -38.55134276
OS 55.36310492 -38.55134276
OS 55.36402948 -38.5504182
OS 55.36865228 -38.54671996
OS 55.3751242 -38.54024804
OS 55.38252068 -38.531927
OS 55.38991716 -38.51990772
OS 55.39638908 -38.50603932
OS 55.40101188 -38.4903218
OS 55.402861 -38.4810762
OS 55.402861 -38.47090604
OS 55.402861 -38.46998148
OS 55.402861 -38.46905692
OS 55.402861 -38.46350956
OS 55.40101188 -38.45611308
OS 55.39916276 -38.44594292
OS 55.39546452 -38.4348482
OS 55.39084172 -38.42282892
OS 55.38344524 -38.41080964
OS 55.37327508 -38.39971492
OS 55.37235052 -38.39879036
OS 55.36772772 -38.39509212
OS 55.3612558 -38.39046932
OS 55.35293476 -38.38492196
OS 55.34184004 -38.38029916
OS 55.3288962 -38.37567636
OS 55.31410324 -38.37197812
OS 55.29746116 -38.37105356
OS 55.29006468 -38.37105356
OS 55.28174364 -38.37290268
OS 55.27064892 -38.3747518
OS 55.25862964 -38.37845004
OS 55.24661036 -38.38307284
OS 55.23366652 -38.39046932
OS 55.22164724 -38.39971492
OS 55.22072268 -38.40063948
OS 55.21702444 -38.40526228
OS 55.21147708 -38.4117342
OS 55.20500516 -38.4209798
OS 55.19853324 -38.43299908
OS 55.19206132 -38.44779204
OS 55.18651396 -38.46535868
OS 55.18281572 -38.485699
OS 55.10422812 -38.4718306
OS 55.10422812 -38.47090604
OS 55.10515268 -38.46813236
OS 55.10607724 -38.46443412
OS 55.1070018 -38.45888676
OS 55.10885092 -38.45241484
OS 55.1116246 -38.44501836
OS 55.11717196 -38.42745172
OS 55.12641756 -38.4071114
OS 55.13751228 -38.38677108
OS 55.15138068 -38.36735532
OS 55.16894732 -38.34978868
OS 55.16987188 -38.34886412
OS 55.171721 -38.34793956
OS 55.17449468 -38.34609044
OS 55.17819292 -38.34331676
OS 55.18281572 -38.33961852
OS 55.18928764 -38.33592028
OS 55.19575956 -38.33222204
OS 55.2040806 -38.32759924
OS 55.2225718 -38.32020276
OS 55.24383668 -38.31280628
OS 55.2687998 -38.30818348
OS 55.28174364 -38.30633436
OS 55.30485764 -38.30633436
OS 55.3150278 -38.30725892
OE
OB 54.48199924 -38.94890356 I
OS 54.39231692 -38.94890356
OS 54.39231692 -38.85922124
OS 54.48199924 -38.85922124
OS 54.48199924 -38.94890356
OE
OB 54.9914318 -38.39231844 I
OS 54.73532868 -38.39231844
OS 54.70111996 -38.56521116
OS 54.70204452 -38.5642866
OS 54.70389364 -38.56336204
OS 54.70666732 -38.56151292
OS 54.71129012 -38.55873924
OS 54.71683748 -38.55596556
OS 54.7233094 -38.55226732
OS 54.73810236 -38.54487084
OS 54.75659356 -38.53747436
OS 54.77693388 -38.53100244
OS 54.79912332 -38.52637964
OS 54.81021804 -38.52453052
OS 54.83055836 -38.52453052
OS 54.83610572 -38.52545508
OS 54.8435022 -38.52637964
OS 54.85182324 -38.5273042
OS 54.86106884 -38.52915332
OS 54.871239 -38.531927
OS 54.89342844 -38.53839892
OS 54.90544772 -38.54302172
OS 54.917467 -38.54949364
OS 54.92948628 -38.55596556
OS 54.94150556 -38.56336204
OS 54.95260028 -38.57260764
OS 54.963695 -38.5827778
OS 54.96461956 -38.58370236
OS 54.96646868 -38.58555148
OS 54.96924236 -38.58832516
OS 54.9729406 -38.59294796
OS 54.9775634 -38.59941988
OS 54.9821862 -38.6058918
OS 54.98773356 -38.61421284
OS 54.99328092 -38.62345844
OS 54.99790372 -38.6336286
OS 55.00345108 -38.64472332
OS 55.00807388 -38.65766716
OS 55.01269668 -38.670611
OS 55.01639492 -38.6844794
OS 55.0191686 -38.70019692
OS 55.02101772 -38.71591444
OS 55.02194228 -38.73255652
OS 55.02194228 -38.73348108
OS 55.02194228 -38.73625476
OS 55.02194228 -38.74087756
OS 55.02101772 -38.74734948
OS 55.02009316 -38.75474596
OS 55.0191686 -38.763067
OS 55.01731948 -38.77323716
OS 55.01547036 -38.78340732
OS 55.009923 -38.80744588
OS 55.0006774 -38.832409
OS 54.99513004 -38.84535284
OS 54.98773356 -38.85737212
OS 54.98033708 -38.87031596
OS 54.97109148 -38.88233524
OS 54.97016692 -38.8832598
OS 54.9683178 -38.88603348
OS 54.96461956 -38.88973172
OS 54.95999676 -38.89435452
OS 54.95352484 -38.89990188
OS 54.94612836 -38.90729836
OS 54.93688276 -38.91377028
OS 54.9267126 -38.92116676
OS 54.91561788 -38.92856324
OS 54.90267404 -38.93503516
OS 54.88880564 -38.94150708
OS 54.87401268 -38.947979
OS 54.85829516 -38.9526018
OS 54.84072852 -38.95630004
OS 54.82223732 -38.95907372
OS 54.80282156 -38.95999828
OS 54.79450052 -38.95999828
OS 54.7880286 -38.95907372
OS 54.78063212 -38.95814916
OS 54.77231108 -38.9572246
OS 54.76214092 -38.95630004
OS 54.75197076 -38.95352636
OS 54.72885676 -38.947979
OS 54.70574276 -38.93965796
OS 54.69372348 -38.9341106
OS 54.6817042 -38.92763868
OS 54.67060948 -38.9202422
OS 54.65951476 -38.91192116
OS 54.6585902 -38.9109966
OS 54.65674108 -38.91007204
OS 54.65489196 -38.9063738
OS 54.65119372 -38.90267556
OS 54.64657092 -38.89805276
OS 54.64194812 -38.8925054
OS 54.63640076 -38.88510892
OS 54.63177796 -38.87678788
OS 54.6262306 -38.86846684
OS 54.62068324 -38.85829668
OS 54.61051308 -38.83610724
OS 54.60219204 -38.81021956
OS 54.59941836 -38.79635116
OS 54.59756924 -38.7815582
OS 54.67985508 -38.77508628
OS 54.67985508 -38.77601084
OS 54.67985508 -38.77785996
OS 54.68077964 -38.78063364
OS 54.6817042 -38.78525644
OS 54.68447788 -38.7954266
OS 54.68817612 -38.809295
OS 54.69372348 -38.8231634
OS 54.70111996 -38.83888092
OS 54.71036556 -38.85274932
OS 54.72146028 -38.86569316
OS 54.7233094 -38.86661772
OS 54.72700764 -38.87031596
OS 54.73440412 -38.87493876
OS 54.74457428 -38.88048612
OS 54.755669 -38.88603348
OS 54.7695374 -38.89065628
OS 54.78525492 -38.89435452
OS 54.80282156 -38.89527908
OS 54.80836892 -38.89527908
OS 54.81206716 -38.89435452
OS 54.82316188 -38.89342996
OS 54.83610572 -38.88973172
OS 54.85182324 -38.88510892
OS 54.86754076 -38.87771244
OS 54.88418284 -38.86661772
OS 54.89157932 -38.8601458
OS 54.8989758 -38.85274932
OS 54.89990036 -38.85182476
OS 54.90082492 -38.8509002
OS 54.90267404 -38.84812652
OS 54.90544772 -38.84535284
OS 54.91191964 -38.83518268
OS 54.91931612 -38.82223884
OS 54.92578804 -38.80652132
OS 54.93225996 -38.78710556
OS 54.93688276 -38.76399156
OS 54.93873188 -38.75197228
OS 54.93873188 -38.73902844
OS 54.93873188 -38.73810388
OS 54.93873188 -38.73625476
OS 54.93873188 -38.73255652
OS 54.93780732 -38.72793372
OS 54.93780732 -38.72238636
OS 54.93688276 -38.71591444
OS 54.93410908 -38.70112148
OS 54.92948628 -38.68355484
OS 54.92301436 -38.6659882
OS 54.91376876 -38.64934612
OS 54.90082492 -38.6336286
OS 54.90082492 -38.63270404
OS 54.8989758 -38.63177948
OS 54.894353 -38.62715668
OS 54.88603196 -38.62068476
OS 54.87493724 -38.61328828
OS 54.86014428 -38.60681636
OS 54.8435022 -38.60034444
OS 54.82408644 -38.59572164
OS 54.81299172 -38.59387252
OS 54.79542508 -38.59387252
OS 54.7880286 -38.59479708
OS 54.778783 -38.59572164
OS 54.76768828 -38.59849532
OS 54.75659356 -38.601269
OS 54.74457428 -38.6058918
OS 54.732555 -38.61143916
OS 54.73163044 -38.61236372
OS 54.7279322 -38.61421284
OS 54.72238484 -38.61883564
OS 54.71498836 -38.62345844
OS 54.70759188 -38.62993036
OS 54.7001954 -38.6382514
OS 54.69187436 -38.64657244
OS 54.68540244 -38.6567426
OS 54.61143764 -38.64657244
OS 54.67338316 -38.31742908
OS 54.9914318 -38.31742908
OS 54.9914318 -38.39231844
OE
OB 49.95350436 -38.72331092 I
OS 50.040413 -38.72331092
OS 50.040413 -38.7954266
OS 49.95350436 -38.7954266
OS 49.95350436 -38.94890356
OS 49.87491676 -38.94890356
OS 49.87491676 -38.7954266
OS 49.5966242 -38.7954266
OS 49.5966242 -38.72331092
OS 49.88970972 -38.30910804
OS 49.95350436 -38.30910804
OS 49.95350436 -38.72331092
OE
OB 50.1467374 -38.95999828 I
OS 50.08386732 -38.95999828
OS 50.26970388 -38.29801332
OS 50.33257396 -38.29801332
OS 50.1467374 -38.95999828
OE
OB 49.35346492 -38.30725892 I
OS 49.3608614 -38.30818348
OS 49.370107 -38.30910804
OS 49.38027716 -38.31095716
OS 49.39044732 -38.31280628
OS 49.41448588 -38.3192782
OS 49.43852444 -38.3285238
OS 49.45054372 -38.33407116
OS 49.462563 -38.34054308
OS 49.47365772 -38.34886412
OS 49.48382788 -38.35810972
OS 49.48475244 -38.35903428
OS 49.48660156 -38.35995884
OS 49.48845068 -38.36365708
OS 49.49214892 -38.36735532
OS 49.49677172 -38.37197812
OS 49.50139452 -38.37845004
OS 49.50601732 -38.38492196
OS 49.51156468 -38.393243
OS 49.52081028 -38.41080964
OS 49.53005588 -38.43299908
OS 49.53375412 -38.4440938
OS 49.53560324 -38.45703764
OS 49.53745236 -38.46998148
OS 49.53837692 -38.48384988
OS 49.53837692 -38.485699
OS 49.53837692 -38.4903218
OS 49.53745236 -38.49771828
OS 49.5365278 -38.50788844
OS 49.53467868 -38.51898316
OS 49.53098044 -38.531927
OS 49.5272822 -38.5457954
OS 49.52173484 -38.5596638
OS 49.52081028 -38.56151292
OS 49.51896116 -38.56613572
OS 49.51526292 -38.5735322
OS 49.50971556 -38.58370236
OS 49.50231908 -38.59479708
OS 49.49307348 -38.60866548
OS 49.48197876 -38.62253388
OS 49.46903492 -38.6382514
OS 49.4671858 -38.64010052
OS 49.462563 -38.64564788
OS 49.4579402 -38.65027068
OS 49.4533174 -38.65489348
OS 49.44777004 -38.66044084
OS 49.44037356 -38.66783732
OS 49.43297708 -38.6752338
OS 49.42373148 -38.68355484
OS 49.41448588 -38.69280044
OS 49.40339116 -38.7029706
OS 49.39137188 -38.71314076
OS 49.37842804 -38.72516004
OS 49.36363508 -38.73717932
OS 49.34884212 -38.75012316
OS 49.34791756 -38.75104772
OS 49.34606844 -38.75289684
OS 49.3423702 -38.75567052
OS 49.3377474 -38.75936876
OS 49.33220004 -38.76491612
OS 49.32572812 -38.77046348
OS 49.31093516 -38.78248276
OS 49.29521764 -38.79635116
OS 49.28042468 -38.81021956
OS 49.26748084 -38.82223884
OS 49.26193348 -38.82686164
OS 49.25731068 -38.83148444
OS 49.25638612 -38.832409
OS 49.25361244 -38.83518268
OS 49.2499142 -38.83888092
OS 49.2452914 -38.84442828
OS 49.2406686 -38.8509002
OS 49.23512124 -38.85737212
OS 49.22402652 -38.87308964
OS 49.53930148 -38.87308964
OS 49.53930148 -38.94890356
OS 49.11492844 -38.94890356
OS 49.11492844 -38.947979
OS 49.11492844 -38.94428076
OS 49.11492844 -38.9387334
OS 49.115853 -38.93133692
OS 49.11677756 -38.92301588
OS 49.11862668 -38.91377028
OS 49.1204758 -38.90452468
OS 49.12417404 -38.89435452
OS 49.12417404 -38.89342996
OS 49.1250986 -38.8925054
OS 49.12694772 -38.88695804
OS 49.13064596 -38.878637
OS 49.13619332 -38.86754228
OS 49.1435898 -38.85459844
OS 49.1528354 -38.83980548
OS 49.16300556 -38.82501252
OS 49.1759494 -38.809295
OS 49.1759494 -38.80837044
OS 49.17779852 -38.80744588
OS 49.18242132 -38.80189852
OS 49.19074236 -38.79357748
OS 49.20276164 -38.7815582
OS 49.21663004 -38.7676898
OS 49.23419668 -38.75104772
OS 49.25546156 -38.73255652
OS 49.27857556 -38.71314076
OS 49.27950012 -38.7122162
OS 49.28319836 -38.70944252
OS 49.28874572 -38.70481972
OS 49.29521764 -38.69927236
OS 49.30353868 -38.69187588
OS 49.31370884 -38.68355484
OS 49.323879 -38.67430924
OS 49.33589828 -38.66413908
OS 49.35901228 -38.64194964
OS 49.38212628 -38.6197602
OS 49.393221 -38.60866548
OS 49.40339116 -38.59757076
OS 49.41263676 -38.5874006
OS 49.42003324 -38.57723044
OS 49.42003324 -38.57630588
OS 49.42188236 -38.57538132
OS 49.42373148 -38.57260764
OS 49.4255806 -38.5689094
OS 49.43205252 -38.55873924
OS 49.439449 -38.54671996
OS 49.44592092 -38.531927
OS 49.45239284 -38.51620948
OS 49.45609108 -38.49864284
OS 49.4579402 -38.48200076
OS 49.4579402 -38.4810762
OS 49.4579402 -38.48015164
OS 49.45701564 -38.47460428
OS 49.45609108 -38.46535868
OS 49.4533174 -38.45518852
OS 49.44961916 -38.44224468
OS 49.44314724 -38.42930084
OS 49.4348262 -38.416357
OS 49.42373148 -38.40341316
OS 49.42188236 -38.40156404
OS 49.41725956 -38.3978658
OS 49.41078764 -38.393243
OS 49.40061748 -38.38677108
OS 49.38767364 -38.38122372
OS 49.37288068 -38.37567636
OS 49.35531404 -38.37197812
OS 49.33589828 -38.37105356
OS 49.33035092 -38.37105356
OS 49.32665268 -38.37197812
OS 49.31555796 -38.37290268
OS 49.30261412 -38.37567636
OS 49.28874572 -38.3793746
OS 49.2730282 -38.38584652
OS 49.25823524 -38.39416756
OS 49.24436684 -38.40526228
OS 49.24251772 -38.4071114
OS 49.23881948 -38.4117342
OS 49.23327212 -38.41913068
OS 49.22772476 -38.4302254
OS 49.22125284 -38.44316924
OS 49.21570548 -38.45981132
OS 49.21200724 -38.47830252
OS 49.21015812 -38.4995674
OS 49.1297214 -38.49124636
OS 49.1297214 -38.4903218
OS 49.13064596 -38.48754812
OS 49.13064596 -38.48292532
OS 49.13157052 -38.4764534
OS 49.13341964 -38.46905692
OS 49.13526876 -38.46073588
OS 49.13804244 -38.45056572
OS 49.14081612 -38.44039556
OS 49.1482126 -38.41820612
OS 49.15930732 -38.39601668
OS 49.16577924 -38.38492196
OS 49.17410028 -38.37382724
OS 49.18242132 -38.36365708
OS 49.19166692 -38.35441148
OS 49.19259148 -38.35348692
OS 49.1944406 -38.35256236
OS 49.19721428 -38.34978868
OS 49.20183708 -38.347015
OS 49.20738444 -38.34331676
OS 49.21385636 -38.33961852
OS 49.22125284 -38.33499572
OS 49.23049844 -38.33037292
OS 49.2406686 -38.32575012
OS 49.25176332 -38.32112732
OS 49.2637826 -38.31742908
OS 49.27672644 -38.31373084
OS 49.29059484 -38.31095716
OS 49.3053878 -38.30818348
OS 49.32110532 -38.30725892
OS 49.3377474 -38.30633436
OS 49.346993 -38.30633436
OS 49.35346492 -38.30725892
OE
OB 48.67576244 -38.94890356 I
OS 48.59717484 -38.94890356
OS 48.59717484 -38.4487166
OS 48.59625028 -38.44964116
OS 48.59162748 -38.4533394
OS 48.58608012 -38.45888676
OS 48.57683452 -38.46535868
OS 48.56666436 -38.47367972
OS 48.55372052 -38.48292532
OS 48.53892756 -38.49309548
OS 48.52228548 -38.50326564
OS 48.52136092 -38.50326564
OS 48.52043636 -38.5041902
OS 48.514889 -38.50788844
OS 48.5056434 -38.51251124
OS 48.49454868 -38.5180586
OS 48.48160484 -38.52453052
OS 48.46773644 -38.53100244
OS 48.45386804 -38.53747436
OS 48.43999964 -38.54302172
OS 48.43999964 -38.4672078
OS 48.4409242 -38.4672078
OS 48.44277332 -38.46535868
OS 48.44647156 -38.46443412
OS 48.45109436 -38.46166044
OS 48.45664172 -38.45888676
OS 48.46311364 -38.45518852
OS 48.47883116 -38.44594292
OS 48.49732236 -38.43577276
OS 48.51581356 -38.42282892
OS 48.53522932 -38.40803596
OS 48.55464508 -38.39231844
OS 48.55556964 -38.39139388
OS 48.5564942 -38.39046932
OS 48.55926788 -38.38769564
OS 48.56296612 -38.38492196
OS 48.57128716 -38.37567636
OS 48.58238188 -38.36458164
OS 48.5934766 -38.3516378
OS 48.60549588 -38.33684484
OS 48.61566604 -38.32205188
OS 48.62491164 -38.30633436
OS 48.67576244 -38.30633436
OS 48.67576244 -38.94890356
OE
OB 48.9032042 -38.95999828 I
OS 48.84033412 -38.95999828
OS 49.02617068 -38.29801332
OS 49.08904076 -38.29801332
OS 48.9032042 -38.95999828
OE
OB 50.59699812 -38.30725892 I
OS 50.6043946 -38.30818348
OS 50.6136402 -38.30910804
OS 50.62381036 -38.31095716
OS 50.63398052 -38.31280628
OS 50.65801908 -38.3192782
OS 50.68205764 -38.3285238
OS 50.69407692 -38.33407116
OS 50.7060962 -38.34054308
OS 50.71719092 -38.34886412
OS 50.72736108 -38.35810972
OS 50.72828564 -38.35903428
OS 50.73013476 -38.35995884
OS 50.73198388 -38.36365708
OS 50.73568212 -38.36735532
OS 50.74030492 -38.37197812
OS 50.74492772 -38.37845004
OS 50.74955052 -38.38492196
OS 50.75509788 -38.393243
OS 50.76434348 -38.41080964
OS 50.77358908 -38.43299908
OS 50.77728732 -38.4440938
OS 50.77913644 -38.45703764
OS 50.78098556 -38.46998148
OS 50.78191012 -38.48384988
OS 50.78191012 -38.485699
OS 50.78191012 -38.4903218
OS 50.78098556 -38.49771828
OS 50.780061 -38.50788844
OS 50.77821188 -38.51898316
OS 50.77451364 -38.531927
OS 50.7708154 -38.5457954
OS 50.76526804 -38.5596638
OS 50.76434348 -38.56151292
OS 50.76249436 -38.56613572
OS 50.75879612 -38.5735322
OS 50.75324876 -38.58370236
OS 50.74585228 -38.59479708
OS 50.73660668 -38.60866548
OS 50.72551196 -38.62253388
OS 50.71256812 -38.6382514
OS 50.710719 -38.64010052
OS 50.7060962 -38.64564788
OS 50.7014734 -38.65027068
OS 50.6968506 -38.65489348
OS 50.69130324 -38.66044084
OS 50.68390676 -38.66783732
OS 50.67651028 -38.6752338
OS 50.66726468 -38.68355484
OS 50.65801908 -38.69280044
OS 50.64692436 -38.7029706
OS 50.63490508 -38.71314076
OS 50.62196124 -38.72516004
OS 50.60716828 -38.73717932
OS 50.59237532 -38.75012316
OS 50.59145076 -38.75104772
OS 50.58960164 -38.75289684
OS 50.5859034 -38.75567052
OS 50.5812806 -38.75936876
OS 50.57573324 -38.76491612
OS 50.56926132 -38.77046348
OS 50.55446836 -38.78248276
OS 50.53875084 -38.79635116
OS 50.52395788 -38.81021956
OS 50.51101404 -38.82223884
OS 50.50546668 -38.82686164
OS 50.50084388 -38.83148444
OS 50.49991932 -38.832409
OS 50.49714564 -38.83518268
OS 50.4934474 -38.83888092
OS 50.4888246 -38.84442828
OS 50.4842018 -38.8509002
OS 50.47865444 -38.85737212
OS 50.46755972 -38.87308964
OS 50.78283468 -38.87308964
OS 50.78283468 -38.94890356
OS 50.35846164 -38.94890356
OS 50.35846164 -38.947979
OS 50.35846164 -38.94428076
OS 50.35846164 -38.9387334
OS 50.3593862 -38.93133692
OS 50.36031076 -38.92301588
OS 50.36215988 -38.91377028
OS 50.364009 -38.90452468
OS 50.36770724 -38.89435452
OS 50.36770724 -38.89342996
OS 50.3686318 -38.8925054
OS 50.37048092 -38.88695804
OS 50.37417916 -38.878637
OS 50.37972652 -38.86754228
OS 50.387123 -38.85459844
OS 50.3963686 -38.83980548
OS 50.40653876 -38.82501252
OS 50.4194826 -38.809295
OS 50.4194826 -38.80837044
OS 50.42133172 -38.80744588
OS 50.42595452 -38.80189852
OS 50.43427556 -38.79357748
OS 50.44629484 -38.7815582
OS 50.46016324 -38.7676898
OS 50.47772988 -38.75104772
OS 50.49899476 -38.73255652
OS 50.52210876 -38.71314076
OS 50.52303332 -38.7122162
OS 50.52673156 -38.70944252
OS 50.53227892 -38.70481972
OS 50.53875084 -38.69927236
OS 50.54707188 -38.69187588
OS 50.55724204 -38.68355484
OS 50.5674122 -38.67430924
OS 50.57943148 -38.66413908
OS 50.60254548 -38.64194964
OS 50.62565948 -38.6197602
OS 50.6367542 -38.60866548
OS 50.64692436 -38.59757076
OS 50.65616996 -38.5874006
OS 50.66356644 -38.57723044
OS 50.66356644 -38.57630588
OS 50.66541556 -38.57538132
OS 50.66726468 -38.57260764
OS 50.6691138 -38.5689094
OS 50.67558572 -38.55873924
OS 50.6829822 -38.54671996
OS 50.68945412 -38.531927
OS 50.69592604 -38.51620948
OS 50.69962428 -38.49864284
OS 50.7014734 -38.48200076
OS 50.7014734 -38.4810762
OS 50.7014734 -38.48015164
OS 50.70054884 -38.47460428
OS 50.69962428 -38.46535868
OS 50.6968506 -38.45518852
OS 50.69315236 -38.44224468
OS 50.68668044 -38.42930084
OS 50.6783594 -38.416357
OS 50.66726468 -38.40341316
OS 50.66541556 -38.40156404
OS 50.66079276 -38.3978658
OS 50.65432084 -38.393243
OS 50.64415068 -38.38677108
OS 50.63120684 -38.38122372
OS 50.61641388 -38.37567636
OS 50.59884724 -38.37197812
OS 50.57943148 -38.37105356
OS 50.57388412 -38.37105356
OS 50.57018588 -38.37197812
OS 50.55909116 -38.37290268
OS 50.54614732 -38.37567636
OS 50.53227892 -38.3793746
OS 50.5165614 -38.38584652
OS 50.50176844 -38.39416756
OS 50.48790004 -38.40526228
OS 50.48605092 -38.4071114
OS 50.48235268 -38.4117342
OS 50.47680532 -38.41913068
OS 50.47125796 -38.4302254
OS 50.46478604 -38.44316924
OS 50.45923868 -38.45981132
OS 50.45554044 -38.47830252
OS 50.45369132 -38.4995674
OS 50.3732546 -38.49124636
OS 50.3732546 -38.4903218
OS 50.37417916 -38.48754812
OS 50.37417916 -38.48292532
OS 50.37510372 -38.4764534
OS 50.37695284 -38.46905692
OS 50.37880196 -38.46073588
OS 50.38157564 -38.45056572
OS 50.38434932 -38.44039556
OS 50.3917458 -38.41820612
OS 50.40284052 -38.39601668
OS 50.40931244 -38.38492196
OS 50.41763348 -38.37382724
OS 50.42595452 -38.36365708
OS 50.43520012 -38.35441148
OS 50.43612468 -38.35348692
OS 50.4379738 -38.35256236
OS 50.44074748 -38.34978868
OS 50.44537028 -38.347015
OS 50.45091764 -38.34331676
OS 50.45738956 -38.33961852
OS 50.46478604 -38.33499572
OS 50.47403164 -38.33037292
OS 50.4842018 -38.32575012
OS 50.49529652 -38.32112732
OS 50.5073158 -38.31742908
OS 50.52025964 -38.31373084
OS 50.53412804 -38.31095716
OS 50.548921 -38.30818348
OS 50.56463852 -38.30725892
OS 50.5812806 -38.30633436
OS 50.5905262 -38.30633436
OS 50.59699812 -38.30725892
OE
OB 51.0944114 -38.30725892 I
OS 51.10643068 -38.30910804
OS 51.12029908 -38.31188172
OS 51.13509204 -38.31557996
OS 51.15080956 -38.32020276
OS 51.16560252 -38.32759924
OS 51.16652708 -38.32759924
OS 51.16745164 -38.3285238
OS 51.17207444 -38.33129748
OS 51.17947092 -38.33592028
OS 51.18871652 -38.3423922
OS 51.19888668 -38.3516378
OS 51.2099814 -38.36180796
OS 51.22015156 -38.37382724
OS 51.23032172 -38.38769564
OS 51.23124628 -38.38954476
OS 51.23494452 -38.39416756
OS 51.23864276 -38.4024886
OS 51.24511468 -38.41450788
OS 51.25066204 -38.42837628
OS 51.25805852 -38.4440938
OS 51.26453044 -38.462585
OS 51.2700778 -38.48292532
OS 51.2700778 -38.48384988
OS 51.27100236 -38.485699
OS 51.27192692 -38.48847268
OS 51.27285148 -38.49309548
OS 51.27377604 -38.49864284
OS 51.2747006 -38.50511476
OS 51.27654972 -38.5134358
OS 51.27747428 -38.5226814
OS 51.2793234 -38.53285156
OS 51.28024796 -38.54394628
OS 51.28117252 -38.55689012
OS 51.28302164 -38.56983396
OS 51.2839462 -38.58462692
OS 51.2839462 -38.59941988
OS 51.28487076 -38.61606196
OS 51.28487076 -38.6336286
OS 51.28487076 -38.63455316
OS 51.28487076 -38.6382514
OS 51.28487076 -38.64472332
OS 51.28487076 -38.6521198
OS 51.2839462 -38.66228996
OS 51.2839462 -38.67338468
OS 51.28302164 -38.68540396
OS 51.28209708 -38.6983478
OS 51.2793234 -38.72793372
OS 51.2747006 -38.7584442
OS 51.26915324 -38.78803012
OS 51.265455 -38.80189852
OS 51.2608322 -38.81576692
OS 51.2608322 -38.81669148
OS 51.25990764 -38.8185406
OS 51.25805852 -38.82223884
OS 51.2562094 -38.82686164
OS 51.25436028 -38.83333356
OS 51.25066204 -38.83980548
OS 51.24326556 -38.855523
OS 51.23401996 -38.87216508
OS 51.22200068 -38.89065628
OS 51.20813228 -38.90729836
OS 51.1914902 -38.92301588
OS 51.19056564 -38.92301588
OS 51.18964108 -38.924865
OS 51.1868674 -38.92671412
OS 51.18316916 -38.92856324
OS 51.17854636 -38.93133692
OS 51.17392356 -38.93503516
OS 51.16005516 -38.94150708
OS 51.14341308 -38.947979
OS 51.12399732 -38.95445092
OS 51.10088332 -38.95814916
OS 51.0759202 -38.95999828
OS 51.0666746 -38.95999828
OS 51.06020268 -38.95907372
OS 51.0528062 -38.95814916
OS 51.0435606 -38.95630004
OS 51.03339044 -38.95445092
OS 51.02229572 -38.95167724
OS 51.011201 -38.947979
OS 50.99918172 -38.94428076
OS 50.98716244 -38.9387334
OS 50.97514316 -38.93226148
OS 50.96312388 -38.924865
OS 50.9511046 -38.9156194
OS 50.94000988 -38.90544924
OS 50.92983972 -38.89435452
OS 50.92891516 -38.89342996
OS 50.92706604 -38.89065628
OS 50.92429236 -38.88603348
OS 50.91966956 -38.878637
OS 50.91504676 -38.87031596
OS 50.91042396 -38.85922124
OS 50.90395204 -38.8462774
OS 50.89840468 -38.83148444
OS 50.89285732 -38.81484236
OS 50.88730996 -38.7954266
OS 50.8817626 -38.77416172
OS 50.8771398 -38.75012316
OS 50.872517 -38.72423548
OS 50.86974332 -38.69649868
OS 50.8678942 -38.6659882
OS 50.86696964 -38.6336286
OS 50.86696964 -38.63270404
OS 50.86696964 -38.6290058
OS 50.86696964 -38.62253388
OS 50.86696964 -38.6151374
OS 50.8678942 -38.60496724
OS 50.8678942 -38.59387252
OS 50.86881876 -38.58185324
OS 50.86974332 -38.56798484
OS 50.872517 -38.53932348
OS 50.8771398 -38.508813
OS 50.88268716 -38.47830252
OS 50.8863854 -38.46443412
OS 50.89008364 -38.45056572
OS 50.89008364 -38.44964116
OS 50.8910082 -38.44779204
OS 50.89285732 -38.4440938
OS 50.89470644 -38.439471
OS 50.89655556 -38.43299908
OS 50.9002538 -38.42652716
OS 50.90765028 -38.41080964
OS 50.91689588 -38.39416756
OS 50.92891516 -38.37660092
OS 50.94278356 -38.35903428
OS 50.95942564 -38.34424132
OS 50.9603502 -38.34424132
OS 50.96127476 -38.3423922
OS 50.96404844 -38.34054308
OS 50.96774668 -38.33869396
OS 50.97236948 -38.33499572
OS 50.97791684 -38.33222204
OS 50.99178524 -38.32482556
OS 51.00842732 -38.31835364
OS 51.02784308 -38.31188172
OS 51.05095708 -38.30818348
OS 51.0759202 -38.30633436
OS 51.08424124 -38.30633436
OS 51.0944114 -38.30725892
OE
OB 51.59182468 -38.30725892 I
OS 51.59922116 -38.30818348
OS 51.60846676 -38.30910804
OS 51.61863692 -38.31095716
OS 51.62880708 -38.31280628
OS 51.65284564 -38.3192782
OS 51.6768842 -38.3285238
OS 51.68890348 -38.33407116
OS 51.70092276 -38.34054308
OS 51.71201748 -38.34886412
OS 51.72218764 -38.35810972
OS 51.7231122 -38.35903428
OS 51.72496132 -38.35995884
OS 51.72681044 -38.36365708
OS 51.73050868 -38.36735532
OS 51.73513148 -38.37197812
OS 51.73975428 -38.37845004
OS 51.74437708 -38.38492196
OS 51.74992444 -38.393243
OS 51.75917004 -38.41080964
OS 51.76841564 -38.43299908
OS 51.77211388 -38.4440938
OS 51.773963 -38.45703764
OS 51.77581212 -38.46998148
OS 51.77673668 -38.48384988
OS 51.77673668 -38.485699
OS 51.77673668 -38.4903218
OS 51.77581212 -38.49771828
OS 51.77488756 -38.50788844
OS 51.77303844 -38.51898316
OS 51.7693402 -38.531927
OS 51.76564196 -38.5457954
OS 51.7600946 -38.5596638
OS 51.75917004 -38.56151292
OS 51.75732092 -38.56613572
OS 51.75362268 -38.5735322
OS 51.74807532 -38.58370236
OS 51.74067884 -38.59479708
OS 51.73143324 -38.60866548
OS 51.72033852 -38.62253388
OS 51.70739468 -38.6382514
OS 51.70554556 -38.64010052
OS 51.70092276 -38.64564788
OS 51.69629996 -38.65027068
OS 51.69167716 -38.65489348
OS 51.6861298 -38.66044084
OS 51.67873332 -38.66783732
OS 51.67133684 -38.6752338
OS 51.66209124 -38.68355484
OS 51.65284564 -38.69280044
OS 51.64175092 -38.7029706
OS 51.62973164 -38.71314076
OS 51.6167878 -38.72516004
OS 51.60199484 -38.73717932
OS 51.58720188 -38.75012316
OS 51.58627732 -38.75104772
OS 51.5844282 -38.75289684
OS 51.58072996 -38.75567052
OS 51.57610716 -38.75936876
OS 51.5705598 -38.76491612
OS 51.56408788 -38.77046348
OS 51.54929492 -38.78248276
OS 51.5335774 -38.79635116
OS 51.51878444 -38.81021956
OS 51.5058406 -38.82223884
OS 51.50029324 -38.82686164
OS 51.49567044 -38.83148444
OS 51.49474588 -38.832409
OS 51.4919722 -38.83518268
OS 51.48827396 -38.83888092
OS 51.48365116 -38.84442828
OS 51.47902836 -38.8509002
OS 51.473481 -38.85737212
OS 51.46238628 -38.87308964
OS 51.77766124 -38.87308964
OS 51.77766124 -38.94890356
OS 51.3532882 -38.94890356
OS 51.3532882 -38.947979
OS 51.3532882 -38.94428076
OS 51.3532882 -38.9387334
OS 51.35421276 -38.93133692
OS 51.35513732 -38.92301588
OS 51.35698644 -38.91377028
OS 51.35883556 -38.90452468
OS 51.3625338 -38.89435452
OS 51.3625338 -38.89342996
OS 51.36345836 -38.8925054
OS 51.36530748 -38.88695804
OS 51.36900572 -38.878637
OS 51.37455308 -38.86754228
OS 51.38194956 -38.85459844
OS 51.39119516 -38.83980548
OS 51.40136532 -38.82501252
OS 51.41430916 -38.809295
OS 51.41430916 -38.80837044
OS 51.41615828 -38.80744588
OS 51.42078108 -38.80189852
OS 51.42910212 -38.79357748
OS 51.4411214 -38.7815582
OS 51.4549898 -38.7676898
OS 51.47255644 -38.75104772
OS 51.49382132 -38.73255652
OS 51.51693532 -38.71314076
OS 51.51785988 -38.7122162
OS 51.52155812 -38.70944252
OS 51.52710548 -38.70481972
OS 51.5335774 -38.69927236
OS 51.54189844 -38.69187588
OS 51.5520686 -38.68355484
OS 51.56223876 -38.67430924
OS 51.57425804 -38.66413908
OS 51.59737204 -38.64194964
OS 51.62048604 -38.6197602
OS 51.63158076 -38.60866548
OS 51.64175092 -38.59757076
OS 51.65099652 -38.5874006
OS 51.658393 -38.57723044
OS 51.658393 -38.57630588
OS 51.66024212 -38.57538132
OS 51.66209124 -38.57260764
OS 51.66394036 -38.5689094
OS 51.67041228 -38.55873924
OS 51.67780876 -38.54671996
OS 51.68428068 -38.531927
OS 51.6907526 -38.51620948
OS 51.69445084 -38.49864284
OS 51.69629996 -38.48200076
OS 51.69629996 -38.4810762
OS 51.69629996 -38.48015164
OS 51.6953754 -38.47460428
OS 51.69445084 -38.46535868
OS 51.69167716 -38.45518852
OS 51.68797892 -38.44224468
OS 51.681507 -38.42930084
OS 51.67318596 -38.416357
OS 51.66209124 -38.40341316
OS 51.66024212 -38.40156404
OS 51.65561932 -38.3978658
OS 51.6491474 -38.393243
OS 51.63897724 -38.38677108
OS 51.6260334 -38.38122372
OS 51.61124044 -38.37567636
OS 51.5936738 -38.37197812
OS 51.57425804 -38.37105356
OS 51.56871068 -38.37105356
OS 51.56501244 -38.37197812
OS 51.55391772 -38.37290268
OS 51.54097388 -38.37567636
OS 51.52710548 -38.3793746
OS 51.51138796 -38.38584652
OS 51.496595 -38.39416756
OS 51.4827266 -38.40526228
OS 51.48087748 -38.4071114
OS 51.47717924 -38.4117342
OS 51.47163188 -38.41913068
OS 51.46608452 -38.4302254
OS 51.4596126 -38.44316924
OS 51.45406524 -38.45981132
OS 51.450367 -38.47830252
OS 51.44851788 -38.4995674
OS 51.36808116 -38.49124636
OS 51.36808116 -38.4903218
OS 51.36900572 -38.48754812
OS 51.36900572 -38.48292532
OS 51.36993028 -38.4764534
OS 51.3717794 -38.46905692
OS 51.37362852 -38.46073588
OS 51.3764022 -38.45056572
OS 51.37917588 -38.44039556
OS 51.38657236 -38.41820612
OS 51.39766708 -38.39601668
OS 51.404139 -38.38492196
OS 51.41246004 -38.37382724
OS 51.42078108 -38.36365708
OS 51.43002668 -38.35441148
OS 51.43095124 -38.35348692
OS 51.43280036 -38.35256236
OS 51.43557404 -38.34978868
OS 51.44019684 -38.347015
OS 51.4457442 -38.34331676
OS 51.45221612 -38.33961852
OS 51.4596126 -38.33499572
OS 51.4688582 -38.33037292
OS 51.47902836 -38.32575012
OS 51.49012308 -38.32112732
OS 51.50214236 -38.31742908
OS 51.5150862 -38.31373084
OS 51.5289546 -38.31095716
OS 51.54374756 -38.30818348
OS 51.55946508 -38.30725892
OS 51.57610716 -38.30633436
OS 51.58535276 -38.30633436
OS 51.59182468 -38.30725892
OE
OB 52.08184148 -38.30725892 I
OS 52.09386076 -38.30910804
OS 52.10865372 -38.31188172
OS 52.1252958 -38.31650452
OS 52.14193788 -38.32205188
OS 52.15857996 -38.32944836
OS 52.15950452 -38.32944836
OS 52.16042908 -38.33037292
OS 52.16597644 -38.3331466
OS 52.17429748 -38.33869396
OS 52.18354308 -38.34516588
OS 52.1946378 -38.35441148
OS 52.20573252 -38.36458164
OS 52.21682724 -38.37660092
OS 52.22607284 -38.39046932
OS 52.2269974 -38.39231844
OS 52.22977108 -38.39694124
OS 52.23346932 -38.40526228
OS 52.23809212 -38.41543244
OS 52.24271492 -38.42745172
OS 52.24641316 -38.44132012
OS 52.24918684 -38.45703764
OS 52.2501114 -38.47275516
OS 52.2501114 -38.47460428
OS 52.2501114 -38.48015164
OS 52.24918684 -38.48754812
OS 52.24733772 -38.49771828
OS 52.24456404 -38.50973756
OS 52.23994124 -38.5226814
OS 52.23439388 -38.53562524
OS 52.2269974 -38.54856908
OS 52.22607284 -38.5504182
OS 52.22329916 -38.55411644
OS 52.2177518 -38.56058836
OS 52.21035532 -38.56798484
OS 52.20110972 -38.57630588
OS 52.190015 -38.58555148
OS 52.17707116 -38.59387252
OS 52.16135364 -38.60219356
OS 52.1622782 -38.60219356
OS 52.16412732 -38.60311812
OS 52.166901 -38.60404268
OS 52.17059924 -38.60496724
OS 52.1807694 -38.60866548
OS 52.19371324 -38.61421284
OS 52.2085062 -38.62160932
OS 52.22329916 -38.63085492
OS 52.23716756 -38.6428742
OS 52.2501114 -38.6567426
OS 52.25103596 -38.65859172
OS 52.2547342 -38.66413908
OS 52.26028156 -38.67338468
OS 52.26582892 -38.68540396
OS 52.27137628 -38.70019692
OS 52.27692364 -38.71776356
OS 52.28062188 -38.73810388
OS 52.28154644 -38.76029332
OS 52.28154644 -38.76121788
OS 52.28154644 -38.76399156
OS 52.28154644 -38.76861436
OS 52.28062188 -38.77416172
OS 52.27969732 -38.7815582
OS 52.2778482 -38.78987924
OS 52.27599908 -38.79912484
OS 52.27414996 -38.809295
OS 52.26675348 -38.83148444
OS 52.26120612 -38.84350372
OS 52.25565876 -38.85459844
OS 52.24826228 -38.86661772
OS 52.23994124 -38.878637
OS 52.23069564 -38.89065628
OS 52.21960092 -38.901751
OS 52.21867636 -38.90267556
OS 52.21682724 -38.90452468
OS 52.213129 -38.90729836
OS 52.2085062 -38.9109966
OS 52.20295884 -38.9156194
OS 52.19556236 -38.9202422
OS 52.18724132 -38.92578956
OS 52.17707116 -38.93041236
OS 52.166901 -38.93595972
OS 52.15488172 -38.94150708
OS 52.14286244 -38.94612988
OS 52.12899404 -38.95075268
OS 52.11420108 -38.95445092
OS 52.09848356 -38.9572246
OS 52.08276604 -38.95907372
OS 52.0651994 -38.95999828
OS 52.05687836 -38.95999828
OS 52.051331 -38.95907372
OS 52.04393452 -38.95814916
OS 52.03561348 -38.9572246
OS 52.02636788 -38.95537548
OS 52.01619772 -38.95352636
OS 51.99400828 -38.947979
OS 51.97089428 -38.9387334
OS 51.958875 -38.93318604
OS 51.94778028 -38.92671412
OS 51.93668556 -38.91839308
OS 51.92559084 -38.91007204
OS 51.92466628 -38.90914748
OS 51.92281716 -38.90729836
OS 51.92004348 -38.90452468
OS 51.9172698 -38.90082644
OS 51.912647 -38.89620364
OS 51.9080242 -38.88973172
OS 51.90247684 -38.8832598
OS 51.89692948 -38.87493876
OS 51.89138212 -38.86569316
OS 51.88583476 -38.85644756
OS 51.8756646 -38.83425812
OS 51.86734356 -38.80837044
OS 51.86456988 -38.79450204
OS 51.86272076 -38.77970908
OS 51.94130836 -38.76953892
OS 51.94130836 -38.77046348
OS 51.94223292 -38.7723126
OS 51.94315748 -38.77601084
OS 51.94408204 -38.78063364
OS 51.9450066 -38.786181
OS 51.94685572 -38.79265292
OS 51.95147852 -38.80652132
OS 51.95795044 -38.8231634
OS 51.96627148 -38.83888092
OS 51.97551708 -38.85367388
OS 51.9866118 -38.86661772
OS 51.98846092 -38.86754228
OS 51.99215916 -38.87124052
OS 51.99955564 -38.87586332
OS 52.00880124 -38.88048612
OS 52.01989596 -38.88603348
OS 52.03376436 -38.89065628
OS 52.04948188 -38.89435452
OS 52.06612396 -38.89527908
OS 52.07167132 -38.89527908
OS 52.07536956 -38.89435452
OS 52.08553972 -38.89342996
OS 52.09848356 -38.89065628
OS 52.11327652 -38.88603348
OS 52.12899404 -38.87956156
OS 52.14471156 -38.87031596
OS 52.15950452 -38.85737212
OS 52.16135364 -38.855523
OS 52.16597644 -38.84997564
OS 52.1715238 -38.8416546
OS 52.17892028 -38.83055988
OS 52.18631676 -38.81669148
OS 52.19186412 -38.80097396
OS 52.19648692 -38.78248276
OS 52.19833604 -38.76214244
OS 52.19833604 -38.76121788
OS 52.19833604 -38.75936876
OS 52.19833604 -38.75659508
OS 52.19741148 -38.75289684
OS 52.19648692 -38.74272668
OS 52.19371324 -38.7307074
OS 52.190015 -38.71591444
OS 52.18354308 -38.70112148
OS 52.17429748 -38.68632852
OS 52.1622782 -38.67246012
OS 52.16042908 -38.670611
OS 52.15580628 -38.66691276
OS 52.1484098 -38.6613654
OS 52.13823964 -38.65489348
OS 52.1252958 -38.64842156
OS 52.10957828 -38.6428742
OS 52.09201164 -38.63917596
OS 52.07259588 -38.63732684
OS 52.06427484 -38.63732684
OS 52.05780292 -38.6382514
OS 52.04948188 -38.63917596
OS 52.04023628 -38.64102508
OS 52.02914156 -38.6428742
OS 52.01712228 -38.64564788
OS 52.02636788 -38.57630588
OS 52.03099068 -38.57630588
OS 52.03468892 -38.57723044
OS 52.0467082 -38.57723044
OS 52.05687836 -38.57538132
OS 52.06889764 -38.5735322
OS 52.08276604 -38.57075852
OS 52.09848356 -38.56613572
OS 52.11327652 -38.5596638
OS 52.12899404 -38.55134276
OS 52.1299186 -38.55134276
OS 52.13084316 -38.5504182
OS 52.13546596 -38.54671996
OS 52.14193788 -38.54024804
OS 52.14933436 -38.531927
OS 52.15673084 -38.51990772
OS 52.16320276 -38.50603932
OS 52.16782556 -38.4903218
OS 52.16967468 -38.4810762
OS 52.16967468 -38.47090604
OS 52.16967468 -38.46998148
OS 52.16967468 -38.46905692
OS 52.16967468 -38.46350956
OS 52.16782556 -38.45611308
OS 52.16597644 -38.44594292
OS 52.1622782 -38.4348482
OS 52.1576554 -38.42282892
OS 52.15025892 -38.41080964
OS 52.14008876 -38.39971492
OS 52.1391642 -38.39879036
OS 52.1345414 -38.39509212
OS 52.12806948 -38.39046932
OS 52.11974844 -38.38492196
OS 52.10865372 -38.38029916
OS 52.09570988 -38.37567636
OS 52.08091692 -38.37197812
OS 52.06427484 -38.37105356
OS 52.05687836 -38.37105356
OS 52.04855732 -38.37290268
OS 52.0374626 -38.3747518
OS 52.02544332 -38.37845004
OS 52.01342404 -38.38307284
OS 52.0004802 -38.39046932
OS 51.98846092 -38.39971492
OS 51.98753636 -38.40063948
OS 51.98383812 -38.40526228
OS 51.97829076 -38.4117342
OS 51.97181884 -38.4209798
OS 51.96534692 -38.43299908
OS 51.958875 -38.44779204
OS 51.95332764 -38.46535868
OS 51.9496294 -38.485699
OS 51.8710418 -38.4718306
OS 51.8710418 -38.47090604
OS 51.87196636 -38.46813236
OS 51.87289092 -38.46443412
OS 51.87381548 -38.45888676
OS 51.8756646 -38.45241484
OS 51.87843828 -38.44501836
OS 51.88398564 -38.42745172
OS 51.89323124 -38.4071114
OS 51.90432596 -38.38677108
OS 51.91819436 -38.36735532
OS 51.935761 -38.34978868
OS 51.93668556 -38.34886412
OS 51.93853468 -38.34793956
OS 51.94130836 -38.34609044
OS 51.9450066 -38.34331676
OS 51.9496294 -38.33961852
OS 51.95610132 -38.33592028
OS 51.96257324 -38.33222204
OS 51.97089428 -38.32759924
OS 51.98938548 -38.32020276
OS 52.01065036 -38.31280628
OS 52.03561348 -38.30818348
OS 52.04855732 -38.30633436
OS 52.07167132 -38.30633436
OS 52.08184148 -38.30725892
OE
OB 51.07499564 -38.37105356 H
OS 51.06944828 -38.37105356
OS 51.06575004 -38.37197812
OS 51.05557988 -38.37382724
OS 51.0435606 -38.37660092
OS 51.0296922 -38.38214828
OS 51.01489924 -38.39046932
OS 51.00750276 -38.39601668
OS 51.00010628 -38.40156404
OS 50.99363436 -38.40896052
OS 50.98716244 -38.41728156
OS 50.98716244 -38.41820612
OS 50.98531332 -38.42005524
OS 50.9834642 -38.42375348
OS 50.98069052 -38.42837628
OS 50.97791684 -38.43577276
OS 50.9742186 -38.4440938
OS 50.97144492 -38.45426396
OS 50.96774668 -38.46628324
OS 50.96404844 -38.48015164
OS 50.9603502 -38.49586916
OS 50.95665196 -38.5134358
OS 50.95387828 -38.53285156
OS 50.9511046 -38.555041
OS 50.94925548 -38.57907956
OS 50.94833092 -38.60496724
OS 50.94740636 -38.6336286
OS 50.94740636 -38.63547772
OS 50.94740636 -38.64010052
OS 50.94740636 -38.64842156
OS 50.94833092 -38.65951628
OS 50.94833092 -38.67153556
OS 50.94925548 -38.68632852
OS 50.95018004 -38.70204604
OS 50.95202916 -38.71868812
OS 50.95665196 -38.75474596
OS 50.95942564 -38.7723126
OS 50.96312388 -38.78895468
OS 50.96682212 -38.8046722
OS 50.97236948 -38.81946516
OS 50.97791684 -38.832409
OS 50.98438876 -38.84350372
OS 50.98438876 -38.84442828
OS 50.98623788 -38.84535284
OS 50.99086068 -38.85182476
OS 50.99918172 -38.8601458
OS 51.00935188 -38.8693914
OS 51.02322028 -38.878637
OS 51.0389378 -38.88695804
OS 51.05650444 -38.89342996
OS 51.06575004 -38.89435452
OS 51.0759202 -38.89527908
OS 51.08146756 -38.89527908
OS 51.0851658 -38.89435452
OS 51.0944114 -38.8925054
OS 51.10735524 -38.88880716
OS 51.12122364 -38.88233524
OS 51.13694116 -38.87308964
OS 51.14433764 -38.86754228
OS 51.15173412 -38.8601458
OS 51.1591306 -38.85274932
OS 51.16652708 -38.84350372
OS 51.16652708 -38.84257916
OS 51.1683762 -38.84073004
OS 51.17022532 -38.83795636
OS 51.17207444 -38.83333356
OS 51.17577268 -38.82686164
OS 51.17854636 -38.8185406
OS 51.1822446 -38.809295
OS 51.18594284 -38.79820028
OS 51.18871652 -38.78433188
OS 51.19241476 -38.76953892
OS 51.196113 -38.75197228
OS 51.19888668 -38.73348108
OS 51.2007358 -38.71129164
OS 51.20258492 -38.68817764
OS 51.20443404 -38.66228996
OS 51.20443404 -38.6336286
OS 51.20443404 -38.63270404
OS 51.20443404 -38.63177948
OS 51.20443404 -38.62715668
OS 51.20443404 -38.61883564
OS 51.20350948 -38.60774092
OS 51.20350948 -38.59572164
OS 51.20258492 -38.58092868
OS 51.20166036 -38.56521116
OS 51.19981124 -38.54764452
OS 51.19518844 -38.51251124
OS 51.19241476 -38.4949446
OS 51.18871652 -38.47830252
OS 51.18501828 -38.462585
OS 51.17947092 -38.44779204
OS 51.17392356 -38.4348482
OS 51.16745164 -38.42375348
OS 51.16745164 -38.42282892
OS 51.16560252 -38.42190436
OS 51.1637534 -38.41913068
OS 51.16097972 -38.41543244
OS 51.15265868 -38.4071114
OS 51.14248852 -38.39694124
OS 51.12862012 -38.38769564
OS 51.1129026 -38.3793746
OS 51.10458156 -38.37567636
OS 51.09533596 -38.37290268
OS 51.0851658 -38.37197812
OS 51.07499564 -38.37105356
OE
OB 54.05947532 -38.37105356 H
OS 54.05392796 -38.37105356
OS 54.05022972 -38.37197812
OS 54.04005956 -38.37382724
OS 54.02804028 -38.37660092
OS 54.01417188 -38.38214828
OS 53.99937892 -38.39046932
OS 53.99198244 -38.39601668
OS 53.98458596 -38.40156404
OS 53.97811404 -38.40896052
OS 53.97164212 -38.41728156
OS 53.97164212 -38.41820612
OS 53.969793 -38.42005524
OS 53.96794388 -38.42375348
OS 53.9651702 -38.42837628
OS 53.96239652 -38.43577276
OS 53.95869828 -38.4440938
OS 53.9559246 -38.45426396
OS 53.95222636 -38.46628324
OS 53.94852812 -38.48015164
OS 53.94482988 -38.49586916
OS 53.94113164 -38.5134358
OS 53.93835796 -38.53285156
OS 53.93558428 -38.555041
OS 53.93373516 -38.57907956
OS 53.9328106 -38.60496724
OS 53.93188604 -38.6336286
OS 53.93188604 -38.63547772
OS 53.93188604 -38.64010052
OS 53.93188604 -38.64842156
OS 53.9328106 -38.65951628
OS 53.9328106 -38.67153556
OS 53.93373516 -38.68632852
OS 53.93465972 -38.70204604
OS 53.93650884 -38.71868812
OS 53.94113164 -38.75474596
OS 53.94390532 -38.7723126
OS 53.94760356 -38.78895468
OS 53.9513018 -38.8046722
OS 53.95684916 -38.81946516
OS 53.96239652 -38.832409
OS 53.96886844 -38.84350372
OS 53.96886844 -38.84442828
OS 53.97071756 -38.84535284
OS 53.97534036 -38.85182476
OS 53.9836614 -38.8601458
OS 53.99383156 -38.8693914
OS 54.00769996 -38.878637
OS 54.02341748 -38.88695804
OS 54.04098412 -38.89342996
OS 54.05022972 -38.89435452
OS 54.06039988 -38.89527908
OS 54.06594724 -38.89527908
OS 54.06964548 -38.89435452
OS 54.07889108 -38.8925054
OS 54.09183492 -38.88880716
OS 54.10570332 -38.88233524
OS 54.12142084 -38.87308964
OS 54.12881732 -38.86754228
OS 54.1362138 -38.8601458
OS 54.14361028 -38.85274932
OS 54.15100676 -38.84350372
OS 54.15100676 -38.84257916
OS 54.15285588 -38.84073004
OS 54.154705 -38.83795636
OS 54.15655412 -38.83333356
OS 54.16025236 -38.82686164
OS 54.16302604 -38.8185406
OS 54.16672428 -38.809295
OS 54.17042252 -38.79820028
OS 54.1731962 -38.78433188
OS 54.17689444 -38.76953892
OS 54.18059268 -38.75197228
OS 54.18336636 -38.73348108
OS 54.18521548 -38.71129164
OS 54.1870646 -38.68817764
OS 54.18891372 -38.66228996
OS 54.18891372 -38.6336286
OS 54.18891372 -38.63270404
OS 54.18891372 -38.63177948
OS 54.18891372 -38.62715668
OS 54.18891372 -38.61883564
OS 54.18798916 -38.60774092
OS 54.18798916 -38.59572164
OS 54.1870646 -38.58092868
OS 54.18614004 -38.56521116
OS 54.18429092 -38.54764452
OS 54.17966812 -38.51251124
OS 54.17689444 -38.4949446
OS 54.1731962 -38.47830252
OS 54.16949796 -38.462585
OS 54.1639506 -38.44779204
OS 54.15840324 -38.4348482
OS 54.15193132 -38.42375348
OS 54.15193132 -38.42282892
OS 54.1500822 -38.42190436
OS 54.14823308 -38.41913068
OS 54.1454594 -38.41543244
OS 54.13713836 -38.4071114
OS 54.1269682 -38.39694124
OS 54.1130998 -38.38769564
OS 54.09738228 -38.3793746
OS 54.08906124 -38.37567636
OS 54.07981564 -38.37290268
OS 54.06964548 -38.37197812
OS 54.05947532 -38.37105356
OE
OB 49.87491676 -38.43669732 H
OS 49.67336268 -38.72331092
OS 49.87491676 -38.72331092
OS 49.87491676 -38.43669732
OE
OB 56.14158444 -38.38492196 H
OS 55.95852156 -38.38492196
OS 55.95852156 -38.61328828
OS 56.13048972 -38.61328828
OS 56.13696164 -38.61236372
OS 56.14343356 -38.61236372
OS 56.15083004 -38.61143916
OS 56.16839668 -38.60959004
OS 56.18781244 -38.6058918
OS 56.2072282 -38.60034444
OS 56.22479484 -38.59294796
OS 56.23311588 -38.58832516
OS 56.2395878 -38.5827778
OS 56.24143692 -38.58092868
OS 56.24513516 -38.57723044
OS 56.25068252 -38.56983396
OS 56.25715444 -38.56058836
OS 56.26362636 -38.54856908
OS 56.26917372 -38.53377612
OS 56.27287196 -38.51713404
OS 56.27472108 -38.49771828
OS 56.27472108 -38.49679372
OS 56.27472108 -38.49586916
OS 56.27472108 -38.49124636
OS 56.27379652 -38.48292532
OS 56.2719474 -38.47367972
OS 56.27009828 -38.46350956
OS 56.26640004 -38.45149028
OS 56.26085268 -38.44039556
OS 56.25438076 -38.42930084
OS 56.2534562 -38.42837628
OS 56.25068252 -38.42467804
OS 56.24605972 -38.42005524
OS 56.24051236 -38.41358332
OS 56.23219132 -38.4071114
OS 56.22294572 -38.40156404
OS 56.21277556 -38.39601668
OS 56.20075628 -38.39139388
OS 56.19983172 -38.39139388
OS 56.19613348 -38.39046932
OS 56.19058612 -38.38954476
OS 56.18318964 -38.38769564
OS 56.17209492 -38.38677108
OS 56.15822652 -38.38584652
OS 56.14158444 -38.38492196
OE
SE
P -2.99999908 16.00000102 4 P 0 0 ;0=3,1=1
P -2.99999908 17.99999956 4 P 0 0 ;0=3,1=1
P -2.99999908 20.00000064 4 P 0 0 ;0=3,1=1
P -2.99999908 21.99999918 4 P 0 0 ;0=3,1=1
P -2.99999908 24.00000026 4 P 0 0 ;0=3,1=1
P -2.99999908 25.9999988 4 P 0 0 ;0=3,1=1
P -2.99999908 27.99999988 4 P 0 0 ;0=3,1=1
P -2.99999908 30.00000096 4 P 0 0 ;0=3,1=1
P -2.99999908 31.9999995 4 P 0 0 ;0=3,1=1
P -2.99999908 34.00000058 4 P 0 0 ;0=3,1=1
P -2.99999908 35.99999912 4 P 0 0 ;0=3,1=1
P -2.99999908 38.0000002 4 P 0 0 ;0=3,1=1
P -2.99999908 39.99999874 4 P 0 0 ;0=3,1=1
P 0.50000154 -3.99999962 4 P 0 0 ;0=3,1=1
P 2.50000008 -3.99999962 4 P 0 0 ;0=3,1=1
P 4.50000116 -3.99999962 4 P 0 0 ;0=3,1=1
P 6.4999997 -3.99999962 4 P 0 0 ;0=3,1=1
P 8.50000078 -3.99999962 4 P 0 0 ;0=3,1=1
P 10.49999932 -3.99999962 4 P 0 0 ;0=3,1=1
P 12.5000004 -3.99999962 4 P 0 0 ;0=3,1=1
P 12.74500118 40.26499948 4 P 0 0 ;0=3,1=1
P 12.74500118 41.21500012 4 P 0 0 ;0=3,1=1
P 12.74500118 44.63999962 4 P 0 0 ;0=3,1=1
P 12.75500116 42.16500076 4 P 0 0 ;0=3,1=1
P 12.98999942 18.0150008 4 P 0 0 ;0=3,1=1
P 14.50000148 -3.99999962 4 P 0 0 ;0=3,1=1
P 15.88470534 21.56499878 4 P 0 0 ;0=3,1=1
P 16.30970576 23.03999964 4 P 0 0 ;0=3,1=1
P 16.50000002 -3.99999962 4 P 0 0 ;0=3,1=1
P 17.57500168 13.89000016 4 P 0 0 ;0=3,1=1
P 17.915001 15.69625258 4 P 0 0 ;0=3,1=1
P 18.8149992 15.10000028 4 P 0 0 ;0=3,1=1
P 18.8149992 15.98270108 4 P 0 0 ;0=3,1=1
P 18.8149992 16.85250122 4 P 0 0 ;0=3,1=1
P 19.01500134 7.39000046 4 P 0 0 ;0=3,1=1
P 19.01500134 8.5900006 4 P 0 0 ;0=3,1=1
P 19.01500134 9.7899982 4 P 0 0 ;0=3,1=1
P 19.01500134 11.09000068 4 P 0 0 ;0=3,1=1
P 19.01500134 12.39000062 4 P 0 0 ;0=3,1=1
P 21.11499968 6.76500044 4 P 0 0 ;0=3,1=1
P 21.11499968 7.78999966 4 P 0 0 ;0=3,1=1
P 21.11499968 8.9899998 4 P 0 0 ;0=3,1=1
P 21.11499968 10.28999974 4 P 0 0 ;0=3,1=1
P 21.11499968 11.38590052 4 P 0 0 ;0=3,1=1
P 22.05919388 12.29000082 4 P 0 0 ;0=3,1=1
P 22.45970616 20.01499934 4 P 0 0 ;0=3,1=1
P 23.29999912 38.90000094 4 P 0 0 ;0=3,1=1
P 23.33999904 44.0138312 4 P 0 0 ;0=3,1=1
P 23.4097068 20.04000056 4 P 0 0 ;0=3,1=1
P 24.35970744 20.04000056 4 P 0 0 ;0=3,1=1
P 24.49999926 -3.50000062 4 P 0 0 ;0=3,1=1
P 25.7999992 38.90000094 4 P 0 0 ;0=3,1=1
P 26.50000034 -3.50000062 4 P 0 0 ;0=3,1=1
P 28.50000142 -3.50000062 4 P 0 0 ;0=3,1=1
P 30.49999996 -3.50000062 4 P 0 0 ;0=3,1=1
P 32.50000104 -3.50000062 4 P 0 0 ;0=3,1=1
P 32.80000044 38.90000094 4 P 0 0 ;0=3,1=1
P 35.30000052 44.0000009 4 P 0 0 ;0=3,1=1
P 38.4999992 -3.50000062 4 P 0 0 ;0=3,1=1
P 39.60000208 38.91499964 4 P 0 0 ;0=3,1=1
P 40.50000028 -3.50000062 4 P 0 0 ;0=3,1=1
P 40.67999992 42.76499956 4 P 0 0 ;0=3,1=1
P 42.2249981 38.91499964 4 P 0 0 ;0=3,1=1
P 44.4999999 0.499999 4 P 0 0 ;0=3,1=1
P 44.4999999 2.50000008 4 P 0 0 ;0=3,1=1
P 44.4999999 4.49999862 4 P 0 0 ;0=3,1=1
P 44.4999999 6.4999997 4 P 0 0 ;0=3,1=1
P 44.4999999 8.49999824 4 P 0 0 ;0=3,1=1
P 44.4999999 10.49999932 4 P 0 0 ;0=3,1=1
P 44.4999999 12.49999786 4 P 0 0 ;0=3,1=1
P 44.4999999 14.49999894 4 P 0 0 ;0=3,1=1
P 44.4999999 16.50000002 4 P 0 0 ;0=3,1=1
P 44.4999999 18.49999856 4 P 0 0 ;0=3,1=1
P 44.4999999 20.49999964 4 P 0 0 ;0=3,1=1
P 44.4999999 22.49999818 4 P 0 0 ;0=3,1=1
P 44.4999999 24.49999926 4 P 0 0 ;0=3,1=1
P 44.4999999 26.4999978 4 P 0 0 ;0=3,1=1
P 44.4999999 28.49999888 4 P 0 0 ;0=3,1=1
P 44.4999999 30.49999996 4 P 0 0 ;0=3,1=1
P 44.4999999 32.4999985 4 P 0 0 ;0=3,1=1
P 44.4999999 34.49999958 4 P 0 0 ;0=3,1=1
P 44.4999999 36.49999812 4 P 0 0 ;0=3,1=1
P 44.4999999 38.4999992 4 P 0 0 ;0=3,1=1
P 44.4999999 40.49999774 4 P 0 0 ;0=3,1=1

### steps/pcb/layers/l04-bottom_layer/features
UNITS=MM
#Layer_Physical_Order=4
#Layer_Color=16711680
#
#Feature symbol names
#
$0 r185.0009
$1 r199.9996
$2 r399.9992
$3 r299.9994
$4 rect1050.00044x1749.99904
$5 rect1050.00044x900.00074
$6 rect569.99886x619.99876
$7 rect419.99916x439.99912
$8 r6200.0003
$9 rect2300.00048x3300.00102
$10 rect800.00094x1449.99964
$11 rect599.9988x299.9994
$12 rect299.9994x1725.00036
$13 rect1299.99994x1649.99924
$14 rect599.9988x619.99876
$15 rect459.99908x419.99916
$16 rect419.99916x459.99908
$17 rect619.99876x599.9988
$18 rect619.99876x569.99886
$19 r1000.00054
$20 r349.9993
$21 r99.9998
$22 r2090.0009
$23 r5299.99956
$24 r1562.00094
$25 r1524
$26 r1799.99894
$27 r599.9988

#
#Feature attribute names
#
@0 .geometry
@1 .pad_usage
@2 .smd
@3 .nomenclature
@4 .string
@5 .string_angle

#
#Feature attribute text strings
#
&0 SMD_RectX1050.0004Y1749.9990
&1 SMD_RectX1050.0004Y900.0007
&2 SMD_RectX569.9989Y619.9988
&3 SMD_RectX419.9992Y439.9991
&4 SMD_RoundX6200.0003Y6200.0003
&5 SMD_RectX2300.0005Y3300.0010
&6 SMD_RectX800.0009Y1449.9996
&7 SMD_RectX599.9988Y299.9994
&8 SMD_RectX299.9994Y1725.0004
&9 SMD_RectX1299.9999Y1649.9992
&10 SMD_RectX599.9988Y619.9988
&11 SMD_RectX459.9991Y419.9992
&12 SMD_RectX419.9992Y459.9991
&13 SMD_RectX619.9988Y599.9988
&14 SMD_RectX619.9988Y569.9989
&15 SMD_RoundX1000.0005Y1000.0005
&16 Pad_Simple_X2090.0009Y2090.0009H1090.0004C2106.0004
&17 Pad_Simple_X5299.9996Y5299.9996H2999.9991C4015.9991
&18 Pad_Simple_X1562.0009Y1562.0009H961.9996C1977.9996
&19 Pad_Simple_X1524.0000Y1524.0000H762.0000C1778.0000
&20 Pad_Simple_X1799.9989Y1799.9989H1200.0001C2216.0001
&21 VIA_RoundD599.9988H299.9994C1315.9994

#
#Layer features
#
A 15.36500102 18.0150008 15.56500062 18.2150004 15.36500102 18.2150004 1 P 0 N
A 15.84000134 18.49000112 15.56500062 18.2150004 15.84000134 18.2150004 1 P 0 N
A 16.40249958 17.869662 16.3439221 18.01108412 16.20249998 17.869662 1 P 0 N
A 18.22000166 19.96000072 18.44000122 19.74000116 18.44000122 19.96000072 3 P 0 N
A 18.43000124 18.49000112 18.68000074 18.74000062 18.43000124 18.74000062 1 P 0 N
A 18.68000074 19.50000164 18.44000122 19.74000116 18.44000122 19.50000164 3 P 0 N
A 19.13999982 20.26500138 19.51500034 19.89000086 19.51500034 20.26500138 2 P 0 N
A 39.78999916 17.36499956 39.35499876 17.79999996 39.35499876 17.36499956 1 P 0 N
A 39.89605178 35.08605124 40.64 36.88210302 38.1 36.88210302 0 P 0 N
L -9.5600012 -24.45999934 40.4400004 -24.45999934 21 P 0
L -9.5600012 -35.9599992 -9.5600012 -24.45999934 21 P 0
L -9.5600012 -35.9599992 28.439999 -35.9599992 21 P 0
L -9.5600012 -39.45999982 -9.5600012 -35.9599992 21 P 0
L -9.5600012 -39.45999982 28.439999 -39.45999982 21 P 0
L -9.5600012 -42.96000044 -9.5600012 -39.45999982 21 P 0
L -9.5600012 -42.96000044 28.439999 -42.96000044 21 P 0
L -10.0600002 -23.96000034 62.93999858 -23.96000034 21 P 0
L -10.0600002 -43.45999944 -10.0600002 -23.96000034 21 P 0
L -10.0600002 -43.45999944 62.93999858 -43.45999944 21 P 0
L 14.86499948 18.0150008 14.86499948 19.16500104 1 P 0
L 14.86499948 18.0150008 15.36500102 18.0150008 1 P 0
L 14.86499948 19.16500104 14.86499948 20.21500148 1 P 0
L 15.84000134 18.49000112 16.31500166 18.49000112 1 P 0
L 15.86500002 20.21500148 16.95499784 20.21500148 1 P 0
L 16.31500166 18.04000202 16.34391956 18.01108158 1 P 0
L 16.31500166 18.94000276 16.46500136 18.94000276 1 P 0
L 16.40249958 17.00250346 16.40249958 17.869662 1 P 0
L 16.46500136 18.94000276 16.95499784 19.42999924 1 P 0
L 16.95499784 19.42999924 16.95499784 20.21500148 1 P 0
L 16.95499784 21.17499956 16.95499784 22.29000114 1 P 0
L 17.1650025 16.09000084 17.1650025 16.85250122 20 P 0
L 17.1650025 16.85250122 17.1650025 17.83497576 20 P 0
L 17.1650025 17.83497576 17.37002876 18.04000202 20 P 0
L 17.37002876 18.04000202 18.0150008 18.04000202 20 P 0
L 18.0150008 18.04000202 20.36500118 18.04000202 20 P 0
L 18.0150008 18.49000112 18.43000124 18.49000112 1 P 0
L 18.22000166 19.96000072 18.22000166 21.17499956 3 P 0
L 18.68000074 18.74000062 18.68000074 19.50000164 3 P 0
L 19.13999982 20.26500138 19.13999982 21.17499956 2 P 0
L 20.36500118 18.04000202 21.11500222 17.29000098 20 P 0
L 21.11500222 16.79000198 21.11500222 17.29000098 20 P 0
L 28.439999 -35.96000174 45.44000056 -35.9599992 21 P 0
L 28.439999 -39.45999982 28.439999 -35.9599992 21 P 0
L 28.439999 -39.46000236 45.44000056 -39.45999982 21 P 0
L 28.439999 -42.96000044 28.439999 -39.45999982 21 P 0
L 28.439999 -42.96000298 45.44000056 -42.96000044 21 P 0
L 37.8500005 17.79999996 39.35499876 17.79999996 1 P 0
L 37.8500005 33.03999996 39.89605178 35.08605124 0 P 0
L 39.78999916 15.96499982 39.78999916 17.36499956 1 P 0
L 40.4400004 -24.45999934 62.43999958 -24.45999934 21 P 0
L 40.4400004 -35.9599992 40.4400004 -24.45999934 21 P 0
L 40.64 36.88210302 40.64 40.64 0 P 0
L 45.44000056 -35.9599992 62.43999958 -35.9599992 21 P 0
L 45.44000056 -39.45999982 62.43999958 -39.45999982 21 P 0
L 45.44000056 -42.96000044 45.44000056 -35.9599992 21 P 0
L 45.44000056 -42.96000044 62.43999958 -42.96000044 21 P 0
L 62.43999958 -35.9599992 62.43999958 -24.45999934 21 P 0
L 62.43999958 -42.96000044 62.43999958 -35.9599992 21 P 0
L 62.93999858 -43.45999944 62.93999858 -23.96000034 21 P 0
P -2.38499904 43.5150006 19 P 0 0 ;0=15,1=0,2
P 0 0 22 P 0 0 ;0=16,1=0
P 0 40.64 22 P 0 0 ;0=16,1=0
P 2.0779994 43.3299997 22 P 0 0 ;0=16,1=0
P 4.39999882 2.00000108 8 P 0 0 ;0=4,1=0,2
P 4.39999882 38.599999 8 P 0 0 ;0=4,1=0,2
P 4.8300005 7.63999996 26 P 0 0 ;0=20,1=0
P 4.8300005 7.63999996 25 P 0 0 ;0=19,1=0
P 4.8300005 12.71999996 26 P 0 0 ;0=20,1=0
P 4.8300005 12.71999996 25 P 0 0 ;0=19,1=0
P 4.8300005 17.79999996 26 P 0 0 ;0=20,1=0
P 4.8300005 17.79999996 25 P 0 0 ;0=19,1=0
P 4.8300005 33.03999996 26 P 0 0 ;0=20,1=0
P 4.8300005 33.03999996 25 P 0 0 ;0=19,1=0
P 5.1259994 43.3299997 22 P 0 0 ;0=16,1=0
P 8.1739994 43.3299997 22 P 0 0 ;0=16,1=0
P 11.2219994 43.3299997 22 P 0 0 ;0=16,1=0
P 13.9050014 18.0150008 6 P 0 0 ;0=2,1=0,2
P 13.9050014 19.16500104 6 P 0 0 ;0=2,1=0,2
P 14.2699994 43.3299997 22 P 0 0 ;0=16,1=0
P 14.86499948 18.0150008 6 P 0 0 ;0=2,1=0,2
P 14.86499948 19.16500104 6 P 0 0 ;0=2,1=0,2
P 14.86499948 20.21500148 16 P 0 0 ;0=12,1=0,2
P 14.86499948 20.87500016 16 P 0 0 ;0=12,1=0,2
P 15.86500002 20.21500148 7 P 0 0 ;0=3,1=0,2
P 15.86500002 20.89500012 7 P 0 0 ;0=3,1=0,2
P 15.91499992 7.38999792 13 P 0 0 ;0=9,1=0,2
P 15.91499992 9.7899982 13 P 0 0 ;0=9,1=0,2
P 15.91499992 12.39000062 13 P 0 0 ;0=9,1=0,2
P 16.29499916 22.29000114 15 P 0 0 ;0=11,1=0,2
P 16.31500166 18.04000202 11 P 0 0 ;0=7,1=0,2
P 16.31500166 18.49000112 11 P 0 0 ;0=7,1=0,2
P 16.31500166 18.94000276 11 P 0 0 ;0=7,1=0,2
P 16.41500146 16.99000158 10 P 0 0 ;0=6,1=0,2
P 16.65500352 14.7900009 14 P 0 0 ;0=10,1=0,2
P 16.95499784 20.21500148 18 P 0 0 ;0=14,1=0,2
P 16.95499784 21.17499956 18 P 0 0 ;0=14,1=0,2
P 16.95499784 22.29000114 15 P 0 0 ;0=11,1=0,2
P 17.1650025 16.85250122 12 P 0 0 ;0=8,1=0,2
P 17.57500168 14.7900009 14 P 0 0 ;0=10,1=0,2
P 17.7150014 7.38999792 13 P 0 0 ;0=9,1=0,2
P 17.7150014 9.7899982 13 P 0 0 ;0=9,1=0,2
P 17.7150014 12.39000062 13 P 0 0 ;0=9,1=0,2
P 17.915001 16.99000158 10 P 0 0 ;0=6,1=0,2
P 18.0150008 18.04000202 11 P 0 0 ;0=7,1=0,2
P 18.0150008 18.49000112 11 P 0 0 ;0=7,1=0,2
P 18.0150008 18.94000276 11 P 0 0 ;0=7,1=0,2
P 18.22000166 21.17499956 14 P 0 0 ;0=10,1=0,2
P 19.13999982 21.17499956 14 P 0 0 ;0=10,1=0,2
P 20.24000016 42.13999954 23 P 0 0 ;0=17,1=0
P 20.43999976 -1.26000002 23 P 0 0 ;0=17,1=0
P 20.76500038 16.85250122 9 P 0 0 ;0=5,1=0,2
P 22.41500216 7.7900022 13 P 0 0 ;0=9,1=0,2
P 22.41500216 10.29000228 13 P 0 0 ;0=9,1=0,2
P 22.95500362 12.29000082 14 P 0 0 ;0=10,1=0,2
P 23.87500178 12.29000082 14 P 0 0 ;0=10,1=0,2
P 24.21500364 7.7900022 13 P 0 0 ;0=9,1=0,2
P 24.21500364 10.29000228 13 P 0 0 ;0=9,1=0,2
P 26.06499994 16.85250122 9 P 0 0 ;0=5,1=0,2
P 32.24000156 7.63999996 4 P 0 0 ;0=0,1=0,2
P 35.24000064 7.63999996 4 P 0 0 ;0=0,1=0,2
P 35.50000012 -1.00000054 8 P 0 0 ;0=4,1=0,2
P 36.20000126 40.10000108 8 P 0 0 ;0=4,1=0,2
P 37.8500005 7.63999996 26 P 0 0 ;0=20,1=0
P 37.8500005 7.63999996 24 P 0 0 ;0=18,1=0
P 37.8500005 9.94000044 14 P 0 0 ;0=10,1=0,2
P 37.8500005 12.71999996 26 P 0 0 ;0=20,1=0
P 37.8500005 12.71999996 24 P 0 0 ;0=18,1=0
P 37.8500005 17.79999996 26 P 0 0 ;0=20,1=0
P 37.8500005 17.79999996 24 P 0 0 ;0=18,1=0
P 37.8500005 22.87999996 24 P 0 0 ;0=18,1=0
P 37.8500005 22.87999996 26 P 0 0 ;0=20,1=0
P 37.8500005 33.03999996 24 P 0 0 ;0=18,1=0
P 37.8500005 33.03999996 26 P 0 0 ;0=20,1=0
P 38.76999866 9.94000044 14 P 0 0 ;0=10,1=0,2
P 39.78999916 14.51500018 5 P 0 0 ;0=1,1=0,2
P 39.78999916 15.96499982 5 P 0 0 ;0=1,1=0,2
P 40.0900011 7.63999996 17 P 0 0 ;0=13,1=0,2
P 40.0900011 8.55999812 17 P 0 0 ;0=13,1=0,2
P 40.64 0 22 P 0 0 ;0=16,1=0
P 40.64 40.64 22 P 0 0 ;0=16,1=0
P 40.67999992 20.33999996 22 P 0 0 ;0=16,1=0
P 43.11499886 43.5150006 19 P 0 0 ;0=15,1=0,2
P 43.18999998 -2.80999946 19 P 0 0 ;0=15,1=0,2
S P 0
OB 16.8150032 17.00366932 I
OS 16.81176216 16.99881792
OS 16.78265884 16.85250122
OS 16.78265884 16.09000084
OS 16.81176216 15.94368414
OS 16.8150032 15.93883274
OS 16.8150032 15.42999708
OS 16.78200352 15.40595852
OS 16.78200352 14.7900009
OS 16.78200352 14.22600152
OS 16.95499784 14.22600152
OS 16.95499784 14.02999734
OS 16.95500038 14.00214878
OS 16.93368724 13.95069346
OS 16.92867582 13.94568204
OS 16.81501082 13.89000524
OS 16.81499812 13.8900027
OS 16.81499304 13.89000524
OS 16.81499304 13.89000016
OS 16.76623012 13.88519702
OS 16.67610838 13.84786664
OS 16.60713214 13.7788904
OS 16.5698043 13.68876866
OS 16.56500116 13.63999812
OS 16.56500116 -2.10999832
OS 16.56500116 -2.22474282
OS 16.52022858 -2.4498173
OS 16.43240808 -2.66183364
OS 16.30491532 -2.85264352
OS 16.14264234 -3.0149165
OS 15.95183246 -3.14240926
OS 15.73981612 -3.23022976
OS 15.51474164 -3.2749998
OS 15.39999968 -3.2749998
OS -2.42500658 -3.27500234
OS -2.54812292 -3.27500488
OS -2.78962104 -3.22697094
OS -3.01710852 -3.13274456
OS -3.22184268 -2.99594778
OS -3.39595206 -2.82183586
OS -3.53274884 -2.6171017
OS -3.62697268 -2.38961168
OS -3.67500408 -2.14811356
OS -3.674999 -2.02499722
OS -3.674999 12.835001
OS -3.674999 13.08516814
OS -3.57738934 13.57588852
OS -3.38591906 14.03813804
OS -3.10794908 14.4541494
OS -2.75415756 14.80794092
OS -2.33814366 15.0859109
OS -1.87589414 15.27738118
OS -1.38517376 15.37499084
OS -1.13500662 15.3749883
OS -1.134999 15.375001
OS 15.33374886 15.375001
OS 15.39642082 15.3811732
OS 15.5122245 15.4291411
OS 15.6008578 15.5177744
OS 15.6488257 15.63357808
OS 15.65500044 15.69625258
OS 15.65500044 17.35499958
OS 15.6549979 17.42660726
OS 15.70980602 17.55892094
OS 15.78688994 17.63600232
OS 16.19858076 17.63600232
OS 16.19858076 17.00250346
OS 16.2141027 16.92446704
OS 16.25830632 16.8583102
OS 16.32446316 16.81410658
OS 16.40249958 16.79858464
OS 16.480536 16.81410658
OS 16.54669284 16.8583102
OS 16.59089646 16.92446704
OS 16.6064184 17.00250346
OS 16.6064184 17.63600232
OS 16.8150032 17.63600232
OS 16.8150032 17.00366932
OE
OB 16.52800352 15.35400028 H
OS 16.10100412 15.35400028
OS 16.10100412 14.9170009
OS 16.52800352 14.9170009
OS 16.52800352 15.35400028
OE
OB 16.52800352 14.6630009 H
OS 16.10100412 14.6630009
OS 16.10100412 14.22600152
OS 16.52800352 14.22600152
OS 16.52800352 14.6630009
OE
OB 4.9748186 13.81999776 H
OS 4.6851824 13.81999776
OS 4.40541664 13.74503474
OS 4.15458656 13.60021664
OS 3.94978382 13.3954139
OS 3.80496572 13.14458382
OS 3.7300027 12.86481806
OS 3.7300027 12.57518186
OS 3.80496572 12.2954161
OS 3.94978382 12.04458602
OS 4.15458656 11.83978328
OS 4.40541664 11.69496518
OS 4.6851824 11.62000216
OS 4.9748186 11.62000216
OS 5.25458436 11.69496518
OS 5.50541444 11.83978328
OS 5.71021718 12.04458602
OS 5.85503528 12.2954161
OS 5.9299983 12.57518186
OS 5.9299983 12.86481806
OS 5.85503528 13.14458382
OS 5.71021718 13.3954139
OS 5.50541444 13.60021664
OS 5.25458436 13.74503474
OS 4.9748186 13.81999776
OE
OB 4.9748186 8.73999776 H
OS 4.6851824 8.73999776
OS 4.40541664 8.66503474
OS 4.15458656 8.52021664
OS 3.94978382 8.3154139
OS 3.80496572 8.06458382
OS 3.7300027 7.78481806
OS 3.7300027 7.49518186
OS 3.80496572 7.2154161
OS 3.94978382 6.96458602
OS 4.15458656 6.75978328
OS 4.40541664 6.61496518
OS 4.6851824 6.54000216
OS 4.9748186 6.54000216
OS 5.25458436 6.61496518
OS 5.50541444 6.75978328
OS 5.71021718 6.96458602
OS 5.85503528 7.2154161
OS 5.9299983 7.49518186
OS 5.9299983 7.78481806
OS 5.85503528 8.06458382
OS 5.71021718 8.3154139
OS 5.50541444 8.52021664
OS 5.25458436 8.66503474
OS 4.9748186 8.73999776
OE
OB 0.24999442 1.2778359 H
OS 0.24999442 0.25000966
OS 1.27783336 0.25000966
OS 1.2104751 0.501396
OS 1.0394569 0.79760318
OS 0.79760318 1.0394569
OS 0.501396 1.2104751
OS 0.24999442 1.2778359
OE
OB -0.25000458 1.27783336 H
OS -0.501396 1.2104751
OS -0.79760318 1.0394569
OS -1.0394569 0.79760318
OS -1.2104751 0.501396
OS -1.27783336 0.25000966
OS -0.25000458 0.25000966
OS -0.25000458 1.27783336
OE
OB -0.25000458 -0.24998934 H
OS -1.27783844 -0.24998934
OS -1.2104751 -0.501396
OS -1.0394569 -0.79760318
OS -0.79760318 -1.0394569
OS -0.501396 -1.2104751
OS -0.25000458 -1.27783336
OS -0.25000458 -0.24998934
OE
OB 1.27783844 -0.24998934 H
OS 0.24999442 -0.24998934
OS 0.24999442 -1.2778359
OS 0.501396 -1.2104751
OS 0.79760318 -1.0394569
OS 1.0394569 -0.79760318
OS 1.2104751 -0.501396
OS 1.27783844 -0.24998934
OE
OB 4.65971382 5.29999956 H
OS 4.14028382 5.29999956
OS 3.627247 5.21874242
OS 3.13323986 5.05822966
OS 2.67042392 4.82241098
OS 2.25019362 4.5170979
OS 1.882902 4.14980628
OS 1.57758892 3.72957598
OS 1.34177024 3.26676004
OS 1.18125748 2.7727529
OS 1.10000034 2.25971608
OS 1.10000034 1.74028608
OS 1.18125748 1.22724926
OS 1.34177024 0.73324212
OS 1.57758892 0.27042618
OS 1.882902 -0.14980412
OS 2.25019362 -0.51709574
OS 2.67042392 -0.82240882
OS 3.13323986 -1.0582275
OS 3.627247 -1.21874026
OS 4.14028382 -1.2999974
OS 4.65971382 -1.2999974
OS 5.17275064 -1.21874026
OS 5.66675778 -1.0582275
OS 6.12957372 -0.82240882
OS 6.54980402 -0.51709574
OS 6.91709564 -0.14980412
OS 7.22240872 0.27042618
OS 7.4582274 0.73324212
OS 7.61874016 1.22724926
OS 7.6999973 1.74028608
OS 7.6999973 2.25971608
OS 7.61874016 2.7727529
OS 7.4582274 3.26676004
OS 7.22240872 3.72957598
OS 6.91709564 4.14980628
OS 6.54980402 4.5170979
OS 6.12957372 4.82241098
OS 5.66675778 5.05822966
OS 5.17275064 5.21874242
OS 4.65971382 5.29999956
OE
SE
S P 0
OB 21.91500062 20.19000026 I
OS 21.91500062 13.89000016
OS 19.78128632 13.89000016
OS 19.31500074 14.35628828
OS 19.31500074 17.11865766
OS 18.5690002 17.8646582
OS 18.5690002 17.91300202
OS 18.0150008 17.91300202
OS 18.0150008 18.16700202
OS 18.5690002 18.16700202
OS 18.5690002 18.18999918
OS 18.59000346 18.18999918
OS 18.80874826 18.40875414
OS 18.81656384 18.41030862
OS 18.93233704 18.48766432
OS 19.00969274 18.60343752
OS 19.01124976 18.61126326
OS 19.04000002 18.64001606
OS 19.04000002 19.50000164
OS 19.04155958 19.50000164
OS 19.04000002 19.50784262
OS 19.04000002 20.01500188
OS 19.21500094 20.1900028
OS 21.91500062 20.19000026
OE
SE
S P 0
OB 32.17499788 24.54999408 I
OS 32.42516502 24.54999662
OS 32.9158854 24.4523895
OS 33.37813492 24.26092176
OS 33.79415136 23.98295178
OS 34.14794034 23.6291628
OS 34.42591286 23.2131489
OS 34.61738314 22.75089938
OS 34.7149928 22.260179
OS 34.71499026 22.01001186
OS 34.71498772 22.01001186
OS 34.71499534 22.01000678
OS 34.7149928 11.55441428
OS 34.66050726 11.49992874
OS 34.61630364 11.43377444
OS 34.55159968 11.27757206
OS 34.53607774 11.19953564
OS 34.53608028 11.11499174
OS 34.53608028 8.71499908
OS 34.51500082 8.71499908
OS 34.51500082 6.56500084
OS 34.53608028 6.56500084
OS 34.53608028 3.9650035
OS 34.53607774 3.8812851
OS 34.53999442 3.86158994
OS 34.53999442 3.84149854
OS 34.57266136 3.67727992
OS 34.5803474 3.65872268
OS 34.58426662 3.63902244
OS 34.6483432 3.4843339
OS 34.65949888 3.46763594
OS 34.66718492 3.44908378
OS 34.6695395 3.44555826
OS 34.57602686 3.315589
OS 34.45428466 3.21088004
OS 34.3113741 3.13765184
OS 34.15527586 3.0999938
OS 34.07498646 3.09999888
OS 24.53412416 3.09999888
OS 24.32643598 3.14130944
OS 24.13079756 3.2223456
OS 23.95472984 3.33999078
OS 23.8049943 3.48972632
OS 23.68734912 3.66579404
OS 23.60631296 3.86143246
OS 23.5650024 4.06912064
OS 23.5650024 4.17500054
OS 23.5650024 11.72600144
OS 23.74798146 11.72600144
OS 23.74798146 12.29001606
OS 23.74798146 12.8540002
OS 23.5650024 12.8540002
OS 23.5650024 13.04249868
OS 23.56499986 13.10416226
OS 23.6121956 13.21809904
OS 23.69939888 13.30530232
OS 23.81333566 13.35249806
OS 23.87499924 13.35249552
OS 23.87500178 13.3525006
OS 24.51749986 13.3525006
OS 24.59504606 13.36013838
OS 24.73833762 13.41949056
OS 24.8480072 13.52916014
OS 24.90735938 13.6724517
OS 24.9149997 13.75000044
OS 24.91500224 13.89000016
OS 24.91500478 13.8900027
OS 24.9149997 13.89000524
OS 24.9149997 19.69000126
OS 24.91499716 19.69000126
OS 24.91499462 23.10999696
OS 24.9105928 23.19968436
OS 24.87560176 23.37560984
OS 24.8069608 23.54132706
OS 24.70730644 23.69047078
OS 24.58047154 23.81730568
OS 24.43132782 23.91696004
OS 24.2656106 23.985601
OS 24.11693424 24.01517168
OS 24.08968512 24.02059458
OS 24.00006376 24.02499132
OS 24.0000028 24.0249964
OS 24.00000026 24.02500148
OS 23.99999772 24.02499894
OS 15.54999684 24.02499894
OS 15.45732748 24.01587018
OS 15.286101 23.94494576
OS 15.1550497 23.81389446
OS 15.08412528 23.64266798
OS 15.07499906 23.55000116
OS 15.07499906 21.3589997
OS 14.99199694 21.3589997
OS 14.99199694 20.87500778
OS 14.86499694 20.87500778
OS 14.86499694 20.74800778
OS 14.4009999 20.74800778
OS 14.4009999 20.64500062
OS 14.40000168 20.64500062
OS 14.35903148 20.64096456
OS 14.28333186 20.60960826
OS 14.22539192 20.55166832
OS 14.19403562 20.4759687
OS 14.1900021 20.43500104
OS 14.1900021 19.72900042
OS 14.0320014 19.72900042
OS 14.0320014 19.16500104
OS 13.9050014 19.16500104
OS 13.9050014 19.03800104
OS 13.36600324 19.03800104
OS 13.36600324 18.85500166
OS 12.81999468 18.85500166
OS 12.79115298 18.85499912
OS 12.7378587 18.87707172
OS 12.69706884 18.91786158
OS 12.67499624 18.97115586
OS 12.67499878 18.99999756
OS 12.67499878 19.8999983
OS 12.67499624 19.96265502
OS 12.72295398 20.07843076
OS 12.81156442 20.1670412
OS 12.92734016 20.21499894
OS 12.98999688 20.2149964
OS 12.98999942 20.21500148
OS 13.15999908 20.21500148
OS 13.24974236 20.22383814
OS 13.41556118 20.29252228
OS 13.54247482 20.41943592
OS 13.61115896 20.58525474
OS 13.61999562 20.67499802
OS 13.6200007 20.67500056
OS 13.6200007 23.64398116
OS 13.6586214 23.83814384
OS 13.73437944 24.02104162
OS 13.84436398 24.18564632
OS 13.98434846 24.3256308
OS 14.14895316 24.43561534
OS 14.33185094 24.51137338
OS 14.52601362 24.54999408
OS 14.62499742 24.54999408
OS 14.62499996 24.54999916
OS 32.17499788 24.54999408
OE
OB 14.73799694 21.3589997 H
OS 14.4009999 21.3589997
OS 14.4009999 21.00200778
OS 14.73799694 21.00200778
OS 14.73799694 21.3589997
OE
OB 13.7780014 19.72900042 H
OS 13.36600324 19.72900042
OS 13.36600324 19.29200104
OS 13.7780014 19.29200104
OS 13.7780014 19.72900042
OE
OB 24.42900118 12.8540002 H
OS 24.00198146 12.8540002
OS 24.00198146 12.41701606
OS 24.42900118 12.41701606
OS 24.42900118 12.8540002
OE
OB 24.42900118 12.16301606 H
OS 24.00198146 12.16301606
OS 24.00198146 11.72600144
OS 24.42900118 11.72600144
OS 24.42900118 12.16301606
OE
SE
S P 0
OB 37.9830838 11.48138674 I
OS 38.09138686 11.37308368
OS 38.1499999 11.23158028
OS 38.1499999 9.52999872
OS 38.15845302 9.44415688
OS 38.22415266 9.28554658
OS 38.34554688 9.16415236
OS 38.50415718 9.09845272
OS 38.58999902 9.0899996
OS 39.08999802 9.08999452
OS 39.13972614 9.08999706
OS 39.23161318 9.0519377
OS 39.30193816 8.98161272
OS 39.31267728 8.95568694
OS 39.33999498 8.8400128
OS 39.33999498 8.83999756
OS 39.33999244 8.83999756
OS 39.34000006 8.83999248
OS 39.34000006 8.41499968
OS 39.34912628 8.32233032
OS 39.4200507 8.1511013
OS 39.551102 8.02005
OS 39.72233102 7.94912558
OS 39.81500038 7.93999936
OS 42.0399972 7.93999428
OS 42.14442676 7.93999682
OS 42.33738802 7.86007064
OS 42.48507124 7.71238742
OS 42.55968628 7.53225062
OS 42.56499488 7.41506518
OS 42.56499488 7.4149966
OS 42.56499234 7.4149966
OS 42.56499996 7.41499152
OS 42.56499996 3.81366776
OS 42.53521592 3.66393984
OS 42.47679592 3.52289872
OS 42.39198024 3.39596476
OS 42.28403278 3.2880173
OS 42.15709882 3.20320162
OS 42.0160577 3.14478162
OS 41.86632978 3.11500012
OS 35.5899974 3.11500012
OS 35.506279 3.11499758
OS 35.34206038 3.14766198
OS 35.18737184 3.21173856
OS 35.04815444 3.30475844
OS 34.92975742 3.42315546
OS 34.83673754 3.56237286
OS 34.77266096 3.7170614
OS 34.73999656 3.88128002
OS 34.7399991 3.96499842
OS 34.7399991 11.11499682
OS 34.73999656 11.1995331
OS 34.80470052 11.35573802
OS 34.92425324 11.47529328
OS 35.0804607 11.5399947
OS 35.16499698 11.53999216
OS 35.16499952 11.53999978
OS 37.8415804 11.53999978
OS 37.9830838 11.48138674
OE
SE
S P 0
OB 43.2467766 45.28782662 I
OS 43.5750081 45.19987658
OS 43.8889648 45.06983112
OS 44.18321872 44.89994068
OS 44.45280162 44.69308308
OS 44.693078 44.45280924
OS 44.89994068 44.18322126
OS 45.06983112 43.8889648
OS 45.19986896 43.57502842
OS 45.28782408 43.24677914
OS 45.33217502 42.90990402
OS 45.33217756 42.7399958
OS 45.33217502 -2.06000096
OS 45.33217502 -2.22990918
OS 45.28782662 -2.56677922
OS 45.19987658 -2.89501072
OS 45.06983112 -3.20896742
OS 44.89994068 -3.50322134
OS 44.69308308 -3.77280424
OS 44.45280924 -4.01308062
OS 44.18322126 -4.2199433
OS 43.8889648 -4.38983374
OS 43.57502842 -4.51987158
OS 43.24677914 -4.6078267
OS 42.90989132 -4.6521751
OS 42.7399958 -4.65217764
OS -2.06000096 -4.65218272
OS -2.22990918 -4.65218272
OS -2.56678938 -4.60783178
OS -2.89502088 -4.51988428
OS -3.20895472 -4.38984644
OS -3.50322388 -4.21994838
OS -3.77279916 -4.0130984
OS -4.0130984 -3.77279916
OS -4.21994584 -3.50322642
OS -4.38984136 -3.2089598
OS -4.51988174 -2.89502088
OS -4.60782924 -2.56679192
OS -4.65218018 -2.22991172
OS -4.65217764 -2.06000604
OS -4.65218526 42.73999834
OS -4.65218526 42.90990656
OS -4.60783432 43.24678422
OS -4.51988682 43.57501318
OS -4.38984644 43.88895464
OS -4.21995092 44.18321872
OS -4.01310094 44.452794
OS -3.77280932 44.69308562
OS -3.50323404 44.89993814
OS -3.20894964 45.06984128
OS -2.89502342 45.19987658
OS -2.56679192 45.28782408
OS -2.22992188 45.33217248
OS -2.07798416 45.33216486
OS -2.07795622 45.33216994
OS 42.74000088 45.33217502
OS 42.90990656 45.33217502
OS 43.2467766 45.28782662
OE
OB 14.42216826 44.87499788 H
OS 14.11783054 44.87499788
OS 13.8193399 44.81562538
OS 13.53816952 44.69915876
OS 13.28511948 44.53007858
OS 13.06992052 44.31487962
OS 12.90084034 44.06182958
OS 12.8147318 43.85394836
OS 12.677267 43.85394836
OS 12.59115846 44.06182958
OS 12.42207828 44.31487962
OS 12.20687932 44.53007858
OS 11.95382928 44.69915876
OS 11.6726589 44.81562538
OS 11.37416826 44.87499788
OS 11.06983054 44.87499788
OS 10.7713399 44.81562538
OS 10.49016952 44.69915876
OS 10.23711948 44.53007858
OS 10.02192052 44.31487962
OS 9.85284034 44.06182958
OS 9.73637372 43.7806592
OS 9.67700122 43.48216856
OS 9.67700122 43.17783084
OS 9.73637372 42.8793402
OS 9.85284034 42.59816982
OS 10.02192052 42.34511978
OS 10.23711948 42.12992082
OS 10.49016952 41.96084064
OS 10.7713399 41.84437402
OS 11.06983054 41.78500152
OS 11.37416826 41.78500152
OS 11.6726589 41.84437402
OS 11.95382928 41.96084064
OS 12.20687932 42.12992082
OS 12.42207828 42.34511978
OS 12.59115846 42.59816982
OS 12.677267 42.80605104
OS 12.8147318 42.80605104
OS 12.90084034 42.59816982
OS 13.06992052 42.34511978
OS 13.28511948 42.12992082
OS 13.53816952 41.96084064
OS 13.8193399 41.84437402
OS 14.11783054 41.78500152
OS 14.42216826 41.78500152
OS 14.7206589 41.84437402
OS 15.00182928 41.96084064
OS 15.25487932 42.12992082
OS 15.47007828 42.34511978
OS 15.63915846 42.59816982
OS 15.75562508 42.8793402
OS 15.81499758 43.17783084
OS 15.81499758 43.48216856
OS 15.75562508 43.7806592
OS 15.63915846 44.06182958
OS 15.47007828 44.31487962
OS 15.25487932 44.53007858
OS 15.00182928 44.69915876
OS 14.7206589 44.81562538
OS 14.42216826 44.87499788
OE
OB 43.11499886 44.72535632 H
OS 42.80173558 44.68411434
OS 42.509821 44.56320018
OS 42.2591484 44.37085106
OS 42.06679928 44.12017846
OS 41.94588512 43.82826388
OS 41.90464314 43.5150006
OS 41.94588512 43.20173732
OS 42.06679928 42.90982274
OS 42.2591484 42.65915014
OS 42.509821 42.46680102
OS 42.80173558 42.34588686
OS 43.11499886 42.30464488
OS 43.42826214 42.34588686
OS 43.72017672 42.46680102
OS 43.97084932 42.65915014
OS 44.16319844 42.90982274
OS 44.2841126 43.20173732
OS 44.32535458 43.5150006
OS 44.2841126 43.82826388
OS 44.16319844 44.12017846
OS 43.97084932 44.37085106
OS 43.72017672 44.56320018
OS 43.42826214 44.68411434
OS 43.11499886 44.72535632
OE
OB -2.38499904 44.72535632 H
OS -2.69826232 44.68411434
OS -2.9901769 44.56320018
OS -3.2408495 44.37085106
OS -3.43319862 44.12017846
OS -3.55411278 43.82826388
OS -3.59535476 43.5150006
OS -3.55411278 43.20173732
OS -3.43319862 42.90982274
OS -3.2408495 42.65915014
OS -2.9901769 42.46680102
OS -2.69826232 42.34588686
OS -2.38499904 42.30464488
OS -2.07173576 42.34588686
OS -1.77982118 42.46680102
OS -1.52914858 42.65915014
OS -1.33679946 42.90982274
OS -1.2158853 43.20173732
OS -1.17464332 43.5150006
OS -1.2158853 43.82826388
OS -1.33679946 44.12017846
OS -1.52914858 44.37085106
OS -1.77982118 44.56320018
OS -2.07173576 44.68411434
OS -2.38499904 44.72535632
OE
OB 8.3379056 44.57499848 H
OS 8.0100932 44.57499848
OS 7.69344664 44.49015486
OS 7.40955084 44.32624866
OS 7.17775044 44.09444826
OS 7.01384424 43.81055246
OS 6.92900062 43.4939059
OS 6.92900062 43.1660935
OS 7.01384424 42.84944694
OS 7.17775044 42.56555114
OS 7.40955084 42.33375074
OS 7.69344664 42.16984454
OS 8.0100932 42.08500092
OS 8.3379056 42.08500092
OS 8.65455216 42.16984454
OS 8.93844796 42.33375074
OS 9.17024836 42.56555114
OS 9.33415456 42.84944694
OS 9.41899818 43.1660935
OS 9.41899818 43.4939059
OS 9.33415456 43.81055246
OS 9.17024836 44.09444826
OS 8.93844796 44.32624866
OS 8.65455216 44.49015486
OS 8.3379056 44.57499848
OE
OB 5.2899056 44.57499848 H
OS 4.9620932 44.57499848
OS 4.64544664 44.49015486
OS 4.36155084 44.32624866
OS 4.12975044 44.09444826
OS 3.96584424 43.81055246
OS 3.88100062 43.4939059
OS 3.88100062 43.1660935
OS 3.96584424 42.84944694
OS 4.12975044 42.56555114
OS 4.36155084 42.33375074
OS 4.64544664 42.16984454
OS 4.9620932 42.08500092
OS 5.2899056 42.08500092
OS 5.60655216 42.16984454
OS 5.89044796 42.33375074
OS 6.12224836 42.56555114
OS 6.28615456 42.84944694
OS 6.37099818 43.1660935
OS 6.37099818 43.4939059
OS 6.28615456 43.81055246
OS 6.12224836 44.09444826
OS 5.89044796 44.32624866
OS 5.60655216 44.49015486
OS 5.2899056 44.57499848
OE
OB 2.2419056 44.57499848 H
OS 1.9140932 44.57499848
OS 1.59744664 44.49015486
OS 1.31355084 44.32624866
OS 1.08175044 44.09444826
OS 0.91784424 43.81055246
OS 0.83300062 43.4939059
OS 0.83300062 43.1660935
OS 0.91784424 42.84944694
OS 1.08175044 42.56555114
OS 1.31355084 42.33375074
OS 1.59744664 42.16984454
OS 1.9140932 42.08500092
OS 2.2419056 42.08500092
OS 2.55855216 42.16984454
OS 2.84244796 42.33375074
OS 3.07424836 42.56555114
OS 3.23815456 42.84944694
OS 3.32299818 43.1660935
OS 3.32299818 43.4939059
OS 3.23815456 43.81055246
OS 3.07424836 44.09444826
OS 2.84244796 44.32624866
OS 2.55855216 44.49015486
OS 2.2419056 44.57499848
OE
OB 0.17101566 41.93899918 H
OS 0.12699492 41.93899918
OS 0.12699492 40.76701016
OS 1.29899918 40.76701016
OS 1.29899918 40.81101566
OS 1.2104751 41.141396
OS 1.0394569 41.43760318
OS 0.79760318 41.6794569
OS 0.501396 41.8504751
OS 0.17101566 41.93899918
OE
OB -0.12700508 41.93899918 H
OS -0.17101566 41.93899918
OS -0.501396 41.8504751
OS -0.79760318 41.6794569
OS -1.0394569 41.43760318
OS -1.2104751 41.141396
OS -1.29899918 40.81101566
OS -1.29899918 40.76701016
OS -0.12700508 40.76701016
OS -0.12700508 41.93899918
OE
OB 1.29899918 40.51301016 H
OS 0.12699492 40.51301016
OS 0.12699492 39.34100082
OS 0.17101566 39.34100082
OS 0.501396 39.4295249
OS 0.79760318 39.6005431
OS 1.0394569 39.84239682
OS 1.2104751 40.138604
OS 1.29899918 40.46898434
OS 1.29899918 40.51301016
OE
OB -0.12700508 40.51301016 H
OS -1.29899918 40.51301016
OS -1.29899918 40.46898434
OS -1.2104751 40.138604
OS -1.0394569 39.84239682
OS -0.79760318 39.6005431
OS -0.501396 39.4295249
OS -0.17101566 39.34100082
OS -0.12700508 39.34100082
OS -0.12700508 40.51301016
OE
OB 20.46429994 44.98999892 H
OS 20.01570038 44.98999892
OS 19.57262278 44.9198238
OS 19.14597898 44.78119822
OS 18.74627442 44.57753848
OS 18.38334906 44.31385854
OS 18.06614116 43.99665064
OS 17.80246122 43.63372528
OS 17.59880148 43.23402072
OS 17.4601759 42.80737692
OS 17.39000078 42.36429932
OS 17.39000078 41.91569976
OS 17.4601759 41.47262216
OS 17.59880148 41.04597836
OS 17.80246122 40.6462738
OS 18.06614116 40.28334844
OS 18.38334906 39.96614054
OS 18.74627442 39.7024606
OS 19.14597898 39.49880086
OS 19.57262278 39.36017528
OS 20.01570038 39.29000016
OS 20.46429994 39.29000016
OS 20.90737754 39.36017528
OS 21.33402134 39.49880086
OS 21.7337259 39.7024606
OS 22.09665126 39.96614054
OS 22.41385916 40.28334844
OS 22.6775391 40.6462738
OS 22.88119884 41.04597836
OS 23.01982442 41.47262216
OS 23.08999954 41.91569976
OS 23.08999954 42.36429932
OS 23.01982442 42.80737692
OS 22.88119884 43.23402072
OS 22.6775391 43.63372528
OS 22.41385916 43.99665064
OS 22.09665126 44.31385854
OS 21.7337259 44.57753848
OS 21.33402134 44.78119822
OS 20.90737754 44.9198238
OS 20.46429994 44.98999892
OE
OB 4.65971382 41.89999748 H
OS 4.14028382 41.89999748
OS 3.627247 41.81874034
OS 3.13323986 41.65822758
OS 2.67042392 41.4224089
OS 2.25019362 41.11709582
OS 1.882902 40.7498042
OS 1.57758892 40.3295739
OS 1.34177024 39.86675796
OS 1.18125748 39.37275082
OS 1.10000034 38.859714
OS 1.10000034 38.340284
OS 1.18125748 37.82724718
OS 1.34177024 37.33324004
OS 1.57758892 36.8704241
OS 1.882902 36.4501938
OS 2.25019362 36.08290218
OS 2.67042392 35.7775891
OS 3.13323986 35.54177042
OS 3.627247 35.38125766
OS 4.14028382 35.30000052
OS 4.65971382 35.30000052
OS 5.17275064 35.38125766
OS 5.66675778 35.54177042
OS 6.12957372 35.7775891
OS 6.54980402 36.08290218
OS 6.91709564 36.4501938
OS 7.22240872 36.8704241
OS 7.4582274 37.33324004
OS 7.61874016 37.82724718
OS 7.6999973 38.340284
OS 7.6999973 38.859714
OS 7.61874016 39.37275082
OS 7.4582274 39.86675796
OS 7.22240872 40.3295739
OS 6.91709564 40.7498042
OS 6.54980402 41.11709582
OS 6.12957372 41.4224089
OS 5.66675778 41.65822758
OS 5.17275064 41.81874034
OS 4.65971382 41.89999748
OE
OB 36.45971626 43.39999956 H
OS 35.94028626 43.39999956
OS 35.42724944 43.31874242
OS 34.9332423 43.15822966
OS 34.47042636 42.92241098
OS 34.05019606 42.6170979
OS 33.68290444 42.24980628
OS 33.37759136 41.82957598
OS 33.14177268 41.36676004
OS 32.98125992 40.8727529
OS 32.90000278 40.35971608
OS 32.90000278 39.84028608
OS 32.98125992 39.32724926
OS 33.14177268 38.83324212
OS 33.37759136 38.37042618
OS 33.68290444 37.95019588
OS 34.05019606 37.58290426
OS 34.47042636 37.27759118
OS 34.9332423 37.0417725
OS 35.42724944 36.88125974
OS 35.94028626 36.8000026
OS 36.45971626 36.8000026
OS 36.97275308 36.88125974
OS 37.46676022 37.0417725
OS 37.92957616 37.27759118
OS 38.34980646 37.58290426
OS 38.71709808 37.95019588
OS 39.02241116 38.37042618
OS 39.25822984 38.83324212
OS 39.4187426 39.32724926
OS 39.4445871 39.49042394
OS 39.56537172 39.52966948
OS 39.65512008 39.43992112
OS 39.90817012 39.27084094
OS 40.03589402 39.21793528
OS 40.03589402 36.88210302
OS 40.04142614 36.8542951
OS 40.00680848 36.50281498
OS 39.8961737 36.138104
OS 39.71651442 35.80198326
OS 39.49245594 35.52896882
OS 39.46888474 35.51321828
OS 38.31930106 34.3636346
OS 38.03431306 34.43999716
OS 37.66568794 34.43999716
OS 37.30962312 34.34458968
OS 36.99038322 34.16027712
OS 36.72972334 33.89961724
OS 36.54541078 33.58037734
OS 36.4500033 33.22431252
OS 36.4500033 32.8556874
OS 36.54541078 32.49962258
OS 36.72972334 32.18038268
OS 36.99038322 31.9197228
OS 37.30962312 31.73541024
OS 37.66568794 31.64000276
OS 38.03431306 31.64000276
OS 38.39037788 31.73541024
OS 38.70961778 31.9197228
OS 38.97027766 32.18038268
OS 39.15459022 32.49962258
OS 39.2499977 32.8556874
OS 39.2499977 33.22431252
OS 39.17363514 33.50930052
OS 40.32321882 34.6588842
OS 40.33227392 34.67243764
OS 40.6420828 35.0351725
OS 40.89970738 35.4555806
OS 41.08839636 35.91111436
OS 41.203499 36.39055714
OS 41.24092844 36.86612896
OS 41.24410598 36.88210302
OS 41.24410598 39.21793528
OS 41.37182988 39.27084094
OS 41.62487992 39.43992112
OS 41.84007888 39.65512008
OS 42.00915906 39.90817012
OS 42.12562568 40.1893405
OS 42.18499818 40.48783114
OS 42.18499818 40.79216886
OS 42.12562568 41.0906595
OS 42.00915906 41.37182988
OS 41.84007888 41.62487992
OS 41.62487992 41.84007888
OS 41.37182988 42.00915906
OS 41.0906595 42.12562568
OS 40.79216886 42.18499818
OS 40.48783114 42.18499818
OS 40.1893405 42.12562568
OS 39.90817012 42.00915906
OS 39.65512008 41.84007888
OS 39.43992112 41.62487992
OS 39.3430887 41.47995768
OS 39.196137 41.48862416
OS 39.02241116 41.82957598
OS 38.71709808 42.24980628
OS 38.34980646 42.6170979
OS 37.92957616 42.92241098
OS 37.46676022 43.15822966
OS 36.97275308 43.31874242
OS 36.45971626 43.39999956
OE
OB 4.9748186 34.13999776 H
OS 4.6851824 34.13999776
OS 4.40541664 34.06503474
OS 4.15458656 33.92021664
OS 3.94978382 33.7154139
OS 3.80496572 33.46458382
OS 3.7300027 33.18481806
OS 3.7300027 32.89518186
OS 3.80496572 32.6154161
OS 3.94978382 32.36458602
OS 4.15458656 32.15978328
OS 4.40541664 32.01496518
OS 4.6851824 31.94000216
OS 4.9748186 31.94000216
OS 5.25458436 32.01496518
OS 5.50541444 32.15978328
OS 5.71021718 32.36458602
OS 5.85503528 32.6154161
OS 5.9299983 32.89518186
OS 5.9299983 33.18481806
OS 5.85503528 33.46458382
OS 5.71021718 33.7154139
OS 5.50541444 33.92021664
OS 5.25458436 34.06503474
OS 4.9748186 34.13999776
OE
OB 38.03431306 24.27999716 H
OS 37.66568794 24.27999716
OS 37.30962312 24.18458968
OS 36.99038322 24.00027712
OS 36.72972334 23.73961724
OS 36.54541078 23.42037734
OS 36.4500033 23.06431252
OS 36.4500033 22.6956874
OS 36.54541078 22.33962258
OS 36.72972334 22.02038268
OS 36.99038322 21.7597228
OS 37.30962312 21.57541024
OS 37.66568794 21.48000276
OS 38.03431306 21.48000276
OS 38.39037788 21.57541024
OS 38.70961778 21.7597228
OS 38.97027766 22.02038268
OS 39.15459022 22.33962258
OS 39.2499977 22.6956874
OS 39.2499977 23.06431252
OS 39.15459022 23.42037734
OS 38.97027766 23.73961724
OS 38.70961778 24.00027712
OS 38.39037788 24.18458968
OS 38.03431306 24.27999716
OE
OB 40.85101558 21.63899914 H
OS 40.80699484 21.63899914
OS 40.80699484 20.46699996
OS 41.9789991 20.46699996
OS 41.9789991 20.51101562
OS 41.89047502 20.84139596
OS 41.71945682 21.13760314
OS 41.4776031 21.37945686
OS 41.18139592 21.55047506
OS 40.85101558 21.63899914
OE
OB 40.55299484 21.63899914 H
OS 40.50898426 21.63899914
OS 40.17860392 21.55047506
OS 39.88239674 21.37945686
OS 39.64054302 21.13760314
OS 39.46952482 20.84139596
OS 39.38100074 20.51101562
OS 39.38100074 20.46699996
OS 40.55299484 20.46699996
OS 40.55299484 21.63899914
OE
OB 14.62499996 24.75391798 H
OS 14.62497456 24.7539129
OS 14.52601362 24.7539129
OS 14.50632354 24.74999622
OS 14.48623214 24.74999622
OS 14.29206946 24.71137298
OS 14.2735173 24.70368948
OS 14.25381706 24.69977026
OS 14.07091674 24.62401222
OS 14.05421624 24.612854
OS 14.03566154 24.60516796
OS 13.87105684 24.49518342
OS 13.85685824 24.48098482
OS 13.8401552 24.46982406
OS 13.70017072 24.32983958
OS 13.68900996 24.31313654
OS 13.67481136 24.29893794
OS 13.56482682 24.13433324
OS 13.55714078 24.11577854
OS 13.54598256 24.09907804
OS 13.47022452 23.91618026
OS 13.4663053 23.89648002
OS 13.4586218 23.87792786
OS 13.4200011 23.68376264
OS 13.4200011 23.6636814
OS 13.41608188 23.64398116
OS 13.41608188 20.6850742
OS 13.41118476 20.635341
OS 13.36959988 20.53494496
OS 13.3000496 20.46539722
OS 13.1996561 20.42381234
OS 13.1499737 20.4189203
OS 12.98999942 20.4189203
OS 12.98997402 20.41891522
OS 12.92733762 20.41891776
OS 12.84931136 20.40339836
OS 12.84930374 20.40339328
OS 12.73353562 20.35544062
OS 12.733528 20.35543808
OS 12.66736862 20.31123192
OS 12.66736354 20.3112243
OS 12.57876326 20.22262656
OS 12.5345571 20.15646718
OS 12.53455456 20.15645956
OS 12.48659682 20.04068382
OS 12.47107742 19.96265756
OS 12.47107996 19.89999068
OS 12.47107996 19.00001534
OS 12.47107742 18.97116348
OS 12.48659174 18.89313722
OS 12.48659682 18.8931296
OS 12.50867196 18.83982516
OS 12.55287558 18.77366832
OS 12.59366544 18.73287846
OS 12.65982228 18.68867484
OS 12.71313434 18.66659462
OS 12.7911606 18.6510803
OS 12.82001246 18.65108284
OS 13.2688584 18.65108284
OS 13.36600324 18.57899764
OS 13.36600324 18.14201096
OS 13.90500648 18.14201096
OS 13.90500648 18.01501096
OS 14.03200648 18.01501096
OS 14.03200648 17.45100142
OS 14.44399956 17.45100142
OS 14.44399956 17.50500182
OS 15.24030988 17.50500182
OS 15.33718294 17.50499928
OS 15.42496534 17.47037908
OS 15.451074 17.42661488
OS 15.45107654 17.4266098
OS 15.45107908 17.40540588
OS 15.45108162 17.35499196
OS 15.45108162 15.7062678
OS 15.44885658 15.6836745
OS 15.4279854 15.63328852
OS 15.39671292 15.60201604
OS 15.3463244 15.58114486
OS 15.3237438 15.57891982
OS -1.134999 15.57891982
OS -1.1350625 15.57890712
OS -1.38517122 15.57890966
OS -1.40487146 15.57499044
OS -1.42495524 15.57499044
OS -1.91567562 15.47738078
OS -1.93422524 15.46969728
OS -1.95393056 15.46577806
OS -2.41618008 15.27430778
OS -2.43288312 15.26314702
OS -2.45143528 15.25546352
OS -2.86744918 14.97749354
OS -2.88164778 14.96329494
OS -2.89835082 14.95213418
OS -3.25214234 14.59834266
OS -3.2633031 14.58163962
OS -3.2775017 14.56744102
OS -3.55547168 14.15142966
OS -3.56316026 14.13287242
OS -3.57431594 14.11617446
OS -3.76578622 13.65392494
OS -3.76970544 13.63421962
OS -3.77738894 13.61567
OS -3.8749986 13.12494962
OS -3.8749986 13.10486838
OS -3.87891782 13.08516814
OS -3.87891782 12.835001
OS -3.87891782 -2.0249896
OS -3.8789229 -2.14810594
OS -3.87500622 -2.16780364
OS -3.87500622 -2.1878925
OS -3.82697482 -2.42939062
OS -3.81928624 -2.4479504
OS -3.81536956 -2.46764556
OS -3.72114572 -2.69513304
OS -3.70999004 -2.711831
OS -3.70230146 -2.73039078
OS -3.56550468 -2.93512494
OS -3.55130354 -2.94932608
OS -3.54014532 -2.96602658
OS -3.36603594 -3.1401385
OS -3.34933544 -3.15129926
OS -3.33513176 -3.1655004
OS -3.1303976 -3.30229718
OS -3.11184036 -3.30998322
OS -3.0951424 -3.32114144
OS -2.86765492 -3.41536782
OS -2.8479623 -3.4192845
OS -2.82939998 -3.42697308
OS -2.58790186 -3.47500702
OS -2.56781554 -3.47500702
OS -2.54811784 -3.4789237
OS -2.4250015 -3.47892116
OS 15.39999968 -3.47891862
OS 15.51474164 -3.47891862
OS 15.53444188 -3.4749994
OS 15.55452312 -3.4749994
OS 15.7795976 -3.43022936
OS 15.79814468 -3.42254586
OS 15.81785508 -3.41862664
OS 16.02986888 -3.33080614
OS 16.04657192 -3.31964538
OS 16.06512154 -3.31196188
OS 16.25593142 -3.18446912
OS 16.27013002 -3.17027306
OS 16.2868356 -3.15910976
OS 16.44910858 -2.99683678
OS 16.46027188 -2.9801312
OS 16.47446794 -2.9659326
OS 16.6019607 -2.77512272
OS 16.6096442 -2.75657056
OS 16.62080496 -2.73987006
OS 16.70862546 -2.52785372
OS 16.71254468 -2.50815348
OS 16.72022818 -2.48960132
OS 16.76500076 -2.26452684
OS 16.76500076 -2.24444306
OS 16.76891998 -2.22474282
OS 16.76891998 -2.10999832
OS 16.76891998 13.62999306
OS 16.76977596 13.63867986
OS 16.78000708 13.66337882
OS 16.7916225 13.67499424
OS 16.816324 13.68522536
OS 16.83498284 13.68706432
OS 16.84476946 13.69003358
OS 16.85499042 13.69004374
OS 16.85500312 13.69004628
OS 16.86680142 13.69494848
OS 16.87948364 13.69654614
OS 16.88584888 13.7001758
OS 16.89302946 13.70160328
OS 16.89842696 13.70521008
OS 16.90471346 13.70687632
OS 17.01837846 13.76255312
OS 17.04501798 13.78288074
OS 17.07286908 13.80149132
OS 17.0778805 13.8065002
OS 17.07986678 13.80947454
OS 17.08163208 13.81082074
OS 17.08739026 13.82073436
OS 17.12208412 13.87265704
OS 17.14339726 13.92411236
OS 17.1433998 13.92412252
OS 17.14340488 13.92413014
OS 17.1517183 13.9659487
OS 17.1589192 14.00214878
OS 17.15891666 14.0021564
OS 17.1589192 14.00216656
OS 17.15891666 14.03001512
OS 17.15891666 14.22600152
OS 17.44800168 14.22600152
OS 17.44800168 14.7900009
OS 17.44800168 15.35400028
OS 17.13545976 15.35400028
OS 17.09928 15.3674826
OS 17.01976022 15.42934684
OS 17.01892202 15.48013922
OS 17.01892202 15.63661592
OS 17.11709556 15.71718726
OS 17.1650025 15.70765718
OS 17.3113192 15.7367605
OS 17.4353601 15.81964324
OS 17.51824284 15.94368414
OS 17.54734616 16.09000084
OS 17.54734616 16.85250122
OS 17.51824284 16.99881792
OS 17.51499926 17.00367186
OS 17.51499926 17.7150014
OS 17.82642104 17.7150014
OS 17.8686841 17.68676168
OS 18.0150008 17.65765836
OS 18.48761352 17.65765836
OS 19.11108192 17.03418996
OS 19.11108192 14.35630098
OS 19.11107938 14.35628828
OS 19.12660386 14.27825186
OS 19.17080748 14.21209502
OS 19.1708151 14.21208994
OS 19.63708798 13.74581452
OS 19.63709306 13.7458069
OS 19.7032499 13.70160328
OS 19.78128632 13.68608134
OS 21.91500062 13.68608134
OS 21.99303704 13.70160328
OS 22.05919388 13.7458069
OS 22.1033975 13.81196374
OS 22.11891944 13.89000016
OS 24.58408342 13.89000016
OS 24.71108088 13.76299762
OS 24.71108088 13.76002074
OS 24.70739026 13.72254558
OS 24.67513226 13.64467172
OS 24.6228235 13.59236296
OS 24.54495472 13.56011004
OS 24.50749226 13.55641942
OS 23.87500178 13.55641942
OS 23.87497638 13.55641434
OS 23.81333312 13.55641688
OS 23.73530686 13.54089748
OS 23.73529924 13.5408924
OS 23.62137008 13.49370174
OS 23.62136246 13.4936992
OS 23.55520816 13.44949558
OS 23.46800234 13.3622923
OS 23.42379872 13.29613546
OS 23.42379618 13.29612784
OS 23.37660044 13.18219106
OS 23.36108104 13.1041648
OS 23.36108358 13.04249106
OS 23.36108358 12.8540002
OS 23.08200362 12.8540002
OS 23.08200362 12.29001606
OS 23.08200362 11.72600144
OS 23.36108358 11.72600144
OS 23.36108358 4.17500054
OS 23.36108358 4.06912064
OS 23.36500026 4.04943056
OS 23.36500026 4.02933916
OS 23.40631336 3.82165098
OS 23.41399686 3.80310136
OS 23.41791608 3.78339604
OS 23.49895224 3.58775762
OS 23.51011046 3.57105712
OS 23.5177965 3.55250242
OS 23.63544168 3.3764347
OS 23.6496479 3.36222848
OS 23.66080358 3.34553306
OS 23.81053658 3.19579752
OS 23.82723962 3.18463676
OS 23.84143822 3.17043816
OS 24.01750594 3.05279298
OS 24.03606318 3.04510694
OS 24.05276114 3.03394872
OS 24.24839956 2.95291256
OS 24.26810488 2.94899334
OS 24.2866545 2.94130984
OS 24.49434268 2.89999928
OS 24.51442138 2.89999928
OS 24.53412416 2.89608006
OS 34.07497376 2.89608006
OS 34.15526316 2.89607498
OS 34.17895628 2.90078668
OS 34.20309898 2.90176204
OS 34.35919722 2.93942008
OS 34.38112758 2.94955976
OS 34.40436604 2.95617138
OS 34.5472766 3.02939958
OS 34.56621992 3.04440336
OS 34.5872562 3.0562804
OS 34.7089984 3.16098682
OS 34.71555668 3.16936628
OS 34.7603318 3.19801494
OS 34.85855614 3.20597276
OS 34.90396118 3.16056518
OS 34.92066676 3.14940188
OS 34.93486536 3.13520582
OS 35.07408276 3.04218594
OS 35.09263746 3.0344999
OS 35.10933288 3.02334422
OS 35.26402142 2.95926764
OS 35.28371912 2.95534842
OS 35.30227636 2.94766238
OS 35.46649752 2.91499798
OS 35.4865813 2.91499798
OS 35.50628408 2.91107876
OS 35.59000248 2.9110813
OS 41.86632978 2.9110813
OS 41.88602494 2.91499798
OS 41.90611126 2.91499798
OS 42.05583918 2.94477948
OS 42.07439896 2.95246806
OS 42.09409158 2.95638474
OS 42.2351327 3.01480474
OS 42.2518332 3.02596296
OS 42.27039298 3.03365154
OS 42.3973244 3.11846468
OS 42.41152808 3.13266836
OS 42.4282235 3.14382404
OS 42.5361735 3.2517715
OS 42.54733426 3.26847454
OS 42.56153286 3.28267314
OS 42.64634854 3.4096071
OS 42.65403458 3.4281618
OS 42.6651928 3.4448623
OS 42.7236128 3.58590596
OS 42.72752948 3.60560112
OS 42.73521552 3.62415582
OS 42.76499956 3.77388374
OS 42.76499956 3.79396752
OS 42.76891878 3.81366776
OS 42.76891878 7.41499152
OS 42.7689137 7.41501692
OS 42.7689137 7.41506518
OS 42.7679993 7.41966004
OS 42.76870542 7.424293
OS 42.76339682 7.54147844
OS 42.75495894 7.57572272
OS 42.74808316 7.61028704
OS 42.67346812 7.79042384
OS 42.6292645 7.85658068
OS 42.62925688 7.85658576
OS 42.48158128 8.0042639
OS 42.41542444 8.04846752
OS 42.2224581 8.12839624
OS 42.14442676 8.14391564
OS 42.03999212 8.1439131
OS 40.65400048 8.14391564
OS 40.65400048 8.4330032
OS 40.09001634 8.4330032
OS 40.09001634 8.5600032
OS 39.96301634 8.5600032
OS 39.96301634 9.11399752
OS 39.52600426 9.11399752
OS 39.52600426 9.11400006
OS 39.41626356 9.15567384
OS 39.37580644 9.19613096
OS 39.3096496 9.24033458
OS 39.28872508 9.24900106
OS 39.31398538 9.37600106
OS 39.32399806 9.37600106
OS 39.32399806 9.81300044
OS 38.76999866 9.81300044
OS 38.76999866 9.94000044
OS 38.64299866 9.94000044
OS 38.64299866 10.50399982
OS 38.35391872 10.50399982
OS 38.35391872 11.23158028
OS 38.33839678 11.3096167
OS 38.27978374 11.4511201
OS 38.24699996 11.50018782
OS 38.2670304 11.63468082
OS 38.26771112 11.63721828
OS 38.2954276 11.64464524
OS 38.5585716 11.7965728
OS 38.77342766 12.01142886
OS 38.92535522 12.27457286
OS 39.0039987 12.5680724
OS 39.0039987 12.5929898
OS 37.84999034 12.5929898
OS 36.6960023 12.5929898
OS 36.6960023 12.5680724
OS 36.77464578 12.27457286
OS 36.92657334 12.01142886
OS 37.0670836 11.8709186
OS 37.01447766 11.7439186
OS 35.16499952 11.7439186
OS 35.16496142 11.74391098
OS 35.08046578 11.74391352
OS 35.04591416 11.73704282
OS 34.92099442 11.81245034
OS 34.91891162 11.81459918
OS 34.91891416 22.01000678
OS 34.91890908 22.01003218
OS 34.91891162 22.26017646
OS 34.9149924 22.2798767
OS 34.9149924 22.29996048
OS 34.81738274 22.79068086
OS 34.80969924 22.80923048
OS 34.80578002 22.8289358
OS 34.61430974 23.29118532
OS 34.60315152 23.30788582
OS 34.59546548 23.32644052
OS 34.31749296 23.74245442
OS 34.30328928 23.7566581
OS 34.2921336 23.77335352
OS 33.93834462 24.12714504
OS 33.9216365 24.13830834
OS 33.90744044 24.1525044
OS 33.491424 24.43047438
OS 33.47287184 24.43815788
OS 33.45617134 24.44931864
OS 32.99392182 24.64078638
OS 32.9742165 24.6447056
OS 32.95566688 24.6523891
OS 32.4649465 24.74999622
OS 32.44486526 24.74999622
OS 32.42516248 24.75391544
OS 32.17499534 24.7539129
OS 14.62499996 24.75391798
OE
OB 41.9789991 20.21299996 H
OS 40.80699484 20.21299996
OS 40.80699484 19.04100078
OS 40.85101558 19.04100078
OS 41.18139592 19.12952486
OS 41.4776031 19.30054306
OS 41.71945682 19.54239678
OS 41.89047502 19.83860396
OS 41.9789991 20.1689843
OS 41.9789991 20.21299996
OE
OB 40.55299484 20.21299996 H
OS 39.38100074 20.21299996
OS 39.38100074 20.1689843
OS 39.46952482 19.83860396
OS 39.64054302 19.54239678
OS 39.88239674 19.30054306
OS 40.17860392 19.12952486
OS 40.50898426 19.04100078
OS 40.55299484 19.04100078
OS 40.55299484 20.21299996
OE
OB 13.77800648 17.88801096 H
OS 13.36600324 17.88801096
OS 13.36600324 17.45100142
OS 13.77800648 17.45100142
OS 13.77800648 17.88801096
OE
OB 4.9748186 18.89999776 H
OS 4.6851824 18.89999776
OS 4.40541664 18.82503474
OS 4.15458656 18.68021664
OS 3.94978382 18.4754139
OS 3.80496572 18.22458382
OS 3.7300027 17.94481806
OS 3.7300027 17.65518186
OS 3.80496572 17.3754161
OS 3.94978382 17.12458602
OS 4.15458656 16.91978328
OS 4.40541664 16.77496518
OS 4.6851824 16.70000216
OS 4.9748186 16.70000216
OS 5.25458436 16.77496518
OS 5.50541444 16.91978328
OS 5.71021718 17.12458602
OS 5.85503528 17.3754161
OS 5.9299983 17.65518186
OS 5.9299983 17.94481806
OS 5.85503528 18.22458382
OS 5.71021718 18.4754139
OS 5.50541444 18.68021664
OS 5.25458436 18.82503474
OS 4.9748186 18.89999776
OE
OB 18.12900108 15.35400028 H
OS 17.70200168 15.35400028
OS 17.70200168 14.9170009
OS 18.12900108 14.9170009
OS 18.12900108 15.35400028
OE
OB 38.03431306 19.19999716 H
OS 37.66568794 19.19999716
OS 37.30962312 19.10458968
OS 36.99038322 18.92027712
OS 36.72972334 18.65961724
OS 36.54541078 18.34037734
OS 36.4500033 17.98431252
OS 36.4500033 17.6156874
OS 36.54541078 17.25962258
OS 36.72972334 16.94038268
OS 36.99038322 16.6797228
OS 37.30962312 16.49541024
OS 37.66568794 16.40000276
OS 38.03431306 16.40000276
OS 38.39037788 16.49541024
OS 38.55501306 16.59046212
OS 38.66500014 16.52696212
OS 38.66500014 14.91500192
OS 39.01099894 14.91500192
OS 39.01099894 14.64200018
OS 40.56899938 14.64200018
OS 40.56899938 14.91500192
OS 40.91499818 14.91500192
OS 40.91499818 17.01499772
OS 40.40175308 17.01499772
OS 40.40175308 17.36499956
OS 40.39339902 17.40699338
OS 40.36335844 17.63518952
OS 40.25906858 17.88696448
OS 40.09316848 18.10316928
OS 39.87696368 18.26906938
OS 39.62518872 18.37335924
OS 39.39699258 18.40339982
OS 39.35499876 18.41175388
OS 39.11338126 18.41175388
OS 38.97027766 18.65961724
OS 38.70961778 18.92027712
OS 38.39037788 19.10458968
OS 38.03431306 19.19999716
OE
OB 18.12900108 14.6630009 H
OS 17.70200168 14.6630009
OS 17.70200168 14.22600152
OS 18.12900108 14.22600152
OS 18.12900108 14.6630009
OE
OB 40.56899938 14.38800018 H
OS 39.91699916 14.38800018
OS 39.91699916 13.81100108
OS 40.56899938 13.81100108
OS 40.56899938 14.38800018
OE
OB 39.66299916 14.38800018 H
OS 39.01099894 14.38800018
OS 39.01099894 13.81100108
OS 39.66299916 13.81100108
OS 39.66299916 14.38800018
OE
OB 38.00192806 13.87399816 H
OS 37.97699034 13.87399816
OS 37.97699034 12.8469898
OS 39.0039987 12.8469898
OS 39.0039987 12.87192752
OS 38.92535522 13.16542706
OS 38.77342766 13.42857106
OS 38.5585716 13.64342712
OS 38.2954276 13.79535468
OS 38.00192806 13.87399816
OE
OB 37.72299034 13.87399816 H
OS 37.69807294 13.87399816
OS 37.4045734 13.79535468
OS 37.1414294 13.64342712
OS 36.92657334 13.42857106
OS 36.77464578 13.16542706
OS 36.6960023 12.87192752
OS 36.6960023 12.8469898
OS 37.72299034 12.8469898
OS 37.72299034 13.87399816
OE
OB 22.82800362 12.8540002 H
OS 22.40100422 12.8540002
OS 22.40100422 12.41701606
OS 22.82800362 12.41701606
OS 22.82800362 12.8540002
OE
OB 22.82800362 12.16301606 H
OS 22.40100422 12.16301606
OS 22.40100422 11.72600144
OS 22.82800362 11.72600144
OS 22.82800362 12.16301606
OE
OB 39.32399806 10.50399982 H
OS 38.89699866 10.50399982
OS 38.89699866 10.06700044
OS 39.32399806 10.06700044
OS 39.32399806 10.50399982
OE
OB 40.65400048 9.11399752 H
OS 40.21701634 9.11399752
OS 40.21701634 8.6870032
OS 40.65400048 8.6870032
OS 40.65400048 9.11399752
OE
OB 40.8039062 1.24499878 H
OS 40.4760938 1.24499878
OS 40.15944724 1.16015516
OS 39.87555144 0.99624896
OS 39.64375104 0.76444856
OS 39.47984484 0.48055276
OS 39.39500122 0.1639062
OS 39.39500122 -0.1639062
OS 39.47984484 -0.48055276
OS 39.64375104 -0.76444856
OS 39.87555144 -0.99624896
OS 40.15944724 -1.16015516
OS 40.4760938 -1.24499878
OS 40.8039062 -1.24499878
OS 41.12055276 -1.16015516
OS 41.40444856 -0.99624896
OS 41.63624896 -0.76444856
OS 41.80015516 -0.48055276
OS 41.88499878 -0.1639062
OS 41.88499878 0.1639062
OS 41.80015516 0.48055276
OS 41.63624896 0.76444856
OS 41.40444856 0.99624896
OS 41.12055276 1.16015516
OS 40.8039062 1.24499878
OE
OB 43.18999998 -1.59964374 H
OS 42.8767367 -1.64088572
OS 42.58482212 -1.76179988
OS 42.33414952 -1.954149
OS 42.1418004 -2.2048216
OS 42.02088624 -2.49673618
OS 41.97964426 -2.80999946
OS 42.02088624 -3.12326274
OS 42.1418004 -3.41517732
OS 42.33414952 -3.66584992
OS 42.58482212 -3.85819904
OS 42.8767367 -3.9791132
OS 43.18999998 -4.02035518
OS 43.50326326 -3.9791132
OS 43.79517784 -3.85819904
OS 44.04585044 -3.66584992
OS 44.23819956 -3.41517732
OS 44.35911372 -3.12326274
OS 44.4003557 -2.80999946
OS 44.35911372 -2.49673618
OS 44.23819956 -2.2048216
OS 44.04585044 -1.954149
OS 43.79517784 -1.76179988
OS 43.50326326 -1.64088572
OS 43.18999998 -1.59964374
OE
OB 20.66429954 1.58999936 H
OS 20.21569998 1.58999936
OS 19.77262238 1.51982424
OS 19.34597858 1.38119866
OS 18.94627402 1.17753892
OS 18.58334866 0.91385898
OS 18.26614076 0.59665108
OS 18.00246082 0.23372572
OS 17.79880108 -0.16597884
OS 17.6601755 -0.59262264
OS 17.59000038 -1.03570024
OS 17.59000038 -1.4842998
OS 17.6601755 -1.9273774
OS 17.79880108 -2.3540212
OS 18.00246082 -2.75372576
OS 18.26614076 -3.11665112
OS 18.58334866 -3.43385902
OS 18.94627402 -3.69753896
OS 19.34597858 -3.9011987
OS 19.77262238 -4.03982428
OS 20.21569998 -4.1099994
OS 20.66429954 -4.1099994
OS 21.10737714 -4.03982428
OS 21.53402094 -3.9011987
OS 21.9337255 -3.69753896
OS 22.29665086 -3.43385902
OS 22.61385876 -3.11665112
OS 22.8775387 -2.75372576
OS 23.08119844 -2.3540212
OS 23.21982402 -1.9273774
OS 23.28999914 -1.4842998
OS 23.28999914 -1.03570024
OS 23.21982402 -0.59262264
OS 23.08119844 -0.16597884
OS 22.8775387 0.23372572
OS 22.61385876 0.59665108
OS 22.29665086 0.91385898
OS 21.9337255 1.17753892
OS 21.53402094 1.38119866
OS 21.10737714 1.51982424
OS 20.66429954 1.58999936
OE
OB 35.75971512 2.29999794 H
OS 35.24028512 2.29999794
OS 34.7272483 2.2187408
OS 34.23324116 2.05822804
OS 33.77042522 1.82240936
OS 33.35019492 1.51709628
OS 32.9829033 1.14980466
OS 32.67759022 0.72957436
OS 32.44177154 0.26675842
OS 32.28125878 -0.22724872
OS 32.20000164 -0.74028554
OS 32.20000164 -1.25971554
OS 32.28125878 -1.77275236
OS 32.44177154 -2.2667595
OS 32.67759022 -2.72957544
OS 32.9829033 -3.14980574
OS 33.35019492 -3.51709736
OS 33.77042522 -3.82241044
OS 34.23324116 -4.05822912
OS 34.7272483 -4.21874188
OS 35.24028512 -4.29999902
OS 35.75971512 -4.29999902
OS 36.27275194 -4.21874188
OS 36.76675908 -4.05822912
OS 37.22957502 -3.82241044
OS 37.64980532 -3.51709736
OS 38.01709694 -3.14980574
OS 38.32241002 -2.72957544
OS 38.5582287 -2.2667595
OS 38.71874146 -1.77275236
OS 38.7999986 -1.25971554
OS 38.7999986 -0.74028554
OS 38.71874146 -0.22724872
OS 38.5582287 0.26675842
OS 38.32241002 0.72957436
OS 38.01709694 1.14980466
OS 37.64980532 1.51709628
OS 37.22957502 1.82240936
OS 36.76675908 2.05822804
OS 36.27275194 2.2187408
OS 35.75971512 2.29999794
OE
OB 24.0646585 23.8176562 I
OS 24.07713244 23.81517462
OS 24.0771426 23.81517462
OS 24.0771553 23.81516954
OS 24.20613904 23.78951554
OS 24.33473924 23.7362492
OS 24.4504845 23.65890874
OS 24.54891458 23.56047866
OS 24.62624996 23.44473594
OS 24.6795163 23.31613828
OS 24.70765696 23.17466028
OS 24.7110758 23.10501602
OS 24.71107834 19.69000126
OS 22.11891944 19.69000126
OS 22.11891944 20.19000026
OS 22.1033975 20.26803668
OS 22.05919388 20.33419352
OS 21.99303704 20.37839714
OS 21.91500062 20.39391908
OS 19.54783492 20.39392162
OS 19.54783492 20.66500058
OS 19.63999882 20.66500058
OS 19.63999882 21.68499854
OS 17.72000266 21.68499854
OS 17.72000266 21.47736624
OS 17.55649778 21.47112546
OS 17.46499682 21.55919996
OS 17.46499682 21.65999732
OS 17.2608748 21.65999732
OS 17.2608748 21.88000196
OS 17.38499698 21.88000196
OS 17.38499698 22.70000032
OS 16.7789987 22.70000032
OS 16.7789987 22.75400072
OS 16.42200424 22.75400072
OS 16.42200424 22.29001638
OS 16.42200424 21.82600156
OS 16.64912088 21.82600156
OS 16.64912088 21.65999732
OS 16.44499886 21.65999732
OS 16.44499886 21.39556046
OS 16.32899706 21.36900222
OS 16.32899706 21.36899968
OS 15.99201018 21.36899968
OS 15.99201018 20.89498996
OS 15.73801018 20.89498996
OS 15.73801018 21.36899968
OS 15.40100552 21.36899968
OS 15.40100044 21.36900476
OS 15.40100044 21.36900222
OS 15.27891788 21.38087418
OS 15.27891788 23.53997324
OS 15.28409694 23.59257664
OS 15.32792464 23.69838542
OS 15.40161258 23.77207082
OS 15.5074239 23.81590106
OS 15.56000698 23.82108012
OS 23.99488978 23.82108012
OS 24.0646585 23.8176562
OE
OB 16.16800424 22.75400072 H
OS 15.81099962 22.75400072
OS 15.81099962 22.41701638
OS 16.16800424 22.41701638
OS 16.16800424 22.75400072
OE
OB 16.16800424 22.16301638 H
OS 15.81099962 22.16301638
OS 15.81099962 21.82600156
OS 16.16800424 21.82600156
OS 16.16800424 22.16301638
OE
SE
S P 0
OB -1.8920841 -38.48662356 I
OS -1.88561218 -38.48662356
OS -1.87914026 -38.48754812
OS -1.86342274 -38.4903218
OS -1.84678066 -38.4949446
OS -1.82921402 -38.50234108
OS -1.81164738 -38.51158668
OS -1.79685442 -38.52453052
OS -1.7950053 -38.52637964
OS -1.79130706 -38.531927
OS -1.78483514 -38.54024804
OS -1.78206146 -38.54671996
OS -1.77836322 -38.55319188
OS -1.77466498 -38.56151292
OS -1.7718913 -38.56983396
OS -1.76819306 -38.57907956
OS -1.76541938 -38.59017428
OS -1.76357026 -38.601269
OS -1.76172114 -38.61421284
OS -1.75987202 -38.62715668
OS -1.75987202 -38.64194964
OS -1.75987202 -38.95999828
OS -1.83845962 -38.95999828
OS -1.83845962 -38.66876188
OS -1.83845962 -38.66783732
OS -1.83845962 -38.66691276
OS -1.83845962 -38.6613654
OS -1.83845962 -38.65304436
OS -1.83938418 -38.6428742
OS -1.84030874 -38.63177948
OS -1.8412333 -38.62068476
OS -1.84308242 -38.60959004
OS -1.8458561 -38.601269
OS -1.8458561 -38.60034444
OS -1.84770522 -38.59757076
OS -1.84955434 -38.59387252
OS -1.85232802 -38.58924972
OS -1.85602626 -38.58370236
OS -1.86064906 -38.578155
OS -1.86619642 -38.57260764
OS -1.8735929 -38.56706028
OS -1.87451746 -38.56613572
OS -1.87729114 -38.56521116
OS -1.88098938 -38.56336204
OS -1.8874613 -38.56058836
OS -1.89393322 -38.55781468
OS -1.90225426 -38.55596556
OS -1.9105753 -38.555041
OS -1.92074546 -38.55411644
OS -1.92536826 -38.55411644
OS -1.9290665 -38.555041
OS -1.9383121 -38.55596556
OS -1.94940682 -38.55781468
OS -1.96235066 -38.56243748
OS -1.97621906 -38.56798484
OS -1.99008746 -38.57630588
OS -2.0030313 -38.5874006
OS -2.00395586 -38.58924972
OS -2.0076541 -38.59387252
OS -2.01320146 -38.601269
OS -2.01874882 -38.61236372
OS -2.02522074 -38.62715668
OS -2.02984354 -38.64472332
OS -2.03354178 -38.6659882
OS -2.0353909 -38.69095132
OS -2.0353909 -38.95999828
OS -2.1139785 -38.95999828
OS -2.1139785 -38.65951628
OS -2.1139785 -38.65859172
OS -2.1139785 -38.6567426
OS -2.1139785 -38.65489348
OS -2.1139785 -38.65119524
OS -2.11490306 -38.64102508
OS -2.11675218 -38.62993036
OS -2.1186013 -38.61698652
OS -2.12229954 -38.60404268
OS -2.12692234 -38.5920234
OS -2.13339426 -38.58092868
OS -2.13431882 -38.58000412
OS -2.1370925 -38.57630588
OS -2.1417153 -38.57260764
OS -2.14818722 -38.56706028
OS -2.15650826 -38.56243748
OS -2.16760298 -38.55781468
OS -2.18054682 -38.555041
OS -2.19626434 -38.55411644
OS -2.2018117 -38.55411644
OS -2.20828362 -38.555041
OS -2.2156801 -38.55596556
OS -2.2249257 -38.55873924
OS -2.23602042 -38.56151292
OS -2.24619058 -38.56613572
OS -2.2572853 -38.57168308
OS -2.25820986 -38.57260764
OS -2.2619081 -38.57538132
OS -2.2665309 -38.57907956
OS -2.27300282 -38.58462692
OS -2.27947474 -38.5920234
OS -2.28594666 -38.601269
OS -2.29241858 -38.61143916
OS -2.29796594 -38.62345844
OS -2.2988905 -38.62530756
OS -2.29981506 -38.62993036
OS -2.30166418 -38.63732684
OS -2.30443786 -38.647497
OS -2.30721154 -38.6613654
OS -2.30906066 -38.67800748
OS -2.30998522 -38.69742324
OS -2.31090978 -38.71961268
OS -2.31090978 -38.95999828
OS -2.38949738 -38.95999828
OS -2.38949738 -38.49586916
OS -2.31923082 -38.49586916
OS -2.31923082 -38.56243748
OS -2.31830626 -38.56058836
OS -2.31553258 -38.55689012
OS -2.30998522 -38.5504182
OS -2.3035133 -38.54302172
OS -2.29519226 -38.53377612
OS -2.2850221 -38.52453052
OS -2.27392738 -38.51528492
OS -2.26098354 -38.50696388
OS -2.25913442 -38.50603932
OS -2.25451162 -38.50326564
OS -2.24711514 -38.50049196
OS -2.23694498 -38.49586916
OS -2.2249257 -38.49217092
OS -2.2110573 -38.48939724
OS -2.19533978 -38.48662356
OS -2.1786977 -38.485699
OS -2.17037666 -38.485699
OS -2.1602065 -38.48662356
OS -2.14911178 -38.48847268
OS -2.13524338 -38.49124636
OS -2.12137498 -38.4949446
OS -2.10750658 -38.50049196
OS -2.09456274 -38.50788844
OS -2.09271362 -38.508813
OS -2.08901538 -38.51158668
OS -2.08346802 -38.51620948
OS -2.07607154 -38.52360596
OS -2.06867506 -38.531927
OS -2.06035402 -38.54209716
OS -2.05295754 -38.55411644
OS -2.04741018 -38.56798484
OS -2.04648562 -38.56706028
OS -2.0446365 -38.5642866
OS -2.04186282 -38.56058836
OS -2.03724002 -38.555041
OS -2.03169266 -38.54856908
OS -2.02522074 -38.54209716
OS -2.01782426 -38.53470068
OS -2.00857866 -38.52637964
OS -1.9984085 -38.51898316
OS -1.98823834 -38.51158668
OS -1.97621906 -38.50511476
OS -1.96327522 -38.49864284
OS -1.94940682 -38.49309548
OS -1.93461386 -38.48939724
OS -1.9198209 -38.48662356
OS -1.90317882 -38.485699
OS -1.8967069 -38.485699
OS -1.8920841 -38.48662356
OE
OB -1.19589042 -39.1375138 I
OS -1.7164177 -39.1375138
OS -1.7164177 -39.08111564
OS -1.19589042 -39.08111564
OS -1.19589042 -39.1375138
OE
OB -2.6825829 -38.48662356 I
OS -2.67426186 -38.48754812
OS -2.66501626 -38.48939724
OS -2.6548461 -38.49124636
OS -2.64282682 -38.49309548
OS -2.6178637 -38.50141652
OS -2.60491986 -38.50603932
OS -2.59197602 -38.51251124
OS -2.57903218 -38.51898316
OS -2.56608834 -38.52822876
OS -2.55406906 -38.53747436
OS -2.54204978 -38.54856908
OS -2.54112522 -38.54949364
OS -2.5392761 -38.55134276
OS -2.53650242 -38.555041
OS -2.53280418 -38.5596638
OS -2.52818138 -38.56613572
OS -2.52263402 -38.57445676
OS -2.51708666 -38.58370236
OS -2.5115393 -38.59387252
OS -2.50599194 -38.60496724
OS -2.50044458 -38.61883564
OS -2.49489722 -38.63270404
OS -2.49027442 -38.64842156
OS -2.48657618 -38.66506364
OS -2.4838025 -38.68263028
OS -2.48195338 -38.70112148
OS -2.48102882 -38.7214618
OS -2.48102882 -38.72238636
OS -2.48102882 -38.72516004
OS -2.48102882 -38.72978284
OS -2.48102882 -38.73625476
OS -2.48195338 -38.74365124
OS -2.48287794 -38.75289684
OS -2.48287794 -38.76214244
OS -2.48472706 -38.7723126
OS -2.48750074 -38.7954266
OS -2.4930481 -38.8185406
OS -2.49952002 -38.8416546
OS -2.50876562 -38.86291948
OS -2.50876562 -38.86384404
OS -2.50969018 -38.8647686
OS -2.5115393 -38.86754228
OS -2.51338842 -38.87124052
OS -2.51986034 -38.88048612
OS -2.52818138 -38.89158084
OS -2.5392761 -38.90452468
OS -2.5531445 -38.91746852
OS -2.56886202 -38.93041236
OS -2.58735322 -38.94243164
OS -2.58827778 -38.94243164
OS -2.58920234 -38.9433562
OS -2.59197602 -38.94520532
OS -2.59659882 -38.94705444
OS -2.60122162 -38.94890356
OS -2.60676898 -38.95075268
OS -2.62063738 -38.95630004
OS -2.6363549 -38.96092284
OS -2.65577066 -38.96554564
OS -2.67611098 -38.96924388
OS -2.69830042 -38.97016844
OS -2.70754602 -38.97016844
OS -2.7149425 -38.96924388
OS -2.72326354 -38.96831932
OS -2.73250914 -38.9664702
OS -2.74360386 -38.96462108
OS -2.75469858 -38.96277196
OS -2.7796617 -38.95537548
OS -2.7935301 -38.94982812
OS -2.80647394 -38.94428076
OS -2.81941778 -38.93688428
OS -2.83236162 -38.92856324
OS -2.8443809 -38.91931764
OS -2.85640018 -38.90822292
OS -2.85732474 -38.90729836
OS -2.85917386 -38.90544924
OS -2.86194754 -38.901751
OS -2.86564578 -38.89620364
OS -2.87026858 -38.88973172
OS -2.87489138 -38.88233524
OS -2.88043874 -38.87308964
OS -2.8859861 -38.86199492
OS -2.89153346 -38.84997564
OS -2.89708082 -38.83610724
OS -2.90170362 -38.82131428
OS -2.90632642 -38.80559676
OS -2.91002466 -38.78803012
OS -2.91279834 -38.76953892
OS -2.91464746 -38.7491986
OS -2.91557202 -38.72793372
OS -2.91557202 -38.7260846
OS -2.91557202 -38.72238636
OS -2.91464746 -38.71591444
OS -2.91464746 -38.70666884
OS -2.9137229 -38.69649868
OS -2.91187378 -38.68355484
OS -2.91002466 -38.670611
OS -2.90632642 -38.65581804
OS -2.90262818 -38.64102508
OS -2.89800538 -38.62530756
OS -2.89245802 -38.60866548
OS -2.88506154 -38.59294796
OS -2.87766506 -38.578155
OS -2.8674949 -38.56336204
OS -2.85732474 -38.54949364
OS -2.8443809 -38.53747436
OS -2.84345634 -38.5365498
OS -2.84160722 -38.53562524
OS -2.83790898 -38.53285156
OS -2.83328618 -38.52915332
OS -2.82773882 -38.52545508
OS -2.82034234 -38.52083228
OS -2.81294586 -38.51620948
OS -2.80370026 -38.51158668
OS -2.7935301 -38.50696388
OS -2.78243538 -38.50234108
OS -2.75747226 -38.49402004
OS -2.7288109 -38.48754812
OS -2.71401794 -38.48662356
OS -2.69830042 -38.485699
OS -2.68905482 -38.485699
OS -2.6825829 -38.48662356
OE
OB -3.29186794 -38.49586916 I
OS -3.21235578 -38.49586916
OS -3.21235578 -38.55689012
OS -3.29186794 -38.55689012
OS -3.29186794 -38.82963532
OS -3.29186794 -38.83148444
OS -3.29186794 -38.83518268
OS -3.29186794 -38.84073004
OS -3.29094338 -38.84720196
OS -3.29001882 -38.86199492
OS -3.28909426 -38.86846684
OS -3.2881697 -38.87308964
OS -3.28724514 -38.87493876
OS -3.28447146 -38.878637
OS -3.28077322 -38.8832598
OS -3.2743013 -38.8878826
OS -3.27245218 -38.88880716
OS -3.26782938 -38.89065628
OS -3.25950834 -38.8925054
OS -3.24748906 -38.89342996
OS -3.23824346 -38.89342996
OS -3.23362066 -38.8925054
OS -3.22714874 -38.8925054
OS -3.21975226 -38.89158084
OS -3.21235578 -38.89065628
OS -3.20218562 -38.95999828
OS -3.20403474 -38.95999828
OS -3.20773298 -38.96092284
OS -3.2142049 -38.9618474
OS -3.22252594 -38.96277196
OS -3.23177154 -38.96462108
OS -3.2419417 -38.96554564
OS -3.26228202 -38.9664702
OS -3.2696785 -38.9664702
OS -3.27707498 -38.96554564
OS -3.28632058 -38.96462108
OS -3.2974153 -38.96369652
OS -3.30851002 -38.96092284
OS -3.31868018 -38.95814916
OS -3.32885034 -38.95352636
OS -3.3297749 -38.9526018
OS -3.33254858 -38.95075268
OS -3.33624682 -38.947979
OS -3.34179418 -38.9433562
OS -3.34641698 -38.9387334
OS -3.35196434 -38.93226148
OS -3.3575117 -38.92578956
OS -3.36120994 -38.91746852
OS -3.36120994 -38.91654396
OS -3.36305906 -38.91284572
OS -3.36398362 -38.9063738
OS -3.36583274 -38.8971282
OS -3.36768186 -38.88510892
OS -3.36860642 -38.87771244
OS -3.36860642 -38.8693914
OS -3.36953098 -38.85922124
OS -3.37045554 -38.84905108
OS -3.37045554 -38.83795636
OS -3.37045554 -38.82501252
OS -3.37045554 -38.55689012
OS -3.42870282 -38.55689012
OS -3.42870282 -38.49586916
OS -3.37045554 -38.49586916
OS -3.37045554 -38.38122372
OS -3.29186794 -38.33407116
OS -3.29186794 -38.49586916
OE
OB -3.0431613 -38.49586916 I
OS -2.96364914 -38.49586916
OS -2.96364914 -38.55689012
OS -3.0431613 -38.55689012
OS -3.0431613 -38.82963532
OS -3.0431613 -38.83148444
OS -3.0431613 -38.83518268
OS -3.0431613 -38.84073004
OS -3.04223674 -38.84720196
OS -3.04131218 -38.86199492
OS -3.04038762 -38.86846684
OS -3.03946306 -38.87308964
OS -3.0385385 -38.87493876
OS -3.03576482 -38.878637
OS -3.03206658 -38.8832598
OS -3.02559466 -38.8878826
OS -3.02374554 -38.88880716
OS -3.01912274 -38.89065628
OS -3.0108017 -38.8925054
OS -2.99878242 -38.89342996
OS -2.98953682 -38.89342996
OS -2.98491402 -38.8925054
OS -2.9784421 -38.8925054
OS -2.97104562 -38.89158084
OS -2.96364914 -38.89065628
OS -2.95347898 -38.95999828
OS -2.9553281 -38.95999828
OS -2.95902634 -38.96092284
OS -2.96549826 -38.9618474
OS -2.9738193 -38.96277196
OS -2.9830649 -38.96462108
OS -2.99323506 -38.96554564
OS -3.01357538 -38.9664702
OS -3.02097186 -38.9664702
OS -3.02836834 -38.96554564
OS -3.03761394 -38.96462108
OS -3.04870866 -38.96369652
OS -3.05980338 -38.96092284
OS -3.06997354 -38.95814916
OS -3.0801437 -38.95352636
OS -3.08106826 -38.9526018
OS -3.08384194 -38.95075268
OS -3.08754018 -38.947979
OS -3.09308754 -38.9433562
OS -3.09771034 -38.9387334
OS -3.1032577 -38.93226148
OS -3.10880506 -38.92578956
OS -3.1125033 -38.91746852
OS -3.1125033 -38.91654396
OS -3.11435242 -38.91284572
OS -3.11527698 -38.9063738
OS -3.1171261 -38.8971282
OS -3.11897522 -38.88510892
OS -3.11989978 -38.87771244
OS -3.11989978 -38.8693914
OS -3.12082434 -38.85922124
OS -3.1217489 -38.84905108
OS -3.1217489 -38.83795636
OS -3.1217489 -38.82501252
OS -3.1217489 -38.55689012
OS -3.17999618 -38.55689012
OS -3.17999618 -38.49586916
OS -3.1217489 -38.49586916
OS -3.1217489 -38.38122372
OS -3.0431613 -38.33407116
OS -3.0431613 -38.49586916
OE
OB -0.73083674 -38.48662356 I
OS -0.71696834 -38.48754812
OS -0.70125082 -38.48939724
OS -0.6855333 -38.49217092
OS -0.66981578 -38.49586916
OS -0.65502282 -38.50049196
OS -0.6531737 -38.50141652
OS -0.6485509 -38.50326564
OS -0.64207898 -38.50603932
OS -0.63375794 -38.50973756
OS -0.62451234 -38.51528492
OS -0.61526674 -38.52083228
OS -0.6069457 -38.52822876
OS -0.59954922 -38.53562524
OS -0.59862466 -38.5365498
OS -0.59677554 -38.53932348
OS -0.59400186 -38.54394628
OS -0.59030362 -38.54949364
OS -0.58568082 -38.55781468
OS -0.58198258 -38.56613572
OS -0.57828434 -38.57630588
OS -0.57551066 -38.58832516
OS -0.57551066 -38.58924972
OS -0.5745861 -38.5920234
OS -0.57366154 -38.59757076
OS -0.57273698 -38.60496724
OS -0.57273698 -38.6151374
OS -0.57181242 -38.62715668
OS -0.57088786 -38.6428742
OS -0.57088786 -38.66044084
OS -0.57088786 -38.76584068
OS -0.57088786 -38.76676524
OS -0.57088786 -38.77046348
OS -0.57088786 -38.77601084
OS -0.57088786 -38.78340732
OS -0.57088786 -38.79172836
OS -0.57088786 -38.80189852
OS -0.5699633 -38.82408796
OS -0.5699633 -38.84720196
OS -0.56903874 -38.87031596
OS -0.56811418 -38.88048612
OS -0.56811418 -38.88973172
OS -0.56718962 -38.89805276
OS -0.56626506 -38.90452468
OS -0.56626506 -38.90544924
OS -0.5653405 -38.90914748
OS -0.56441594 -38.91469484
OS -0.56164226 -38.92209132
OS -0.55979314 -38.93041236
OS -0.5560949 -38.93965796
OS -0.5514721 -38.94982812
OS -0.5468493 -38.95999828
OS -0.62913514 -38.95999828
OS -0.6300597 -38.95907372
OS -0.63098426 -38.95537548
OS -0.63283338 -38.95075268
OS -0.63560706 -38.9433562
OS -0.63838074 -38.93503516
OS -0.64022986 -38.924865
OS -0.64207898 -38.91377028
OS -0.6439281 -38.901751
OS -0.64485266 -38.901751
OS -0.64577722 -38.90360012
OS -0.65132458 -38.90822292
OS -0.65964562 -38.91469484
OS -0.67074034 -38.92301588
OS -0.68460874 -38.93133692
OS -0.69847714 -38.94058252
OS -0.7132701 -38.94890356
OS -0.72898762 -38.95537548
OS -0.73083674 -38.95630004
OS -0.7363841 -38.9572246
OS -0.74470514 -38.95999828
OS -0.7548753 -38.96277196
OS -0.76781914 -38.96554564
OS -0.7826121 -38.96739476
OS -0.79925418 -38.96924388
OS -0.81589626 -38.97016844
OS -0.82329274 -38.97016844
OS -0.8288401 -38.96924388
OS -0.83531202 -38.96924388
OS -0.8427085 -38.96831932
OS -0.85935058 -38.96554564
OS -0.87784178 -38.96092284
OS -0.8981821 -38.95445092
OS -0.9166733 -38.94520532
OS -0.93331538 -38.93318604
OS -0.9351645 -38.93133692
OS -0.9397873 -38.92671412
OS -0.94625922 -38.91839308
OS -0.9536557 -38.90729836
OS -0.96105218 -38.89342996
OS -0.9675241 -38.87771244
OS -0.9721469 -38.85829668
OS -0.97307146 -38.84905108
OS -0.97399602 -38.83795636
OS -0.97399602 -38.83610724
OS -0.97399602 -38.832409
OS -0.97307146 -38.82593708
OS -0.9721469 -38.81761604
OS -0.97029778 -38.80744588
OS -0.9675241 -38.79727572
OS -0.96382586 -38.786181
OS -0.95920306 -38.77601084
OS -0.9582785 -38.77508628
OS -0.95642938 -38.77138804
OS -0.95273114 -38.76584068
OS -0.94810834 -38.75936876
OS -0.94256098 -38.75197228
OS -0.9351645 -38.7445758
OS -0.92776802 -38.73717932
OS -0.91852242 -38.7307074
OS -0.91759786 -38.72978284
OS -0.91389962 -38.72793372
OS -0.90927682 -38.72423548
OS -0.90188034 -38.72053724
OS -0.8935593 -38.716839
OS -0.88338914 -38.7122162
OS -0.87321898 -38.70851796
OS -0.8611997 -38.70481972
OS -0.86027514 -38.70481972
OS -0.8565769 -38.70389516
OS -0.85102954 -38.70204604
OS -0.84363306 -38.70112148
OS -0.83438746 -38.69927236
OS -0.82236818 -38.69742324
OS -0.80849978 -38.69464956
OS -0.7918577 -38.69280044
OS -0.79093314 -38.69280044
OS -0.7872349 -38.69187588
OS -0.7826121 -38.69187588
OS -0.77614018 -38.69095132
OS -0.7687437 -38.69002676
OS -0.7594981 -38.68817764
OS -0.74932794 -38.68725308
OS -0.73823322 -38.68540396
OS -0.71604378 -38.68078116
OS -0.69200522 -38.67615836
OS -0.67074034 -38.670611
OS -0.66057018 -38.66783732
OS -0.65132458 -38.66506364
OS -0.65132458 -38.66413908
OS -0.65132458 -38.66228996
OS -0.65040002 -38.6567426
OS -0.65040002 -38.65027068
OS -0.65040002 -38.64657244
OS -0.65040002 -38.64472332
OS -0.65040002 -38.64379876
OS -0.65040002 -38.6428742
OS -0.65040002 -38.63732684
OS -0.65132458 -38.62808124
OS -0.6531737 -38.61791108
OS -0.65594738 -38.60681636
OS -0.66057018 -38.59572164
OS -0.66611754 -38.58555148
OS -0.67351402 -38.57723044
OS -0.67443858 -38.57630588
OS -0.67906138 -38.57260764
OS -0.68645786 -38.5689094
OS -0.69570346 -38.56336204
OS -0.7086473 -38.55873924
OS -0.72344026 -38.55411644
OS -0.74193146 -38.55134276
OS -0.76319634 -38.5504182
OS -0.77244194 -38.5504182
OS -0.78168754 -38.55134276
OS -0.79463138 -38.55319188
OS -0.80757522 -38.555041
OS -0.82144362 -38.55873924
OS -0.83438746 -38.56336204
OS -0.84548218 -38.56983396
OS -0.84640674 -38.57075852
OS -0.85010498 -38.5735322
OS -0.85472778 -38.578155
OS -0.86027514 -38.58555148
OS -0.8658225 -38.59479708
OS -0.87229442 -38.60681636
OS -0.87784178 -38.62160932
OS -0.88338914 -38.6382514
OS -0.96012762 -38.62808124
OS -0.96012762 -38.62715668
OS -0.95920306 -38.62623212
OS -0.95920306 -38.62345844
OS -0.9582785 -38.6197602
OS -0.95550482 -38.61143916
OS -0.95180658 -38.59941988
OS -0.94718378 -38.5874006
OS -0.94163642 -38.57445676
OS -0.93423994 -38.56151292
OS -0.9259189 -38.54949364
OS -0.92499434 -38.54856908
OS -0.9212961 -38.54487084
OS -0.91574874 -38.53932348
OS -0.90835226 -38.531927
OS -0.8981821 -38.52453052
OS -0.88616282 -38.51713404
OS -0.87229442 -38.508813
OS -0.8565769 -38.50234108
OS -0.85565234 -38.50234108
OS -0.85472778 -38.50141652
OS -0.8519541 -38.50049196
OS -0.84825586 -38.4995674
OS -0.83901026 -38.49679372
OS -0.82606642 -38.49402004
OS -0.81127346 -38.49124636
OS -0.79278226 -38.48847268
OS -0.7733665 -38.48662356
OS -0.75117706 -38.485699
OS -0.7410069 -38.485699
OS -0.73083674 -38.48662356
OE
OB 0.68004182 -38.48662356 I
OS 0.69021198 -38.48847268
OS 0.70223126 -38.49217092
OS 0.7151751 -38.49679372
OS 0.72996806 -38.50326564
OS 0.74568558 -38.51158668
OS 0.71702422 -38.58370236
OS 0.71609966 -38.5827778
OS 0.71240142 -38.58092868
OS 0.70685406 -38.578155
OS 0.69945758 -38.57538132
OS 0.69113654 -38.57260764
OS 0.68096638 -38.56983396
OS 0.67079622 -38.56798484
OS 0.66062606 -38.56706028
OS 0.65600326 -38.56706028
OS 0.65138046 -38.56798484
OS 0.64490854 -38.5689094
OS 0.63843662 -38.57075852
OS 0.63011558 -38.5735322
OS 0.62179454 -38.57723044
OS 0.61439806 -38.5827778
OS 0.6134735 -38.58370236
OS 0.61069982 -38.58555148
OS 0.60792614 -38.58924972
OS 0.60330334 -38.59387252
OS 0.59868054 -38.60034444
OS 0.59405774 -38.60774092
OS 0.58943494 -38.61606196
OS 0.5857367 -38.62623212
OS 0.58481214 -38.62808124
OS 0.58388758 -38.6336286
OS 0.58203846 -38.64194964
OS 0.57926478 -38.65304436
OS 0.5764911 -38.66691276
OS 0.57464198 -38.68263028
OS 0.57371742 -38.69927236
OS 0.57279286 -38.71776356
OS 0.57279286 -38.95999828
OS 0.49420526 -38.95999828
OS 0.49420526 -38.49586916
OS 0.56539638 -38.49586916
OS 0.56539638 -38.56613572
OS 0.56632094 -38.56521116
OS 0.57001918 -38.55873924
OS 0.57464198 -38.5504182
OS 0.58203846 -38.54024804
OS 0.58943494 -38.53007788
OS 0.59775598 -38.51898316
OS 0.60607702 -38.50973756
OS 0.61439806 -38.50234108
OS 0.61532262 -38.50141652
OS 0.6180963 -38.4995674
OS 0.62364366 -38.49679372
OS 0.62919102 -38.49402004
OS 0.6365875 -38.49124636
OS 0.6458331 -38.48847268
OS 0.6550787 -38.48662356
OS 0.66524886 -38.485699
OS 0.67172078 -38.485699
OS 0.68004182 -38.48662356
OE
OB 0.8631047 -38.42745172 I
OS 0.84183982 -38.54671996
OS 0.79283814 -38.54671996
OS 0.77342238 -38.42745172
OS 0.77342238 -38.32020276
OS 0.8631047 -38.32020276
OS 0.8631047 -38.42745172
OE
OB 0.20296886 -38.48662356 I
OS 0.21036534 -38.48754812
OS 0.21961094 -38.48939724
OS 0.2297811 -38.49124636
OS 0.24180038 -38.49402004
OS 0.2528951 -38.49679372
OS 0.26583894 -38.50141652
OS 0.27785822 -38.50603932
OS 0.29080206 -38.51251124
OS 0.3037459 -38.51990772
OS 0.31668974 -38.52822876
OS 0.32870902 -38.53839892
OS 0.33980374 -38.54949364
OS 0.3407283 -38.5504182
OS 0.34257742 -38.55226732
OS 0.3453511 -38.55596556
OS 0.34904934 -38.56151292
OS 0.35367214 -38.56798484
OS 0.35829494 -38.57538132
OS 0.3638423 -38.58462692
OS 0.36938966 -38.59572164
OS 0.37493702 -38.60774092
OS 0.38048438 -38.62068476
OS 0.38510718 -38.63547772
OS 0.38972998 -38.65119524
OS 0.39342822 -38.66876188
OS 0.3962019 -38.68725308
OS 0.39805102 -38.70666884
OS 0.39897558 -38.72793372
OS 0.39897558 -38.72885828
OS 0.39897558 -38.73255652
OS 0.39897558 -38.73902844
OS 0.39805102 -38.74827404
OS 0.05134102 -38.74827404
OS 0.05134102 -38.7491986
OS 0.05134102 -38.75197228
OS 0.05226558 -38.75567052
OS 0.05226558 -38.76121788
OS 0.05319014 -38.7676898
OS 0.05503926 -38.77508628
OS 0.05781294 -38.79172836
OS 0.0633603 -38.81021956
OS 0.07075678 -38.83055988
OS 0.08092694 -38.84905108
OS 0.09387078 -38.86569316
OS 0.09479534 -38.86569316
OS 0.0957199 -38.86754228
OS 0.10126726 -38.87216508
OS 0.1095883 -38.878637
OS 0.12068302 -38.88510892
OS 0.13547598 -38.8925054
OS 0.15211806 -38.89897732
OS 0.17060926 -38.90360012
OS 0.18077942 -38.90452468
OS 0.19187414 -38.90544924
OS 0.19927062 -38.90544924
OS 0.20759166 -38.90452468
OS 0.21776182 -38.90267556
OS 0.22885654 -38.89990188
OS 0.24180038 -38.89620364
OS 0.25381966 -38.89065628
OS 0.26583894 -38.8832598
OS 0.2667635 -38.88233524
OS 0.2713863 -38.878637
OS 0.27693366 -38.87308964
OS 0.28340558 -38.86569316
OS 0.29080206 -38.855523
OS 0.2991231 -38.84257916
OS 0.30744414 -38.8277862
OS 0.31484062 -38.81021956
OS 0.3962019 -38.82038972
OS 0.3962019 -38.82131428
OS 0.39527734 -38.8231634
OS 0.39435278 -38.82686164
OS 0.39250366 -38.832409
OS 0.38972998 -38.83795636
OS 0.3869563 -38.84535284
OS 0.37955982 -38.86107036
OS 0.37031422 -38.878637
OS 0.35737038 -38.8971282
OS 0.34257742 -38.91469484
OS 0.32408622 -38.93133692
OS 0.32316166 -38.93133692
OS 0.32131254 -38.93318604
OS 0.31853886 -38.93503516
OS 0.31484062 -38.93780884
OS 0.30929326 -38.94058252
OS 0.3037459 -38.9433562
OS 0.29634942 -38.94705444
OS 0.28802838 -38.95075268
OS 0.27878278 -38.95445092
OS 0.26953718 -38.95814916
OS 0.24642318 -38.96369652
OS 0.2205355 -38.96831932
OS 0.19187414 -38.97016844
OS 0.18170398 -38.97016844
OS 0.17523206 -38.96924388
OS 0.16691102 -38.96831932
OS 0.15674086 -38.9664702
OS 0.14564614 -38.96462108
OS 0.13362686 -38.96277196
OS 0.10773918 -38.95537548
OS 0.09387078 -38.94982812
OS 0.08092694 -38.94428076
OS 0.06705854 -38.93688428
OS 0.0541147 -38.92856324
OS 0.04209542 -38.91931764
OS 0.03007614 -38.90822292
OS 0.02915158 -38.90729836
OS 0.02730246 -38.90544924
OS 0.02452878 -38.901751
OS 0.02083054 -38.89620364
OS 0.01620774 -38.88973172
OS 0.01158494 -38.88233524
OS 0.00603758 -38.87308964
OS 0.00049022 -38.86291948
OS -0.00505714 -38.8509002
OS -0.0106045 -38.83795636
OS -0.0152273 -38.8231634
OS -0.0198501 -38.80744588
OS -0.02354834 -38.7908038
OS -0.02632202 -38.7723126
OS -0.02817114 -38.75289684
OS -0.0290957 -38.73255652
OS -0.0290957 -38.73163196
OS -0.0290957 -38.72700916
OS -0.0290957 -38.7214618
OS -0.02817114 -38.71314076
OS -0.02724658 -38.7029706
OS -0.02632202 -38.69187588
OS -0.0244729 -38.67893204
OS -0.02169922 -38.6659882
OS -0.01430274 -38.63640228
OS -0.00967994 -38.62160932
OS -0.00413258 -38.6058918
OS 0.0032639 -38.59109884
OS 0.01158494 -38.57723044
OS 0.02083054 -38.56336204
OS 0.0310007 -38.5504182
OS 0.03192526 -38.54949364
OS 0.03377438 -38.54764452
OS 0.03747262 -38.54487084
OS 0.04209542 -38.54024804
OS 0.04764278 -38.53562524
OS 0.05503926 -38.53007788
OS 0.0633603 -38.52360596
OS 0.07353046 -38.5180586
OS 0.08370062 -38.51158668
OS 0.0957199 -38.50603932
OS 0.10866374 -38.50049196
OS 0.12253214 -38.49586916
OS 0.1373251 -38.49124636
OS 0.15304262 -38.48847268
OS 0.1696847 -38.48662356
OS 0.18725134 -38.485699
OS 0.19649694 -38.485699
OS 0.20296886 -38.48662356
OE
OB -1.0692257 -38.95999828 I
OS -1.1478133 -38.95999828
OS -1.1478133 -38.32020276
OS -1.0692257 -38.32020276
OS -1.0692257 -38.95999828
OE
OB -0.2463673 -38.96739476 I
OS -0.2463673 -38.96831932
OS -0.24729186 -38.971093
OS -0.24914098 -38.97479124
OS -0.2509901 -38.97941404
OS -0.25376378 -38.98588596
OS -0.25653746 -38.99328244
OS -0.26300938 -39.00899996
OS -0.2694813 -39.0265666
OS -0.27687778 -39.04413324
OS -0.28427426 -39.05985076
OS -0.2879725 -39.06632268
OS -0.29074618 -39.0727946
OS -0.29167074 -39.07464372
OS -0.29444442 -39.07926652
OS -0.29906722 -39.08573844
OS -0.30461458 -39.09405948
OS -0.31201106 -39.10330508
OS -0.3203321 -39.11255068
OS -0.32865314 -39.12179628
OS -0.3388233 -39.12919276
OS -0.33974786 -39.13011732
OS -0.3434461 -39.13196644
OS -0.34899346 -39.13474012
OS -0.3573145 -39.13843836
OS -0.3665601 -39.1421366
OS -0.37765482 -39.14491028
OS -0.3896741 -39.1467594
OS -0.4035425 -39.14768396
OS -0.40724074 -39.14768396
OS -0.41186354 -39.1467594
OS -0.41833546 -39.1467594
OS -0.42573194 -39.14491028
OS -0.43405298 -39.14306116
OS -0.44329858 -39.14121204
OS -0.45346874 -39.1375138
OS -0.46178978 -39.06447356
OS -0.46086522 -39.06447356
OS -0.45716698 -39.06539812
OS -0.45254418 -39.06632268
OS -0.44699682 -39.0681718
OS -0.43220386 -39.07094548
OS -0.4174109 -39.07187004
OS -0.4127881 -39.07187004
OS -0.4081653 -39.07094548
OS -0.40261794 -39.07094548
OS -0.38874954 -39.0681718
OS -0.38227762 -39.06539812
OS -0.3758057 -39.06262444
OS -0.37488114 -39.06262444
OS -0.37303202 -39.06077532
OS -0.37025834 -39.0589262
OS -0.3665601 -39.05615252
OS -0.35823906 -39.04875604
OS -0.35084258 -39.03858588
OS -0.35084258 -39.03766132
OS -0.34899346 -39.0358122
OS -0.34714434 -39.03211396
OS -0.34529522 -39.0265666
OS -0.34159698 -39.01917012
OS -0.33789874 -39.0080754
OS -0.33235138 -38.99513156
OS -0.32680402 -38.97941404
OS -0.32680402 -38.97848948
OS -0.3249549 -38.97479124
OS -0.32310578 -38.96831932
OS -0.31940754 -38.95999828
OS -0.49507394 -38.49586916
OS -0.41186354 -38.49586916
OS -0.31478474 -38.76491612
OS -0.31478474 -38.76584068
OS -0.31386018 -38.76676524
OS -0.31293562 -38.76953892
OS -0.31201106 -38.77416172
OS -0.31016194 -38.77878452
OS -0.30831282 -38.78433188
OS -0.30369002 -38.79727572
OS -0.29814266 -38.81299324
OS -0.2925953 -38.83148444
OS -0.28704794 -38.8509002
OS -0.28150058 -38.87216508
OS -0.28150058 -38.87124052
OS -0.28057602 -38.8693914
OS -0.27965146 -38.86661772
OS -0.2787269 -38.86291948
OS -0.27780234 -38.85829668
OS -0.27595322 -38.85274932
OS -0.27225498 -38.83888092
OS -0.26763218 -38.8231634
OS -0.26116026 -38.8046722
OS -0.2556129 -38.786181
OS -0.24821642 -38.76676524
OS -0.14836394 -38.49586916
OS -0.06977634 -38.49586916
OS -0.2463673 -38.96739476
OE
OB -5.4655085 -38.31835364 I
OS -5.45348922 -38.32020276
OS -5.43962082 -38.32297644
OS -5.42482786 -38.32667468
OS -5.40911034 -38.33129748
OS -5.39431738 -38.33869396
OS -5.39339282 -38.33869396
OS -5.39246826 -38.33961852
OS -5.38784546 -38.3423922
OS -5.38044898 -38.347015
OS -5.37120338 -38.35348692
OS -5.36103322 -38.36273252
OS -5.3499385 -38.37290268
OS -5.33976834 -38.38492196
OS -5.32959818 -38.39879036
OS -5.32867362 -38.40063948
OS -5.32497538 -38.40526228
OS -5.32127714 -38.41358332
OS -5.31480522 -38.4256026
OS -5.30925786 -38.439471
OS -5.30186138 -38.45518852
OS -5.29538946 -38.47367972
OS -5.2898421 -38.49402004
OS -5.2898421 -38.4949446
OS -5.28891754 -38.49679372
OS -5.28799298 -38.4995674
OS -5.28706842 -38.5041902
OS -5.28614386 -38.50973756
OS -5.2852193 -38.51620948
OS -5.28337018 -38.52453052
OS -5.28244562 -38.53377612
OS -5.2805965 -38.54394628
OS -5.27967194 -38.555041
OS -5.27874738 -38.56798484
OS -5.27689826 -38.58092868
OS -5.2759737 -38.59572164
OS -5.2759737 -38.6105146
OS -5.27504914 -38.62715668
OS -5.27504914 -38.64472332
OS -5.27504914 -38.64564788
OS -5.27504914 -38.64934612
OS -5.27504914 -38.65581804
OS -5.27504914 -38.66321452
OS -5.2759737 -38.67338468
OS -5.2759737 -38.6844794
OS -5.27689826 -38.69649868
OS -5.27782282 -38.70944252
OS -5.2805965 -38.73902844
OS -5.2852193 -38.76953892
OS -5.29076666 -38.79912484
OS -5.2944649 -38.81299324
OS -5.2990877 -38.82686164
OS -5.2990877 -38.8277862
OS -5.30001226 -38.82963532
OS -5.30186138 -38.83333356
OS -5.3037105 -38.83795636
OS -5.30555962 -38.84442828
OS -5.30925786 -38.8509002
OS -5.31665434 -38.86661772
OS -5.32589994 -38.8832598
OS -5.33791922 -38.901751
OS -5.35178762 -38.91839308
OS -5.3684297 -38.9341106
OS -5.36935426 -38.9341106
OS -5.37027882 -38.93595972
OS -5.3730525 -38.93780884
OS -5.37675074 -38.93965796
OS -5.38137354 -38.94243164
OS -5.38599634 -38.94612988
OS -5.39986474 -38.9526018
OS -5.41650682 -38.95907372
OS -5.43592258 -38.96554564
OS -5.45903658 -38.96924388
OS -5.4839997 -38.971093
OS -5.4932453 -38.971093
OS -5.49971722 -38.97016844
OS -5.5071137 -38.96924388
OS -5.5163593 -38.96739476
OS -5.52652946 -38.96554564
OS -5.53762418 -38.96277196
OS -5.5487189 -38.95907372
OS -5.56073818 -38.95537548
OS -5.57275746 -38.94982812
OS -5.58477674 -38.9433562
OS -5.59679602 -38.93595972
OS -5.6088153 -38.92671412
OS -5.61991002 -38.91654396
OS -5.63008018 -38.90544924
OS -5.63100474 -38.90452468
OS -5.63285386 -38.901751
OS -5.63562754 -38.8971282
OS -5.64025034 -38.88973172
OS -5.64487314 -38.88141068
OS -5.64949594 -38.87031596
OS -5.65596786 -38.85737212
OS -5.66151522 -38.84257916
OS -5.66706258 -38.82593708
OS -5.67260994 -38.80652132
OS -5.6781573 -38.78525644
OS -5.6827801 -38.76121788
OS -5.6874029 -38.7353302
OS -5.69017658 -38.7075934
OS -5.6920257 -38.67708292
OS -5.69295026 -38.64472332
OS -5.69295026 -38.64379876
OS -5.69295026 -38.64010052
OS -5.69295026 -38.6336286
OS -5.69295026 -38.62623212
OS -5.6920257 -38.61606196
OS -5.6920257 -38.60496724
OS -5.69110114 -38.59294796
OS -5.69017658 -38.57907956
OS -5.6874029 -38.5504182
OS -5.6827801 -38.51990772
OS -5.67723274 -38.48939724
OS -5.6735345 -38.47552884
OS -5.66983626 -38.46166044
OS -5.66983626 -38.46073588
OS -5.6689117 -38.45888676
OS -5.66706258 -38.45518852
OS -5.66521346 -38.45056572
OS -5.66336434 -38.4440938
OS -5.6596661 -38.43762188
OS -5.65226962 -38.42190436
OS -5.64302402 -38.40526228
OS -5.63100474 -38.38769564
OS -5.61713634 -38.370129
OS -5.60049426 -38.35533604
OS -5.5995697 -38.35533604
OS -5.59864514 -38.35348692
OS -5.59587146 -38.3516378
OS -5.59217322 -38.34978868
OS -5.58755042 -38.34609044
OS -5.58200306 -38.34331676
OS -5.56813466 -38.33592028
OS -5.55149258 -38.32944836
OS -5.53207682 -38.32297644
OS -5.50896282 -38.3192782
OS -5.4839997 -38.31742908
OS -5.47567866 -38.31742908
OS -5.4655085 -38.31835364
OE
OB -4.46421002 -38.7676898 I
OS -4.7073693 -38.7676898
OS -4.7073693 -38.6891022
OS -4.46421002 -38.6891022
OS -4.46421002 -38.7676898
OE
OB -4.86546906 -38.73440564 I
OS -4.77856042 -38.73440564
OS -4.77856042 -38.80652132
OS -4.86546906 -38.80652132
OS -4.86546906 -38.95999828
OS -4.94405666 -38.95999828
OS -4.94405666 -38.80652132
OS -5.22234922 -38.80652132
OS -5.22234922 -38.73440564
OS -4.9292637 -38.32020276
OS -4.86546906 -38.32020276
OS -4.86546906 -38.73440564
OE
OB -4.30148746 -38.54856908 I
OS -4.3005629 -38.54764452
OS -4.29963834 -38.5457954
OS -4.29686466 -38.54302172
OS -4.29224186 -38.53839892
OS -4.28761906 -38.53377612
OS -4.2820717 -38.52822876
OS -4.27467522 -38.5226814
OS -4.26727874 -38.51713404
OS -4.24878754 -38.50511476
OS -4.22752266 -38.49586916
OS -4.21550338 -38.49124636
OS -4.20255954 -38.48847268
OS -4.18869114 -38.48662356
OS -4.17482274 -38.485699
OS -4.16742626 -38.485699
OS -4.15910522 -38.48662356
OS -4.14893506 -38.48754812
OS -4.13691578 -38.4903218
OS -4.12304738 -38.49309548
OS -4.10825442 -38.49771828
OS -4.09438602 -38.50326564
OS -4.0925369 -38.5041902
OS -4.0879141 -38.50603932
OS -4.08051762 -38.51066212
OS -4.07219658 -38.51620948
OS -4.06202642 -38.5226814
OS -4.05185626 -38.53100244
OS -4.04076154 -38.5411726
OS -4.03151594 -38.55226732
OS -4.03059138 -38.55319188
OS -4.0278177 -38.55781468
OS -4.0231949 -38.5642866
OS -4.01764754 -38.57260764
OS -4.01117562 -38.58370236
OS -4.0047037 -38.5966462
OS -3.99823178 -38.61143916
OS -3.99268442 -38.62715668
OS -3.99268442 -38.62808124
OS -3.99175986 -38.6290058
OS -3.9908353 -38.63177948
OS -3.98991074 -38.63455316
OS -3.98806162 -38.64379876
OS -3.98528794 -38.65581804
OS -3.98251426 -38.66968644
OS -3.97974058 -38.68540396
OS -3.97881602 -38.7029706
OS -3.97789146 -38.7214618
OS -3.97789146 -38.72238636
OS -3.97789146 -38.72700916
OS -3.97789146 -38.73255652
OS -3.97881602 -38.74087756
OS -3.97974058 -38.75104772
OS -3.98066514 -38.76214244
OS -3.98251426 -38.77508628
OS -3.98528794 -38.78895468
OS -3.99268442 -38.8185406
OS -3.99730722 -38.83425812
OS -4.00285458 -38.84905108
OS -4.0093265 -38.8647686
OS -4.01764754 -38.878637
OS -4.02689314 -38.8925054
OS -4.0370633 -38.90544924
OS -4.03798786 -38.9063738
OS -4.03983698 -38.90822292
OS -4.04261066 -38.9109966
OS -4.04723346 -38.9156194
OS -4.05370538 -38.9202422
OS -4.0601773 -38.92578956
OS -4.06757378 -38.93133692
OS -4.07681938 -38.93780884
OS -4.08698954 -38.9433562
OS -4.0971597 -38.94982812
OS -4.12212282 -38.95999828
OS -4.13506666 -38.96462108
OS -4.14893506 -38.96739476
OS -4.16372802 -38.96924388
OS -4.17852098 -38.97016844
OS -4.18221922 -38.97016844
OS -4.18684202 -38.96924388
OS -4.19238938 -38.96924388
OS -4.1988613 -38.96831932
OS -4.20718234 -38.9664702
OS -4.22567354 -38.9618474
OS -4.2358437 -38.95814916
OS -4.24601386 -38.95352636
OS -4.25710858 -38.947979
OS -4.26727874 -38.94150708
OS -4.27837346 -38.93318604
OS -4.28854362 -38.92394044
OS -4.29778922 -38.91377028
OS -4.30703482 -38.901751
OS -4.30703482 -38.95999828
OS -4.38007506 -38.95999828
OS -4.38007506 -38.32020276
OS -4.30148746 -38.32020276
OS -4.30148746 -38.54856908
OE
OB -3.67740946 -38.48662356 I
OS -3.66908842 -38.48754812
OS -3.65984282 -38.48939724
OS -3.64967266 -38.49124636
OS -3.63765338 -38.49309548
OS -3.61269026 -38.50141652
OS -3.59974642 -38.50603932
OS -3.58680258 -38.51251124
OS -3.57385874 -38.51898316
OS -3.5609149 -38.52822876
OS -3.54889562 -38.53747436
OS -3.53687634 -38.54856908
OS -3.53595178 -38.54949364
OS -3.53410266 -38.55134276
OS -3.53132898 -38.555041
OS -3.52763074 -38.5596638
OS -3.52300794 -38.56613572
OS -3.51746058 -38.57445676
OS -3.51191322 -38.58370236
OS -3.50636586 -38.59387252
OS -3.5008185 -38.60496724
OS -3.49527114 -38.61883564
OS -3.48972378 -38.63270404
OS -3.48510098 -38.64842156
OS -3.48140274 -38.66506364
OS -3.47862906 -38.68263028
OS -3.47677994 -38.70112148
OS -3.47585538 -38.7214618
OS -3.47585538 -38.72238636
OS -3.47585538 -38.72516004
OS -3.47585538 -38.72978284
OS -3.47585538 -38.73625476
OS -3.47677994 -38.74365124
OS -3.4777045 -38.75289684
OS -3.4777045 -38.76214244
OS -3.47955362 -38.7723126
OS -3.4823273 -38.7954266
OS -3.48787466 -38.8185406
OS -3.49434658 -38.8416546
OS -3.50359218 -38.86291948
OS -3.50359218 -38.86384404
OS -3.50451674 -38.8647686
OS -3.50636586 -38.86754228
OS -3.50821498 -38.87124052
OS -3.5146869 -38.88048612
OS -3.52300794 -38.89158084
OS -3.53410266 -38.90452468
OS -3.54797106 -38.91746852
OS -3.56368858 -38.93041236
OS -3.58217978 -38.94243164
OS -3.58310434 -38.94243164
OS -3.5840289 -38.9433562
OS -3.58680258 -38.94520532
OS -3.59142538 -38.94705444
OS -3.59604818 -38.94890356
OS -3.60159554 -38.95075268
OS -3.61546394 -38.95630004
OS -3.63118146 -38.96092284
OS -3.65059722 -38.96554564
OS -3.67093754 -38.96924388
OS -3.69312698 -38.97016844
OS -3.70237258 -38.97016844
OS -3.70976906 -38.96924388
OS -3.7180901 -38.96831932
OS -3.7273357 -38.9664702
OS -3.73843042 -38.96462108
OS -3.74952514 -38.96277196
OS -3.77448826 -38.95537548
OS -3.78835666 -38.94982812
OS -3.8013005 -38.94428076
OS -3.81424434 -38.93688428
OS -3.82718818 -38.92856324
OS -3.83920746 -38.91931764
OS -3.85122674 -38.90822292
OS -3.8521513 -38.90729836
OS -3.85400042 -38.90544924
OS -3.8567741 -38.901751
OS -3.86047234 -38.89620364
OS -3.86509514 -38.88973172
OS -3.86971794 -38.88233524
OS -3.8752653 -38.87308964
OS -3.88081266 -38.86199492
OS -3.88636002 -38.84997564
OS -3.89190738 -38.83610724
OS -3.89653018 -38.82131428
OS -3.90115298 -38.80559676
OS -3.90485122 -38.78803012
OS -3.9076249 -38.76953892
OS -3.90947402 -38.7491986
OS -3.91039858 -38.72793372
OS -3.91039858 -38.7260846
OS -3.91039858 -38.72238636
OS -3.90947402 -38.71591444
OS -3.90947402 -38.70666884
OS -3.90854946 -38.69649868
OS -3.90670034 -38.68355484
OS -3.90485122 -38.670611
OS -3.90115298 -38.65581804
OS -3.89745474 -38.64102508
OS -3.89283194 -38.62530756
OS -3.88728458 -38.60866548
OS -3.8798881 -38.59294796
OS -3.87249162 -38.578155
OS -3.86232146 -38.56336204
OS -3.8521513 -38.54949364
OS -3.83920746 -38.53747436
OS -3.8382829 -38.5365498
OS -3.83643378 -38.53562524
OS -3.83273554 -38.53285156
OS -3.82811274 -38.52915332
OS -3.82256538 -38.52545508
OS -3.8151689 -38.52083228
OS -3.80777242 -38.51620948
OS -3.79852682 -38.51158668
OS -3.78835666 -38.50696388
OS -3.77726194 -38.50234108
OS -3.75229882 -38.49402004
OS -3.72363746 -38.48754812
OS -3.7088445 -38.48662356
OS -3.69312698 -38.485699
OS -3.68388138 -38.485699
OS -3.67740946 -38.48662356
OE
OB -5.79280274 -38.95999828 I
OS -5.87139034 -38.95999828
OS -5.87139034 -38.32020276
OS -5.79280274 -38.32020276
OS -5.79280274 -38.95999828
OE
OB -5.97031826 -38.42745172 I
OS -5.99158314 -38.54671996
OS -6.04058482 -38.54671996
OS -6.06000058 -38.42745172
OS -6.06000058 -38.32020276
OS -5.97031826 -38.32020276
OS -5.97031826 -38.42745172
OE
OB -5.48492426 -38.38214828 H
OS -5.49047162 -38.38214828
OS -5.49416986 -38.38307284
OS -5.50434002 -38.38492196
OS -5.5163593 -38.38769564
OS -5.5302277 -38.393243
OS -5.54502066 -38.40156404
OS -5.55241714 -38.4071114
OS -5.55981362 -38.41265876
OS -5.56628554 -38.42005524
OS -5.57275746 -38.42837628
OS -5.57275746 -38.42930084
OS -5.57460658 -38.43114996
OS -5.5764557 -38.4348482
OS -5.57922938 -38.439471
OS -5.58200306 -38.44686748
OS -5.5857013 -38.45518852
OS -5.58847498 -38.46535868
OS -5.59217322 -38.47737796
OS -5.59587146 -38.49124636
OS -5.5995697 -38.50696388
OS -5.60326794 -38.52453052
OS -5.60604162 -38.54394628
OS -5.6088153 -38.56613572
OS -5.61066442 -38.59017428
OS -5.61158898 -38.61606196
OS -5.61251354 -38.64472332
OS -5.61251354 -38.64657244
OS -5.61251354 -38.65119524
OS -5.61251354 -38.65951628
OS -5.61158898 -38.670611
OS -5.61158898 -38.68263028
OS -5.61066442 -38.69742324
OS -5.60973986 -38.71314076
OS -5.60789074 -38.72978284
OS -5.60326794 -38.76584068
OS -5.60049426 -38.78340732
OS -5.59679602 -38.8000494
OS -5.59309778 -38.81576692
OS -5.58755042 -38.83055988
OS -5.58200306 -38.84350372
OS -5.57553114 -38.85459844
OS -5.57553114 -38.855523
OS -5.57368202 -38.85644756
OS -5.56905922 -38.86291948
OS -5.56073818 -38.87124052
OS -5.55056802 -38.88048612
OS -5.53669962 -38.88973172
OS -5.5209821 -38.89805276
OS -5.50341546 -38.90452468
OS -5.49416986 -38.90544924
OS -5.4839997 -38.9063738
OS -5.47845234 -38.9063738
OS -5.4747541 -38.90544924
OS -5.4655085 -38.90360012
OS -5.45256466 -38.89990188
OS -5.43869626 -38.89342996
OS -5.42297874 -38.88418436
OS -5.41558226 -38.878637
OS -5.40818578 -38.87124052
OS -5.4007893 -38.86384404
OS -5.39339282 -38.85459844
OS -5.39339282 -38.85367388
OS -5.3915437 -38.85182476
OS -5.38969458 -38.84905108
OS -5.38784546 -38.84442828
OS -5.38414722 -38.83795636
OS -5.38137354 -38.82963532
OS -5.3776753 -38.82038972
OS -5.37397706 -38.809295
OS -5.37120338 -38.7954266
OS -5.36750514 -38.78063364
OS -5.3638069 -38.763067
OS -5.36103322 -38.7445758
OS -5.3591841 -38.72238636
OS -5.35733498 -38.69927236
OS -5.35548586 -38.67338468
OS -5.35548586 -38.64472332
OS -5.35548586 -38.64379876
OS -5.35548586 -38.6428742
OS -5.35548586 -38.6382514
OS -5.35548586 -38.62993036
OS -5.35641042 -38.61883564
OS -5.35641042 -38.60681636
OS -5.35733498 -38.5920234
OS -5.35825954 -38.57630588
OS -5.36010866 -38.55873924
OS -5.36473146 -38.52360596
OS -5.36750514 -38.50603932
OS -5.37120338 -38.48939724
OS -5.37490162 -38.47367972
OS -5.38044898 -38.45888676
OS -5.38599634 -38.44594292
OS -5.39246826 -38.4348482
OS -5.39246826 -38.43392364
OS -5.39431738 -38.43299908
OS -5.3961665 -38.4302254
OS -5.39894018 -38.42652716
OS -5.40726122 -38.41820612
OS -5.41743138 -38.40803596
OS -5.43129978 -38.39879036
OS -5.4470173 -38.39046932
OS -5.45533834 -38.38677108
OS -5.46458394 -38.3839974
OS -5.4747541 -38.38307284
OS -5.48492426 -38.38214828
OE
OB 0.1881759 -38.5504182 H
OS 0.18262854 -38.5504182
OS 0.1789303 -38.55134276
OS 0.16876014 -38.55226732
OS 0.15674086 -38.555041
OS 0.1419479 -38.5596638
OS 0.12623038 -38.56613572
OS 0.11143742 -38.57538132
OS 0.09664446 -38.5874006
OS 0.09479534 -38.58924972
OS 0.0910971 -38.59387252
OS 0.08462518 -38.60219356
OS 0.07815326 -38.61328828
OS 0.07075678 -38.62623212
OS 0.06428486 -38.6428742
OS 0.0587375 -38.66228996
OS 0.05596382 -38.68355484
OS 0.31576518 -38.68355484
OS 0.31576518 -38.68263028
OS 0.31576518 -38.68078116
OS 0.31484062 -38.67800748
OS 0.31484062 -38.67430924
OS 0.3129915 -38.66321452
OS 0.31021782 -38.65119524
OS 0.30559502 -38.63640228
OS 0.30097222 -38.62253388
OS 0.29357574 -38.60866548
OS 0.2852547 -38.5966462
OS 0.2852547 -38.59572164
OS 0.28340558 -38.59479708
OS 0.27878278 -38.58924972
OS 0.27046174 -38.58185324
OS 0.25936702 -38.5735322
OS 0.24549862 -38.56521116
OS 0.22885654 -38.55781468
OS 0.20944078 -38.55226732
OS 0.19927062 -38.55134276
OS 0.1881759 -38.5504182
OE
OB -2.69830042 -38.5504182 H
OS -2.70384778 -38.5504182
OS -2.70847058 -38.55134276
OS -2.71864074 -38.55226732
OS -2.73250914 -38.55596556
OS -2.74822666 -38.56151292
OS -2.76486874 -38.5689094
OS -2.78058626 -38.58000412
OS -2.7889073 -38.5874006
OS -2.79630378 -38.59479708
OS -2.79630378 -38.59572164
OS -2.7981529 -38.5966462
OS -2.80000202 -38.59941988
OS -2.8027757 -38.60311812
OS -2.80554938 -38.60774092
OS -2.80832306 -38.61328828
OS -2.8120213 -38.62068476
OS -2.81571954 -38.62808124
OS -2.81941778 -38.63732684
OS -2.82311602 -38.64657244
OS -2.8258897 -38.65766716
OS -2.82866338 -38.66968644
OS -2.83143706 -38.68263028
OS -2.83328618 -38.69649868
OS -2.83421074 -38.7122162
OS -2.8351353 -38.72793372
OS -2.8351353 -38.72885828
OS -2.8351353 -38.73163196
OS -2.8351353 -38.73625476
OS -2.83421074 -38.74272668
OS -2.83421074 -38.75012316
OS -2.83328618 -38.7584442
OS -2.8305125 -38.77785996
OS -2.8258897 -38.8000494
OS -2.81849322 -38.82223884
OS -2.80924762 -38.84350372
OS -2.8027757 -38.85274932
OS -2.79630378 -38.86199492
OS -2.79537922 -38.86199492
OS -2.79445466 -38.86384404
OS -2.7889073 -38.86846684
OS -2.78058626 -38.87586332
OS -2.76949154 -38.8832598
OS -2.75562314 -38.89158084
OS -2.73898106 -38.89897732
OS -2.7195653 -38.90360012
OS -2.70939514 -38.90452468
OS -2.69830042 -38.90544924
OS -2.69275306 -38.90544924
OS -2.68813026 -38.90452468
OS -2.6779601 -38.90267556
OS -2.6640917 -38.89990188
OS -2.64929874 -38.89435452
OS -2.63265666 -38.88695804
OS -2.61693914 -38.87586332
OS -2.6086181 -38.86846684
OS -2.60122162 -38.86107036
OS -2.60029706 -38.8601458
OS -2.5993725 -38.85922124
OS -2.59752338 -38.85644756
OS -2.5947497 -38.85274932
OS -2.59197602 -38.84812652
OS -2.58827778 -38.84257916
OS -2.58457954 -38.83518268
OS -2.5808813 -38.8277862
OS -2.57718306 -38.8185406
OS -2.57440938 -38.80837044
OS -2.57071114 -38.79727572
OS -2.56793746 -38.78525644
OS -2.56516378 -38.77138804
OS -2.56331466 -38.75751964
OS -2.56146554 -38.74180212
OS -2.56146554 -38.72516004
OS -2.56146554 -38.72423548
OS -2.56146554 -38.7214618
OS -2.56146554 -38.716839
OS -2.5623901 -38.71129164
OS -2.5623901 -38.70389516
OS -2.56331466 -38.69557412
OS -2.56608834 -38.67615836
OS -2.57071114 -38.65581804
OS -2.57810762 -38.6336286
OS -2.58827778 -38.61328828
OS -2.59382514 -38.60311812
OS -2.60122162 -38.59479708
OS -2.60122162 -38.59387252
OS -2.60307074 -38.59294796
OS -2.6086181 -38.5874006
OS -2.61693914 -38.58092868
OS -2.62803386 -38.57260764
OS -2.64190226 -38.5642866
OS -2.65854434 -38.55689012
OS -2.67703554 -38.55226732
OS -2.6872057 -38.55134276
OS -2.69830042 -38.5504182
OE
OB -3.69312698 -38.5504182 H
OS -3.69867434 -38.5504182
OS -3.70329714 -38.55134276
OS -3.7134673 -38.55226732
OS -3.7273357 -38.55596556
OS -3.74305322 -38.56151292
OS -3.7596953 -38.5689094
OS -3.77541282 -38.58000412
OS -3.78373386 -38.5874006
OS -3.79113034 -38.59479708
OS -3.79113034 -38.59572164
OS -3.79297946 -38.5966462
OS -3.79482858 -38.59941988
OS -3.79760226 -38.60311812
OS -3.80037594 -38.60774092
OS -3.80314962 -38.61328828
OS -3.80684786 -38.62068476
OS -3.8105461 -38.62808124
OS -3.81424434 -38.63732684
OS -3.81794258 -38.64657244
OS -3.82071626 -38.65766716
OS -3.82348994 -38.66968644
OS -3.82626362 -38.68263028
OS -3.82811274 -38.69649868
OS -3.8290373 -38.7122162
OS -3.82996186 -38.72793372
OS -3.82996186 -38.72885828
OS -3.82996186 -38.73163196
OS -3.82996186 -38.73625476
OS -3.8290373 -38.74272668
OS -3.8290373 -38.75012316
OS -3.82811274 -38.7584442
OS -3.82533906 -38.77785996
OS -3.82071626 -38.8000494
OS -3.81331978 -38.82223884
OS -3.80407418 -38.84350372
OS -3.79760226 -38.85274932
OS -3.79113034 -38.86199492
OS -3.79020578 -38.86199492
OS -3.78928122 -38.86384404
OS -3.78373386 -38.86846684
OS -3.77541282 -38.87586332
OS -3.7643181 -38.8832598
OS -3.7504497 -38.89158084
OS -3.73380762 -38.89897732
OS -3.71439186 -38.90360012
OS -3.7042217 -38.90452468
OS -3.69312698 -38.90544924
OS -3.68757962 -38.90544924
OS -3.68295682 -38.90452468
OS -3.67278666 -38.90267556
OS -3.65891826 -38.89990188
OS -3.6441253 -38.89435452
OS -3.62748322 -38.88695804
OS -3.6117657 -38.87586332
OS -3.60344466 -38.86846684
OS -3.59604818 -38.86107036
OS -3.59512362 -38.8601458
OS -3.59419906 -38.85922124
OS -3.59234994 -38.85644756
OS -3.58957626 -38.85274932
OS -3.58680258 -38.84812652
OS -3.58310434 -38.84257916
OS -3.5794061 -38.83518268
OS -3.57570786 -38.8277862
OS -3.57200962 -38.8185406
OS -3.56923594 -38.80837044
OS -3.5655377 -38.79727572
OS -3.56276402 -38.78525644
OS -3.55999034 -38.77138804
OS -3.55814122 -38.75751964
OS -3.5562921 -38.74180212
OS -3.5562921 -38.72516004
OS -3.5562921 -38.72423548
OS -3.5562921 -38.7214618
OS -3.5562921 -38.716839
OS -3.55721666 -38.71129164
OS -3.55721666 -38.70389516
OS -3.55814122 -38.69557412
OS -3.5609149 -38.67615836
OS -3.5655377 -38.65581804
OS -3.57293418 -38.6336286
OS -3.58310434 -38.61328828
OS -3.5886517 -38.60311812
OS -3.59604818 -38.59479708
OS -3.59604818 -38.59387252
OS -3.5978973 -38.59294796
OS -3.60344466 -38.5874006
OS -3.6117657 -38.58092868
OS -3.62286042 -38.57260764
OS -3.63672882 -38.5642866
OS -3.6533709 -38.55689012
OS -3.6718621 -38.55226732
OS -3.68203226 -38.55134276
OS -3.69312698 -38.5504182
OE
OB -4.17297362 -38.5504182 H
OS -4.18684202 -38.5504182
OS -4.19054026 -38.55134276
OS -4.20071042 -38.55319188
OS -4.2127297 -38.55596556
OS -4.2265981 -38.56151292
OS -4.24139106 -38.56983396
OS -4.24878754 -38.57445676
OS -4.25618402 -38.58092868
OS -4.2635805 -38.5874006
OS -4.27097698 -38.59572164
OS -4.27097698 -38.5966462
OS -4.2728261 -38.59757076
OS -4.27467522 -38.60034444
OS -4.27652434 -38.60404268
OS -4.27929802 -38.60866548
OS -4.28299626 -38.61421284
OS -4.28576994 -38.62068476
OS -4.28946818 -38.62808124
OS -4.29316642 -38.63732684
OS -4.2959401 -38.64657244
OS -4.29963834 -38.65766716
OS -4.30241202 -38.66876188
OS -4.30426114 -38.68170572
OS -4.30611026 -38.69557412
OS -4.30795938 -38.70944252
OS -4.30795938 -38.72516004
OS -4.30795938 -38.7260846
OS -4.30795938 -38.72885828
OS -4.30795938 -38.73348108
OS -4.30795938 -38.73902844
OS -4.30703482 -38.74550036
OS -4.30703482 -38.7538214
OS -4.3051857 -38.77138804
OS -4.30241202 -38.7908038
OS -4.29871378 -38.81114412
OS -4.29316642 -38.82963532
OS -4.28946818 -38.83795636
OS -4.28576994 -38.84535284
OS -4.28576994 -38.8462774
OS -4.28392082 -38.84812652
OS -4.2820717 -38.8509002
OS -4.27929802 -38.85459844
OS -4.27097698 -38.8647686
OS -4.2589577 -38.87493876
OS -4.2450893 -38.88603348
OS -4.22752266 -38.89620364
OS -4.21827706 -38.89990188
OS -4.20718234 -38.90267556
OS -4.19701218 -38.90452468
OS -4.1849929 -38.90544924
OS -4.1803701 -38.90544924
OS -4.17667186 -38.90452468
OS -4.1665017 -38.90267556
OS -4.15448242 -38.89990188
OS -4.14061402 -38.89435452
OS -4.12582106 -38.88695804
OS -4.1110281 -38.87586332
OS -4.10363162 -38.86846684
OS -4.09623514 -38.86107036
OS -4.09623514 -38.8601458
OS -4.09438602 -38.85922124
OS -4.0925369 -38.85644756
OS -4.09068778 -38.85274932
OS -4.08698954 -38.84812652
OS -4.08421586 -38.84257916
OS -4.08051762 -38.83518268
OS -4.07681938 -38.8277862
OS -4.0740457 -38.8185406
OS -4.07034746 -38.809295
OS -4.06664922 -38.79820028
OS -4.06387554 -38.786181
OS -4.06202642 -38.77323716
OS -4.0601773 -38.75936876
OS -4.05832818 -38.74365124
OS -4.05832818 -38.72793372
OS -4.05832818 -38.72700916
OS -4.05832818 -38.72423548
OS -4.05832818 -38.71961268
OS -4.05925274 -38.71314076
OS -4.05925274 -38.70574428
OS -4.0601773 -38.69649868
OS -4.06295098 -38.67708292
OS -4.06664922 -38.65581804
OS -4.07312114 -38.63270404
OS -4.08236674 -38.61236372
OS -4.0879141 -38.60219356
OS -4.09438602 -38.59387252
OS -4.09438602 -38.59294796
OS -4.09623514 -38.5920234
OS -4.10085794 -38.5874006
OS -4.10825442 -38.58000412
OS -4.11842458 -38.57168308
OS -4.13136842 -38.5642866
OS -4.14616138 -38.55689012
OS -4.16372802 -38.55226732
OS -4.17297362 -38.5504182
OE
OB -4.94405666 -38.44779204 H
OS -5.14561074 -38.73440564
OS -4.94405666 -38.73440564
OS -4.94405666 -38.44779204
OE
OB -0.65040002 -38.72700916 H
OS -0.65132458 -38.72700916
OS -0.65224914 -38.72793372
OS -0.65502282 -38.72885828
OS -0.65872106 -38.72978284
OS -0.66334386 -38.73163196
OS -0.66889122 -38.73348108
OS -0.67536314 -38.7353302
OS -0.68275962 -38.73717932
OS -0.69108066 -38.739953
OS -0.70125082 -38.74180212
OS -0.71142098 -38.7445758
OS -0.72344026 -38.74734948
OS -0.7363841 -38.75012316
OS -0.74932794 -38.75289684
OS -0.7641209 -38.75474596
OS -0.77983842 -38.75751964
OS -0.78168754 -38.75751964
OS -0.7872349 -38.7584442
OS -0.7964805 -38.76029332
OS -0.80665066 -38.76214244
OS -0.81774538 -38.76399156
OS -0.8288401 -38.76676524
OS -0.83901026 -38.76953892
OS -0.84825586 -38.77323716
OS -0.84918042 -38.77323716
OS -0.8519541 -38.77508628
OS -0.85565234 -38.7769354
OS -0.85935058 -38.77970908
OS -0.8704453 -38.78710556
OS -0.8796909 -38.79820028
OS -0.8796909 -38.79912484
OS -0.88154002 -38.80097396
OS -0.88246458 -38.8046722
OS -0.8843137 -38.809295
OS -0.88616282 -38.81484236
OS -0.88801194 -38.82038972
OS -0.8889365 -38.8277862
OS -0.88986106 -38.83518268
OS -0.88986106 -38.83610724
OS -0.88986106 -38.84073004
OS -0.8889365 -38.8462774
OS -0.88708738 -38.85367388
OS -0.8843137 -38.86199492
OS -0.8796909 -38.87031596
OS -0.87414354 -38.87956156
OS -0.86674706 -38.8878826
OS -0.8658225 -38.88880716
OS -0.86212426 -38.89065628
OS -0.8565769 -38.89435452
OS -0.84918042 -38.89805276
OS -0.83901026 -38.901751
OS -0.82699098 -38.90544924
OS -0.81312258 -38.90729836
OS -0.7964805 -38.90822292
OS -0.78908402 -38.90822292
OS -0.77983842 -38.90729836
OS -0.76966826 -38.90544924
OS -0.75672442 -38.90360012
OS -0.74378058 -38.89990188
OS -0.72991218 -38.89527908
OS -0.71604378 -38.88880716
OS -0.71419466 -38.8878826
OS -0.71049642 -38.88510892
OS -0.7040245 -38.88048612
OS -0.69662802 -38.8740142
OS -0.68830698 -38.86661772
OS -0.67906138 -38.85737212
OS -0.6716649 -38.8462774
OS -0.66426842 -38.83425812
OS -0.66334386 -38.83333356
OS -0.6624193 -38.82963532
OS -0.66057018 -38.8231634
OS -0.6577965 -38.81484236
OS -0.65502282 -38.80374764
OS -0.6531737 -38.7908038
OS -0.65224914 -38.77508628
OS -0.65132458 -38.75659508
OS -0.65040002 -38.72700916
OE
SE
S P 0
OB -4.66714078 -36.5016923 I
OS -4.65465922 -36.5016923
OS -4.62553558 -36.50307914
OS -4.5950251 -36.50723966
OS -4.56174094 -36.51140018
OS -4.53123046 -36.51833438
OS -4.51597522 -36.5224949
OS -4.50349366 -36.52665542
OS -4.50210682 -36.52665542
OS -4.50071998 -36.52804226
OS -4.49239894 -36.53220278
OS -4.47991738 -36.53775014
OS -4.46466214 -36.54745802
OS -4.44802006 -36.55993958
OS -4.42999114 -36.57658166
OS -4.41334906 -36.59599742
OS -4.39670698 -36.61818686
OS -4.39670698 -36.6195737
OS -4.39532014 -36.62096054
OS -4.38977278 -36.62928158
OS -4.38422542 -36.64314998
OS -4.37590438 -36.6611789
OS -4.36897018 -36.6819815
OS -4.36203598 -36.70694462
OS -4.35787546 -36.73329458
OS -4.35648862 -36.76241822
OS -4.35648862 -36.76380506
OS -4.35648862 -36.76657874
OS -4.35648862 -36.7721261
OS -4.35787546 -36.7790603
OS -4.35787546 -36.78876818
OS -4.3592623 -36.79847606
OS -4.36480966 -36.82205234
OS -4.3731307 -36.84978914
OS -4.38422542 -36.87891278
OS -4.4008675 -36.90803642
OS -4.41196222 -36.92190482
OS -4.42305694 -36.93577322
OS -4.42444378 -36.93716006
OS -4.42583062 -36.9385469
OS -4.42999114 -36.94270742
OS -4.4355385 -36.94686794
OS -4.4424727 -36.9524153
OS -4.45079374 -36.95796266
OS -4.46188846 -36.96489686
OS -4.47298318 -36.9732179
OS -4.48685158 -36.9801521
OS -4.50210682 -36.9870863
OS -4.5187489 -36.99540734
OS -4.53677782 -37.00234154
OS -4.55758042 -37.0078889
OS -4.57838302 -37.0148231
OS -4.6019593 -37.01898362
OS -4.62692242 -37.02314414
OS -4.62414874 -37.02453098
OS -4.61860138 -37.02730466
OS -4.61028034 -37.03285202
OS -4.59918562 -37.03839938
OS -4.5742225 -37.05365462
OS -4.56174094 -37.0633625
OS -4.55064622 -37.07168354
OS -4.54787254 -37.07445722
OS -4.54093834 -37.08139142
OS -4.52984362 -37.09248614
OS -4.51597522 -37.10635454
OS -4.50071998 -37.1257703
OS -4.48269106 -37.1465729
OS -4.46466214 -37.17153602
OS -4.44524638 -37.19927282
OS -4.28021242 -37.45999874
OS -4.43831218 -37.45999874
OS -4.56451462 -37.26029378
OS -4.56451462 -37.25890694
OS -4.5672883 -37.25613326
OS -4.57006198 -37.25197274
OS -4.5742225 -37.24642538
OS -4.58393038 -37.23117014
OS -4.59641194 -37.21175438
OS -4.61166718 -37.19095178
OS -4.62692242 -37.16876234
OS -4.64217766 -37.14795974
OS -4.65604606 -37.12854398
OS -4.6574329 -37.12715714
OS -4.66159342 -37.12160978
OS -4.66852762 -37.11328874
OS -4.6782355 -37.10358086
OS -4.6990381 -37.08277826
OS -4.71013282 -37.07307038
OS -4.72122754 -37.06474934
OS -4.72261438 -37.0633625
OS -4.72538806 -37.06197566
OS -4.73093542 -37.05920198
OS -4.73925646 -37.05504146
OS -4.7475775 -37.05088094
OS -4.75728538 -37.04672042
OS -4.77947482 -37.03978622
OS -4.78086166 -37.03978622
OS -4.78363534 -37.03839938
OS -4.7891827 -37.03839938
OS -4.7961169 -37.03701254
OS -4.80582478 -37.0356257
OS -4.8169195 -37.0356257
OS -4.83217474 -37.03423886
OS -4.99582186 -37.03423886
OS -4.99582186 -37.45999874
OS -5.12341114 -37.45999874
OS -5.12341114 -36.50030546
OS -4.6782355 -36.50030546
OS -4.66714078 -36.5016923
OE
OB -1.0100437 -37.45999874 I
OS -1.13208562 -37.45999874
OS -1.13208562 -36.65701838
OS -1.4122273 -37.45999874
OS -1.52594818 -37.45999874
OS -1.80331618 -36.64314998
OS -1.80331618 -37.45999874
OS -1.9253581 -37.45999874
OS -1.9253581 -36.50030546
OS -1.73536102 -36.50030546
OS -1.50791926 -37.1812439
OS -1.50791926 -37.18263074
OS -1.50653242 -37.18540442
OS -1.50514558 -37.18956494
OS -1.5023719 -37.19649914
OS -1.49682454 -37.21314122
OS -1.48989034 -37.23394382
OS -1.48295614 -37.2575201
OS -1.4746351 -37.28109638
OS -1.4677009 -37.30328582
OS -1.46215354 -37.32270158
OS -1.4607667 -37.3199279
OS -1.45937986 -37.3129937
OS -1.45521934 -37.30051214
OS -1.44967198 -37.28387006
OS -1.44273778 -37.26168062
OS -1.4330299 -37.23533066
OS -1.42332202 -37.20482018
OS -1.41084046 -37.16876234
OS -1.18062502 -36.50030546
OS -1.0100437 -36.50030546
OS -1.0100437 -37.45999874
OE
OB -2.02382374 -37.45999874 I
OS -2.1680551 -37.45999874
OS -2.28038914 -37.16876234
OS -2.68257274 -37.16876234
OS -2.78658574 -37.45999874
OS -2.92110922 -37.45999874
OS -2.55498346 -36.50030546
OS -2.41629946 -36.50030546
OS -2.02382374 -37.45999874
OE
OB -3.02928274 -37.45999874 I
OS -3.16103254 -37.45999874
OS -3.66306862 -36.70694462
OS -3.66306862 -37.45999874
OS -3.78511054 -37.45999874
OS -3.78511054 -36.50030546
OS -3.65474758 -36.50030546
OS -3.15132466 -37.25474642
OS -3.15132466 -36.50030546
OS -3.02928274 -36.50030546
OS -3.02928274 -37.45999874
OE
OB -5.3231161 -36.61402634 I
OS -5.89033366 -36.61402634
OS -5.89033366 -36.90664958
OS -5.35917394 -36.90664958
OS -5.35917394 -37.02037046
OS -5.89033366 -37.02037046
OS -5.89033366 -37.34627786
OS -5.30092666 -37.34627786
OS -5.30092666 -37.45999874
OS -6.01792294 -37.45999874
OS -6.01792294 -36.50030546
OS -5.3231161 -36.50030546
OS -5.3231161 -36.61402634
OE
OB -0.10721086 -36.61402634 I
OS -0.67442842 -36.61402634
OS -0.67442842 -36.90664958
OS -0.1432687 -36.90664958
OS -0.1432687 -37.02037046
OS -0.67442842 -37.02037046
OS -0.67442842 -37.34627786
OS -0.08502142 -37.34627786
OS -0.08502142 -37.45999874
OS -0.8020177 -37.45999874
OS -0.8020177 -36.50030546
OS -0.10721086 -36.50030546
OS -0.10721086 -36.61402634
OE
OB -8.43241138 -37.34627786 I
OS -7.95949894 -37.34627786
OS -7.95949894 -37.45999874
OS -8.56000066 -37.45999874
OS -8.56000066 -36.50030546
OS -8.43241138 -36.50030546
OS -8.43241138 -37.34627786
OE
OB -6.51718534 -37.05365462 I
OS -6.51718534 -37.45999874
OS -6.64477462 -37.45999874
OS -6.64477462 -37.05365462
OS -7.0150609 -36.50030546
OS -6.86112166 -36.50030546
OS -6.67251142 -36.79154186
OS -6.67251142 -36.7929287
OS -6.66973774 -36.79570238
OS -6.66696406 -36.7998629
OS -6.66419038 -36.80541026
OS -6.65864302 -36.81234446
OS -6.65309566 -36.8206655
OS -6.6406141 -36.8414681
OS -6.62535886 -36.86643122
OS -6.60871678 -36.89416802
OS -6.59068786 -36.92329166
OS -6.57404578 -36.95380214
OS -6.57404578 -36.9524153
OS -6.57265894 -36.94964162
OS -6.56988526 -36.9454811
OS -6.56572474 -36.93993374
OS -6.56156422 -36.93299954
OS -6.55601686 -36.9246785
OS -6.5435353 -36.9038759
OS -6.52828006 -36.87891278
OS -6.51025114 -36.84978914
OS -6.48944854 -36.81789182
OS -6.4672591 -36.78322082
OS -6.28280938 -36.50030546
OS -6.1344175 -36.50030546
OS -6.51718534 -37.05365462
OE
OB -7.01644774 -37.45999874 I
OS -7.1606791 -37.45999874
OS -7.27301314 -37.16876234
OS -7.67519674 -37.16876234
OS -7.77920974 -37.45999874
OS -7.91373322 -37.45999874
OS -7.54760746 -36.50030546
OS -7.40892346 -36.50030546
OS -7.01644774 -37.45999874
OE
OB -7.48103914 -36.60015794 H
OS -7.48103914 -36.60154478
OS -7.48242598 -36.60431846
OS -7.48242598 -36.60986582
OS -7.48519966 -36.61541318
OS -7.4865865 -36.62512106
OS -7.48936018 -36.63482894
OS -7.49490754 -36.65840522
OS -7.50184174 -36.68614202
OS -7.51154962 -36.7166525
OS -7.5212575 -36.74993666
OS -7.53373906 -36.78460766
OS -7.63775206 -37.06474934
OS -7.3132315 -37.06474934
OS -7.41308398 -36.80124974
OS -7.41308398 -36.7998629
OS -7.41447082 -36.79570238
OS -7.4172445 -36.78876818
OS -7.42001818 -36.78044714
OS -7.4241787 -36.77073926
OS -7.42833922 -36.7582577
OS -7.43249974 -36.7443893
OS -7.4380471 -36.7305209
OS -7.44914182 -36.69862358
OS -7.46023654 -36.66533942
OS -7.47133126 -36.63205526
OS -7.48103914 -36.60015794
OE
OB -4.69349074 -36.60709214 H
OS -4.99582186 -36.60709214
OS -4.99582186 -36.9246785
OS -4.71013282 -36.9246785
OS -4.69349074 -36.92329166
OS -4.67407498 -36.92190482
OS -4.65188554 -36.92051798
OS -4.6296961 -36.9177443
OS -4.60750666 -36.91358378
OS -4.5880909 -36.90803642
OS -4.58531722 -36.90664958
OS -4.57976986 -36.9038759
OS -4.57144882 -36.89971538
OS -4.5603541 -36.89416802
OS -4.54787254 -36.88584698
OS -4.53539098 -36.8761391
OS -4.52290942 -36.86365754
OS -4.51320154 -36.84978914
OS -4.5118147 -36.8484023
OS -4.50904102 -36.84285494
OS -4.5048805 -36.8345339
OS -4.49933314 -36.82343918
OS -4.49517262 -36.81095762
OS -4.4910121 -36.79708922
OS -4.48823842 -36.78044714
OS -4.48685158 -36.76380506
OS -4.48685158 -36.76241822
OS -4.48685158 -36.76103138
OS -4.48823842 -36.75271034
OS -4.48962526 -36.74022878
OS -4.49239894 -36.7235867
OS -4.49933314 -36.70694462
OS -4.50765418 -36.68752886
OS -4.52013574 -36.66949994
OS -4.53677782 -36.65147102
OS -4.5395515 -36.65008418
OS -4.5464857 -36.64453682
OS -4.55758042 -36.63760262
OS -4.57560934 -36.62928158
OS -4.59641194 -36.62096054
OS -4.62414874 -36.61402634
OS -4.65604606 -36.60847898
OS -4.69349074 -36.60709214
OE
OB -2.48841514 -36.60015794 H
OS -2.48841514 -36.60154478
OS -2.48980198 -36.60431846
OS -2.48980198 -36.60986582
OS -2.49257566 -36.61541318
OS -2.4939625 -36.62512106
OS -2.49673618 -36.63482894
OS -2.50228354 -36.65840522
OS -2.50921774 -36.68614202
OS -2.51892562 -36.7166525
OS -2.5286335 -36.74993666
OS -2.54111506 -36.78460766
OS -2.64512806 -37.06474934
OS -2.3206075 -37.06474934
OS -2.42045998 -36.80124974
OS -2.42045998 -36.7998629
OS -2.42184682 -36.79570238
OS -2.4246205 -36.78876818
OS -2.42739418 -36.78044714
OS -2.4315547 -36.77073926
OS -2.43571522 -36.7582577
OS -2.43987574 -36.7443893
OS -2.4454231 -36.7305209
OS -2.45651782 -36.69862358
OS -2.46761254 -36.66533942
OS -2.47870726 -36.63205526
OS -2.48841514 -36.60015794
OE
SE
S P 0
OB 35.73690338 -37.45999874 I
OS 35.61486146 -37.45999874
OS 35.61486146 -36.65701838
OS 35.33471978 -37.45999874
OS 35.2209989 -37.45999874
OS 34.9436309 -36.64314998
OS 34.9436309 -37.45999874
OS 34.82158898 -37.45999874
OS 34.82158898 -36.50030546
OS 35.01158606 -36.50030546
OS 35.23902782 -37.1812439
OS 35.23902782 -37.18263074
OS 35.24041466 -37.18540442
OS 35.2418015 -37.18956494
OS 35.24457518 -37.19649914
OS 35.25012254 -37.21314122
OS 35.25705674 -37.23394382
OS 35.26399094 -37.2575201
OS 35.27231198 -37.28109638
OS 35.27924618 -37.30328582
OS 35.28479354 -37.32270158
OS 35.28618038 -37.3199279
OS 35.28756722 -37.3129937
OS 35.29172774 -37.30051214
OS 35.2972751 -37.28387006
OS 35.3042093 -37.26168062
OS 35.31391718 -37.23533066
OS 35.32362506 -37.20482018
OS 35.33610662 -37.16876234
OS 35.56632206 -36.50030546
OS 35.73690338 -36.50030546
OS 35.73690338 -37.45999874
OE
OB 34.61356298 -37.05504146 I
OS 34.61356298 -37.0564283
OS 34.61356298 -37.06197566
OS 34.61356298 -37.06890986
OS 34.61356298 -37.07861774
OS 34.61217614 -37.0910993
OS 34.61217614 -37.1049677
OS 34.6107893 -37.12160978
OS 34.60940246 -37.13825186
OS 34.60524194 -37.17569654
OS 34.59969458 -37.21452806
OS 34.59137354 -37.25197274
OS 34.58582618 -37.27000166
OS 34.58027882 -37.28664374
OS 34.58027882 -37.28803058
OS 34.57889198 -37.29080426
OS 34.5761183 -37.29496478
OS 34.57334462 -37.30051214
OS 34.56502358 -37.31576738
OS 34.55254202 -37.33518314
OS 34.53589994 -37.35737258
OS 34.51648418 -37.37956202
OS 34.49152106 -37.4031383
OS 34.46101058 -37.4239409
OS 34.45962374 -37.4239409
OS 34.45685006 -37.42671458
OS 34.45268954 -37.42810142
OS 34.44575534 -37.43226194
OS 34.4374343 -37.43642246
OS 34.42633958 -37.44058298
OS 34.41524486 -37.4447435
OS 34.40137646 -37.45029086
OS 34.38612122 -37.45583822
OS 34.36947914 -37.45999874
OS 34.35145022 -37.46415926
OS 34.33064762 -37.46831978
OS 34.30984502 -37.47109346
OS 34.28765558 -37.47386714
OS 34.23772934 -37.47664082
OS 34.22524778 -37.47664082
OS 34.2155399 -37.47525398
OS 34.20444518 -37.47525398
OS 34.19057678 -37.47386714
OS 34.17532154 -37.4724803
OS 34.1600663 -37.47109346
OS 34.1253953 -37.4655461
OS 34.08795062 -37.45722506
OS 34.05189278 -37.44613034
OS 34.01722178 -37.4308751
OS 34.01583494 -37.4308751
OS 34.01306126 -37.42810142
OS 34.00890074 -37.42532774
OS 34.00335338 -37.42255406
OS 33.98809814 -37.41145934
OS 33.97006922 -37.3962041
OS 33.94926662 -37.37678834
OS 33.92985086 -37.3545989
OS 33.9104351 -37.3268621
OS 33.89517986 -37.29635162
OS 33.89517986 -37.29496478
OS 33.89379302 -37.2921911
OS 33.89240618 -37.28664374
OS 33.8896325 -37.27970954
OS 33.88685882 -37.2713885
OS 33.88408514 -37.26029378
OS 33.87992462 -37.24781222
OS 33.87715094 -37.23255698
OS 33.87437726 -37.2159149
OS 33.87021674 -37.19788598
OS 33.86744306 -37.17847022
OS 33.86466938 -37.15766762
OS 33.8618957 -37.13409134
OS 33.86050886 -37.10912822
OS 33.85912202 -37.08277826
OS 33.85912202 -37.05504146
OS 33.85912202 -36.50030546
OS 33.9867113 -36.50030546
OS 33.9867113 -37.05504146
OS 33.9867113 -37.0564283
OS 33.9867113 -37.06058882
OS 33.9867113 -37.06752302
OS 33.9867113 -37.07584406
OS 33.98809814 -37.08555194
OS 33.98809814 -37.0980335
OS 33.98948498 -37.12438346
OS 33.99225866 -37.15489394
OS 33.99641918 -37.18540442
OS 34.00196654 -37.21452806
OS 34.00474022 -37.22700962
OS 34.00890074 -37.23949118
OS 34.01028758 -37.24226486
OS 34.01306126 -37.24919906
OS 34.01999546 -37.25890694
OS 34.0283165 -37.27277534
OS 34.03802438 -37.28664374
OS 34.05189278 -37.30189898
OS 34.06853486 -37.31715422
OS 34.08795062 -37.32963578
OS 34.0907243 -37.33102262
OS 34.0976585 -37.33518314
OS 34.11014006 -37.33934366
OS 34.12678214 -37.34489102
OS 34.1461979 -37.35182522
OS 34.17116102 -37.35598574
OS 34.19751098 -37.36014626
OS 34.22663462 -37.3615331
OS 34.24050302 -37.3615331
OS 34.24882406 -37.36014626
OS 34.26130562 -37.36014626
OS 34.27378718 -37.35875942
OS 34.30429766 -37.35321206
OS 34.33758182 -37.34627786
OS 34.36947914 -37.33518314
OS 34.39998962 -37.3199279
OS 34.41385802 -37.31022002
OS 34.42633958 -37.2991253
OS 34.42772642 -37.29773846
OS 34.42911326 -37.29635162
OS 34.43188694 -37.2921911
OS 34.43604746 -37.28664374
OS 34.44020798 -37.2783227
OS 34.44575534 -37.27000166
OS 34.4513027 -37.2575201
OS 34.45685006 -37.24503854
OS 34.46239742 -37.2297833
OS 34.46655794 -37.21175438
OS 34.4721053 -37.19095178
OS 34.47626582 -37.16876234
OS 34.48042634 -37.14379922
OS 34.48320002 -37.11744926
OS 34.4859737 -37.08693878
OS 34.4859737 -37.05504146
OS 34.4859737 -36.50030546
OS 34.61356298 -36.50030546
OS 34.61356298 -37.05504146
OE
OB 33.64416182 -37.45999874 I
OS 33.51241202 -37.45999874
OS 33.01037594 -36.70694462
OS 33.01037594 -37.45999874
OS 32.88833402 -37.45999874
OS 32.88833402 -36.50030546
OS 33.01869698 -36.50030546
OS 33.5221199 -37.25474642
OS 33.5221199 -36.50030546
OS 33.64416182 -36.50030546
OS 33.64416182 -37.45999874
OE
OB 38.19022334 -36.5016923 I
OS 38.2027049 -36.5016923
OS 38.23182854 -36.50307914
OS 38.26233902 -36.50723966
OS 38.29562318 -36.51140018
OS 38.32613366 -36.51833438
OS 38.3413889 -36.5224949
OS 38.35387046 -36.52665542
OS 38.3552573 -36.52665542
OS 38.35664414 -36.52804226
OS 38.36496518 -36.53220278
OS 38.37744674 -36.53775014
OS 38.39270198 -36.54745802
OS 38.40934406 -36.55993958
OS 38.42737298 -36.57658166
OS 38.44401506 -36.59599742
OS 38.46065714 -36.61818686
OS 38.46065714 -36.6195737
OS 38.46204398 -36.62096054
OS 38.46759134 -36.62928158
OS 38.4731387 -36.64314998
OS 38.48145974 -36.6611789
OS 38.48839394 -36.6819815
OS 38.49532814 -36.70694462
OS 38.49948866 -36.73329458
OS 38.5008755 -36.76241822
OS 38.5008755 -36.76380506
OS 38.5008755 -36.76657874
OS 38.5008755 -36.7721261
OS 38.49948866 -36.7790603
OS 38.49948866 -36.78876818
OS 38.49810182 -36.79847606
OS 38.49255446 -36.82205234
OS 38.48423342 -36.84978914
OS 38.4731387 -36.87891278
OS 38.45649662 -36.90803642
OS 38.4454019 -36.92190482
OS 38.43430718 -36.93577322
OS 38.43292034 -36.93716006
OS 38.4315335 -36.9385469
OS 38.42737298 -36.94270742
OS 38.42182562 -36.94686794
OS 38.41489142 -36.9524153
OS 38.40657038 -36.95796266
OS 38.39547566 -36.96489686
OS 38.38438094 -36.9732179
OS 38.37051254 -36.9801521
OS 38.3552573 -36.9870863
OS 38.33861522 -36.99540734
OS 38.3205863 -37.00234154
OS 38.2997837 -37.0078889
OS 38.2789811 -37.0148231
OS 38.25540482 -37.01898362
OS 38.2304417 -37.02314414
OS 38.23321538 -37.02453098
OS 38.23876274 -37.02730466
OS 38.24708378 -37.03285202
OS 38.2581785 -37.03839938
OS 38.28314162 -37.05365462
OS 38.29562318 -37.0633625
OS 38.3067179 -37.07168354
OS 38.30949158 -37.07445722
OS 38.31642578 -37.08139142
OS 38.3275205 -37.09248614
OS 38.3413889 -37.10635454
OS 38.35664414 -37.1257703
OS 38.37467306 -37.1465729
OS 38.39270198 -37.17153602
OS 38.41211774 -37.19927282
OS 38.5771517 -37.45999874
OS 38.41905194 -37.45999874
OS 38.2928495 -37.26029378
OS 38.2928495 -37.25890694
OS 38.29007582 -37.25613326
OS 38.28730214 -37.25197274
OS 38.28314162 -37.24642538
OS 38.27343374 -37.23117014
OS 38.26095218 -37.21175438
OS 38.24569694 -37.19095178
OS 38.2304417 -37.16876234
OS 38.21518646 -37.14795974
OS 38.20131806 -37.12854398
OS 38.19993122 -37.12715714
OS 38.1957707 -37.12160978
OS 38.1888365 -37.11328874
OS 38.17912862 -37.10358086
OS 38.15832602 -37.08277826
OS 38.1472313 -37.07307038
OS 38.13613658 -37.06474934
OS 38.13474974 -37.0633625
OS 38.13197606 -37.06197566
OS 38.1264287 -37.05920198
OS 38.11810766 -37.05504146
OS 38.10978662 -37.05088094
OS 38.10007874 -37.04672042
OS 38.0778893 -37.03978622
OS 38.07650246 -37.03978622
OS 38.07372878 -37.03839938
OS 38.06818142 -37.03839938
OS 38.06124722 -37.03701254
OS 38.05153934 -37.0356257
OS 38.04044462 -37.0356257
OS 38.02518938 -37.03423886
OS 37.86154226 -37.03423886
OS 37.86154226 -37.45999874
OS 37.73395298 -37.45999874
OS 37.73395298 -36.50030546
OS 38.17912862 -36.50030546
OS 38.19022334 -36.5016923
OE
OB 37.53424802 -36.61402634 I
OS 36.96703046 -36.61402634
OS 36.96703046 -36.90664958
OS 37.49819018 -36.90664958
OS 37.49819018 -37.02037046
OS 36.96703046 -37.02037046
OS 36.96703046 -37.34627786
OS 37.55643746 -37.34627786
OS 37.55643746 -37.45999874
OS 36.83944118 -37.45999874
OS 36.83944118 -36.50030546
OS 37.53424802 -36.50030546
OS 37.53424802 -36.61402634
OE
OB 36.32492354 -36.5016923 I
OS 36.33601826 -36.5016923
OS 36.36098138 -36.50446598
OS 36.38871818 -36.50723966
OS 36.41784182 -36.51278702
OS 36.44696546 -36.51972122
OS 36.47331542 -36.5294291
OS 36.47470226 -36.5294291
OS 36.4760891 -36.53081594
OS 36.48441014 -36.53497646
OS 36.4968917 -36.54191066
OS 36.5107601 -36.55161854
OS 36.52740218 -36.5641001
OS 36.5454311 -36.57935534
OS 36.56207318 -36.5987711
OS 36.57732842 -36.6195737
OS 36.57871526 -36.62234738
OS 36.58287578 -36.63066842
OS 36.58980998 -36.64176314
OS 36.59674418 -36.65840522
OS 36.60367838 -36.67782098
OS 36.61061258 -36.69862358
OS 36.6147731 -36.72219986
OS 36.61615994 -36.74577614
OS 36.61615994 -36.74854982
OS 36.61615994 -36.75548402
OS 36.6147731 -36.76796558
OS 36.61199942 -36.78322082
OS 36.6078389 -36.80124974
OS 36.6009047 -36.8206655
OS 36.59258366 -36.84008126
OS 36.58148894 -36.86088386
OS 36.5801021 -36.86365754
OS 36.57594158 -36.8692049
OS 36.56762054 -36.88029962
OS 36.55652582 -36.89139434
OS 36.54265742 -36.90526274
OS 36.52601534 -36.92051798
OS 36.50521274 -36.93438638
OS 36.48163646 -36.94825478
OS 36.4830233 -36.94825478
OS 36.48579698 -36.94964162
OS 36.4899575 -36.95102846
OS 36.49550486 -36.95380214
OS 36.51214694 -36.9593495
OS 36.5315627 -36.96905738
OS 36.5523653 -36.98153894
OS 36.57594158 -36.99679418
OS 36.59674418 -37.0148231
OS 36.61615994 -37.03701254
OS 36.61754678 -37.03978622
OS 36.62309414 -37.04810726
OS 36.63141518 -37.06058882
OS 36.63973622 -37.0772309
OS 36.64805726 -37.09942034
OS 36.6563783 -37.12299662
OS 36.66192566 -37.15073342
OS 36.6633125 -37.1812439
OS 36.6633125 -37.18263074
OS 36.6633125 -37.18401758
OS 36.6633125 -37.19233862
OS 36.66192566 -37.20620702
OS 36.65915198 -37.2228491
OS 36.6563783 -37.24226486
OS 36.65083094 -37.26306746
OS 36.64389674 -37.2852569
OS 36.63418886 -37.30744634
OS 36.63280202 -37.31022002
OS 36.6286415 -37.31715422
OS 36.62309414 -37.3268621
OS 36.6147731 -37.3407305
OS 36.60367838 -37.3545989
OS 36.59258366 -37.36985414
OS 36.57871526 -37.38510938
OS 36.56346002 -37.39759094
OS 36.56207318 -37.39897778
OS 36.55652582 -37.4031383
OS 36.54681794 -37.40868566
OS 36.53433638 -37.41423302
OS 36.51908114 -37.42255406
OS 36.50105222 -37.4308751
OS 36.48163646 -37.4378093
OS 36.45806018 -37.4447435
OS 36.4552865 -37.4447435
OS 36.44696546 -37.44751718
OS 36.43309706 -37.44890402
OS 36.41506814 -37.4516777
OS 36.3928787 -37.45445138
OS 36.36652874 -37.45722506
OS 36.3374051 -37.4586119
OS 36.30412094 -37.45999874
OS 35.93799518 -37.45999874
OS 35.93799518 -36.50030546
OS 36.31521566 -36.50030546
OS 36.32492354 -36.5016923
OE
OB 32.3849111 -36.61402634 I
OS 32.06871158 -36.61402634
OS 32.06871158 -37.45999874
OS 31.9411223 -37.45999874
OS 31.9411223 -36.61402634
OS 31.62492278 -36.61402634
OS 31.62492278 -36.50030546
OS 32.3849111 -36.50030546
OS 32.3849111 -36.61402634
OE
OB 30.62639798 -37.45999874 I
OS 30.48216662 -37.45999874
OS 30.36983258 -37.16876234
OS 29.96764898 -37.16876234
OS 29.86363598 -37.45999874
OS 29.7291125 -37.45999874
OS 30.09523826 -36.50030546
OS 30.23392226 -36.50030546
OS 30.62639798 -37.45999874
OE
OB 29.3546657 -36.5016923 I
OS 29.37824198 -36.50307914
OS 29.4032051 -36.50446598
OS 29.42678138 -36.50723966
OS 29.44758398 -36.51001334
OS 29.45035766 -36.51001334
OS 29.46006554 -36.51278702
OS 29.4725471 -36.5155607
OS 29.48918918 -36.51972122
OS 29.5072181 -36.52665542
OS 29.52663386 -36.53497646
OS 29.54743646 -36.54468434
OS 29.56546538 -36.55577906
OS 29.56823906 -36.5571659
OS 29.57378642 -36.56132642
OS 29.58210746 -36.56964746
OS 29.59320218 -36.57935534
OS 29.60568374 -36.5918369
OS 29.6181653 -36.60847898
OS 29.6320337 -36.6265079
OS 29.64312842 -36.6473105
OS 29.64451526 -36.65008418
OS 29.64728894 -36.65701838
OS 29.6528363 -36.66949994
OS 29.65838366 -36.68614202
OS 29.66254418 -36.70555778
OS 29.66809154 -36.72774722
OS 29.67086522 -36.75271034
OS 29.67225206 -36.7790603
OS 29.67225206 -36.78044714
OS 29.67225206 -36.78460766
OS 29.67225206 -36.79015502
OS 29.67086522 -36.7998629
OS 29.66947838 -36.80957078
OS 29.66809154 -36.82205234
OS 29.66531786 -36.83592074
OS 29.66254418 -36.85117598
OS 29.6528363 -36.8830733
OS 29.64728894 -36.89971538
OS 29.6389679 -36.9177443
OS 29.62926002 -36.93577322
OS 29.61955214 -36.9524153
OS 29.60707058 -36.96905738
OS 29.59320218 -36.98569946
OS 29.59181534 -36.9870863
OS 29.58904166 -36.98985998
OS 29.58488114 -36.9940205
OS 29.57794694 -36.99818102
OS 29.5696259 -37.00511522
OS 29.55853118 -37.01204942
OS 29.54466278 -37.02037046
OS 29.52940754 -37.02730466
OS 29.51137862 -37.0356257
OS 29.49057602 -37.04394674
OS 29.46838658 -37.05088094
OS 29.44203662 -37.0564283
OS 29.41429982 -37.06197566
OS 29.38378934 -37.06613618
OS 29.34911834 -37.06890986
OS 29.3130605 -37.0702967
OS 29.06758982 -37.0702967
OS 29.06758982 -37.45999874
OS 28.94000054 -37.45999874
OS 28.94000054 -36.50030546
OS 29.3338631 -36.50030546
OS 29.3546657 -36.5016923
OE
OB 31.18668134 -36.5016923 I
OS 31.1991629 -36.5016923
OS 31.22828654 -36.50307914
OS 31.25879702 -36.50723966
OS 31.29208118 -36.51140018
OS 31.32259166 -36.51833438
OS 31.3378469 -36.5224949
OS 31.35032846 -36.52665542
OS 31.3517153 -36.52665542
OS 31.35310214 -36.52804226
OS 31.36142318 -36.53220278
OS 31.37390474 -36.53775014
OS 31.38915998 -36.54745802
OS 31.40580206 -36.55993958
OS 31.42383098 -36.57658166
OS 31.44047306 -36.59599742
OS 31.45711514 -36.61818686
OS 31.45711514 -36.6195737
OS 31.45850198 -36.62096054
OS 31.46404934 -36.62928158
OS 31.4695967 -36.64314998
OS 31.47791774 -36.6611789
OS 31.48485194 -36.6819815
OS 31.49178614 -36.70694462
OS 31.49594666 -36.73329458
OS 31.4973335 -36.76241822
OS 31.4973335 -36.76380506
OS 31.4973335 -36.76657874
OS 31.4973335 -36.7721261
OS 31.49594666 -36.7790603
OS 31.49594666 -36.78876818
OS 31.49455982 -36.79847606
OS 31.48901246 -36.82205234
OS 31.48069142 -36.84978914
OS 31.4695967 -36.87891278
OS 31.45295462 -36.90803642
OS 31.4418599 -36.92190482
OS 31.43076518 -36.93577322
OS 31.42937834 -36.93716006
OS 31.4279915 -36.9385469
OS 31.42383098 -36.94270742
OS 31.41828362 -36.94686794
OS 31.41134942 -36.9524153
OS 31.40302838 -36.95796266
OS 31.39193366 -36.96489686
OS 31.38083894 -36.9732179
OS 31.36697054 -36.9801521
OS 31.3517153 -36.9870863
OS 31.33507322 -36.99540734
OS 31.3170443 -37.00234154
OS 31.2962417 -37.0078889
OS 31.2754391 -37.0148231
OS 31.25186282 -37.01898362
OS 31.2268997 -37.02314414
OS 31.22967338 -37.02453098
OS 31.23522074 -37.02730466
OS 31.24354178 -37.03285202
OS 31.2546365 -37.03839938
OS 31.27959962 -37.05365462
OS 31.29208118 -37.0633625
OS 31.3031759 -37.07168354
OS 31.30594958 -37.07445722
OS 31.31288378 -37.08139142
OS 31.3239785 -37.09248614
OS 31.3378469 -37.10635454
OS 31.35310214 -37.1257703
OS 31.37113106 -37.1465729
OS 31.38915998 -37.17153602
OS 31.40857574 -37.19927282
OS 31.5736097 -37.45999874
OS 31.41550994 -37.45999874
OS 31.2893075 -37.26029378
OS 31.2893075 -37.25890694
OS 31.28653382 -37.25613326
OS 31.28376014 -37.25197274
OS 31.27959962 -37.24642538
OS 31.26989174 -37.23117014
OS 31.25741018 -37.21175438
OS 31.24215494 -37.19095178
OS 31.2268997 -37.16876234
OS 31.21164446 -37.14795974
OS 31.19777606 -37.12854398
OS 31.19638922 -37.12715714
OS 31.1922287 -37.12160978
OS 31.1852945 -37.11328874
OS 31.17558662 -37.10358086
OS 31.15478402 -37.08277826
OS 31.1436893 -37.07307038
OS 31.13259458 -37.06474934
OS 31.13120774 -37.0633625
OS 31.12843406 -37.06197566
OS 31.1228867 -37.05920198
OS 31.11456566 -37.05504146
OS 31.10624462 -37.05088094
OS 31.09653674 -37.04672042
OS 31.0743473 -37.03978622
OS 31.07296046 -37.03978622
OS 31.07018678 -37.03839938
OS 31.06463942 -37.03839938
OS 31.05770522 -37.03701254
OS 31.04799734 -37.0356257
OS 31.03690262 -37.0356257
OS 31.02164738 -37.03423886
OS 30.85800026 -37.03423886
OS 30.85800026 -37.45999874
OS 30.73041098 -37.45999874
OS 30.73041098 -36.50030546
OS 31.17558662 -36.50030546
OS 31.18668134 -36.5016923
OE
OB 38.16387338 -36.60709214 H
OS 37.86154226 -36.60709214
OS 37.86154226 -36.9246785
OS 38.1472313 -36.9246785
OS 38.16387338 -36.92329166
OS 38.18328914 -36.92190482
OS 38.20547858 -36.92051798
OS 38.22766802 -36.9177443
OS 38.24985746 -36.91358378
OS 38.26927322 -36.90803642
OS 38.2720469 -36.90664958
OS 38.27759426 -36.9038759
OS 38.2859153 -36.89971538
OS 38.29701002 -36.89416802
OS 38.30949158 -36.88584698
OS 38.32197314 -36.8761391
OS 38.3344547 -36.86365754
OS 38.34416258 -36.84978914
OS 38.34554942 -36.8484023
OS 38.3483231 -36.84285494
OS 38.35248362 -36.8345339
OS 38.35803098 -36.82343918
OS 38.3621915 -36.81095762
OS 38.36635202 -36.79708922
OS 38.3691257 -36.78044714
OS 38.37051254 -36.76380506
OS 38.37051254 -36.76241822
OS 38.37051254 -36.76103138
OS 38.3691257 -36.75271034
OS 38.36773886 -36.74022878
OS 38.36496518 -36.7235867
OS 38.35803098 -36.70694462
OS 38.34970994 -36.68752886
OS 38.33722838 -36.66949994
OS 38.3205863 -36.65147102
OS 38.31781262 -36.65008418
OS 38.31087842 -36.64453682
OS 38.2997837 -36.63760262
OS 38.28175478 -36.62928158
OS 38.26095218 -36.62096054
OS 38.23321538 -36.61402634
OS 38.20131806 -36.60847898
OS 38.16387338 -36.60709214
OE
OB 29.34218414 -36.61402634 H
OS 29.06758982 -36.61402634
OS 29.06758982 -36.95657582
OS 29.32554206 -36.95657582
OS 29.33524994 -36.95518898
OS 29.34495782 -36.95518898
OS 29.35605254 -36.95380214
OS 29.3824025 -36.95102846
OS 29.41152614 -36.9454811
OS 29.44064978 -36.93716006
OS 29.46699974 -36.92606534
OS 29.4794813 -36.91913114
OS 29.48918918 -36.9108101
OS 29.49196286 -36.90803642
OS 29.49751022 -36.90248906
OS 29.50583126 -36.89139434
OS 29.51553914 -36.87752594
OS 29.52524702 -36.85949702
OS 29.53356806 -36.83730758
OS 29.53911542 -36.81234446
OS 29.5418891 -36.78322082
OS 29.5418891 -36.78183398
OS 29.5418891 -36.78044714
OS 29.5418891 -36.77351294
OS 29.54050226 -36.76103138
OS 29.53772858 -36.74716298
OS 29.5349549 -36.73190774
OS 29.52940754 -36.71387882
OS 29.5210865 -36.69723674
OS 29.51137862 -36.68059466
OS 29.50999178 -36.67920782
OS 29.50583126 -36.67366046
OS 29.49889706 -36.66672626
OS 29.49057602 -36.65701838
OS 29.47809446 -36.6473105
OS 29.46422606 -36.63898946
OS 29.44897082 -36.63066842
OS 29.4309419 -36.62373422
OS 29.42955506 -36.62373422
OS 29.4240077 -36.62234738
OS 29.41568666 -36.62096054
OS 29.40459194 -36.61818686
OS 29.38794986 -36.61680002
OS 29.36714726 -36.61541318
OS 29.34218414 -36.61402634
OE
OB 30.16180658 -36.60015794 H
OS 30.16180658 -36.60154478
OS 30.16041974 -36.60431846
OS 30.16041974 -36.60986582
OS 30.15764606 -36.61541318
OS 30.15625922 -36.62512106
OS 30.15348554 -36.63482894
OS 30.14793818 -36.65840522
OS 30.14100398 -36.68614202
OS 30.1312961 -36.7166525
OS 30.12158822 -36.74993666
OS 30.10910666 -36.78460766
OS 30.00509366 -37.06474934
OS 30.32961422 -37.06474934
OS 30.22976174 -36.80124974
OS 30.22976174 -36.7998629
OS 30.2283749 -36.79570238
OS 30.22560122 -36.78876818
OS 30.22282754 -36.78044714
OS 30.21866702 -36.77073926
OS 30.2145065 -36.7582577
OS 30.21034598 -36.7443893
OS 30.20479862 -36.7305209
OS 30.1937039 -36.69862358
OS 30.18260918 -36.66533942
OS 30.17151446 -36.63205526
OS 30.16180658 -36.60015794
OE
OB 31.16033138 -36.60709214 H
OS 30.85800026 -36.60709214
OS 30.85800026 -36.9246785
OS 31.1436893 -36.9246785
OS 31.16033138 -36.92329166
OS 31.17974714 -36.92190482
OS 31.20193658 -36.92051798
OS 31.22412602 -36.9177443
OS 31.24631546 -36.91358378
OS 31.26573122 -36.90803642
OS 31.2685049 -36.90664958
OS 31.27405226 -36.9038759
OS 31.2823733 -36.89971538
OS 31.29346802 -36.89416802
OS 31.30594958 -36.88584698
OS 31.31843114 -36.8761391
OS 31.3309127 -36.86365754
OS 31.34062058 -36.84978914
OS 31.34200742 -36.8484023
OS 31.3447811 -36.84285494
OS 31.34894162 -36.8345339
OS 31.35448898 -36.82343918
OS 31.3586495 -36.81095762
OS 31.36281002 -36.79708922
OS 31.3655837 -36.78044714
OS 31.36697054 -36.76380506
OS 31.36697054 -36.76241822
OS 31.36697054 -36.76103138
OS 31.3655837 -36.75271034
OS 31.36419686 -36.74022878
OS 31.36142318 -36.7235867
OS 31.35448898 -36.70694462
OS 31.34616794 -36.68752886
OS 31.33368638 -36.66949994
OS 31.3170443 -36.65147102
OS 31.31427062 -36.65008418
OS 31.30733642 -36.64453682
OS 31.2962417 -36.63760262
OS 31.27821278 -36.62928158
OS 31.25741018 -36.62096054
OS 31.22967338 -36.61402634
OS 31.19777606 -36.60847898
OS 31.16033138 -36.60709214
OE
OB 36.29302622 -36.61402634 H
OS 36.06558446 -36.61402634
OS 36.06558446 -36.90248906
OS 36.30134726 -36.90248906
OS 36.31937618 -36.90110222
OS 36.33879194 -36.89971538
OS 36.3582077 -36.89832854
OS 36.37762346 -36.89555486
OS 36.3928787 -36.89278118
OS 36.39565238 -36.89139434
OS 36.40119974 -36.8900075
OS 36.40952078 -36.88584698
OS 36.4206155 -36.88029962
OS 36.43171022 -36.87475226
OS 36.44419178 -36.86643122
OS 36.45667334 -36.8553365
OS 36.46638122 -36.84424178
OS 36.46776806 -36.84285494
OS 36.47054174 -36.83869442
OS 36.47470226 -36.83037338
OS 36.47886278 -36.8206655
OS 36.4830233 -36.80957078
OS 36.48718382 -36.79570238
OS 36.4899575 -36.7790603
OS 36.49134434 -36.76103138
OS 36.49134434 -36.7582577
OS 36.49134434 -36.75271034
OS 36.4899575 -36.7443893
OS 36.48857066 -36.73329458
OS 36.48579698 -36.71942618
OS 36.48163646 -36.70555778
OS 36.4760891 -36.69168938
OS 36.46776806 -36.67782098
OS 36.46638122 -36.67643414
OS 36.46360754 -36.67227362
OS 36.45806018 -36.66533942
OS 36.45112598 -36.65840522
OS 36.4414181 -36.65008418
OS 36.43032338 -36.64176314
OS 36.41645498 -36.6334421
OS 36.40119974 -36.62789474
OS 36.3998129 -36.62789474
OS 36.3928787 -36.62512106
OS 36.38317082 -36.62373422
OS 36.36791558 -36.62096054
OS 36.34711298 -36.61818686
OS 36.3235367 -36.61680002
OS 36.29302622 -36.61402634
OE
OB 36.31798934 -37.01620994 H
OS 36.06558446 -37.01620994
OS 36.06558446 -37.34627786
OS 36.33879194 -37.34627786
OS 36.36791558 -37.34489102
OS 36.38039714 -37.34350418
OS 36.39149186 -37.34211734
OS 36.3928787 -37.34211734
OS 36.39842606 -37.3407305
OS 36.4067471 -37.33934366
OS 36.41645498 -37.33656998
OS 36.44003126 -37.32824894
OS 36.46360754 -37.31715422
OS 36.46499438 -37.31576738
OS 36.4691549 -37.3129937
OS 36.47470226 -37.30883318
OS 36.48163646 -37.30328582
OS 36.48857066 -37.29496478
OS 36.49827854 -37.28664374
OS 36.50521274 -37.27554902
OS 36.51353378 -37.26306746
OS 36.51492062 -37.26168062
OS 36.51630746 -37.2575201
OS 36.51908114 -37.24919906
OS 36.52324166 -37.23949118
OS 36.52740218 -37.22839646
OS 36.53017586 -37.21452806
OS 36.5315627 -37.19788598
OS 36.53294954 -37.1812439
OS 36.53294954 -37.17847022
OS 36.53294954 -37.17292286
OS 36.5315627 -37.16182814
OS 36.52878902 -37.14934658
OS 36.52601534 -37.13547818
OS 36.52046798 -37.12022294
OS 36.51353378 -37.1049677
OS 36.5038259 -37.08971246
OS 36.50243906 -37.08832562
OS 36.49827854 -37.08277826
OS 36.49273118 -37.07584406
OS 36.48441014 -37.06752302
OS 36.47331542 -37.05781514
OS 36.45944702 -37.04810726
OS 36.44419178 -37.03978622
OS 36.42616286 -37.03285202
OS 36.42338918 -37.03146518
OS 36.41784182 -37.03007834
OS 36.40536026 -37.02730466
OS 36.39010502 -37.02453098
OS 36.37068926 -37.0217573
OS 36.34711298 -37.01898362
OS 36.31798934 -37.01620994
OE
SE
S P 0
OB 40.9056459 -38.32112732 I
OS 40.92136342 -38.32205188
OS 40.9380055 -38.32297644
OS 40.95372302 -38.32482556
OS 40.96759142 -38.32667468
OS 40.96944054 -38.32667468
OS 40.97591246 -38.3285238
OS 40.9842335 -38.33037292
OS 40.99532822 -38.3331466
OS 41.0073475 -38.3377694
OS 41.02029134 -38.34331676
OS 41.03415974 -38.34978868
OS 41.04617902 -38.35718516
OS 41.04802814 -38.35810972
OS 41.05172638 -38.3608834
OS 41.05727374 -38.36643076
OS 41.06467022 -38.37290268
OS 41.07299126 -38.38122372
OS 41.0813123 -38.39231844
OS 41.0905579 -38.40433772
OS 41.09795438 -38.41820612
OS 41.09887894 -38.42005524
OS 41.10072806 -38.42467804
OS 41.1044263 -38.43299908
OS 41.10812454 -38.4440938
OS 41.11089822 -38.45703764
OS 41.11459646 -38.4718306
OS 41.11644558 -38.48847268
OS 41.11737014 -38.50603932
OS 41.11737014 -38.50696388
OS 41.11737014 -38.50973756
OS 41.11737014 -38.5134358
OS 41.11644558 -38.51990772
OS 41.11552102 -38.52637964
OS 41.11459646 -38.53470068
OS 41.11274734 -38.54394628
OS 41.11089822 -38.55411644
OS 41.1044263 -38.57538132
OS 41.10072806 -38.58647604
OS 41.0951807 -38.59849532
OS 41.08870878 -38.6105146
OS 41.08223686 -38.62160932
OS 41.07391582 -38.63270404
OS 41.06467022 -38.64379876
OS 41.06374566 -38.64472332
OS 41.06189654 -38.64657244
OS 41.05912286 -38.64934612
OS 41.05450006 -38.6521198
OS 41.0489527 -38.6567426
OS 41.04155622 -38.6613654
OS 41.03231062 -38.66691276
OS 41.02214046 -38.67153556
OS 41.01012118 -38.67708292
OS 40.99625278 -38.68263028
OS 40.98145982 -38.68725308
OS 40.96389318 -38.69095132
OS 40.94540198 -38.69464956
OS 40.92506166 -38.69742324
OS 40.90194766 -38.69927236
OS 40.8779091 -38.70019692
OS 40.71426198 -38.70019692
OS 40.71426198 -38.95999828
OS 40.62920246 -38.95999828
OS 40.62920246 -38.32020276
OS 40.8917775 -38.32020276
OS 40.9056459 -38.32112732
OE
OB 40.49791494 -38.98403684 I
OS 40.49791494 -38.9849614
OS 40.49791494 -38.98773508
OS 40.49791494 -38.99235788
OS 40.49791494 -38.99790524
OS 40.49699038 -39.00530172
OS 40.49699038 -39.0126982
OS 40.49514126 -39.0311894
OS 40.49236758 -39.05060516
OS 40.48866934 -39.07094548
OS 40.48312198 -39.08851212
OS 40.47942374 -39.09683316
OS 40.4757255 -39.10330508
OS 40.4757255 -39.10422964
OS 40.47480094 -39.1051542
OS 40.47017814 -39.109777
OS 40.46278166 -39.11717348
OS 40.45353606 -39.12549452
OS 40.44059222 -39.13381556
OS 40.42395014 -39.14028748
OS 40.40453438 -39.14583484
OS 40.39343966 -39.1467594
OS 40.38142038 -39.14768396
OS 40.37587302 -39.14768396
OS 40.37032566 -39.1467594
OS 40.36200462 -39.1467594
OS 40.35275902 -39.14583484
OS 40.34258886 -39.14398572
OS 40.32039942 -39.13843836
OS 40.33519238 -39.07187004
OS 40.33611694 -39.07187004
OS 40.33889062 -39.0727946
OS 40.34351342 -39.07371916
OS 40.34813622 -39.07464372
OS 40.3601555 -39.0774174
OS 40.36570286 -39.07834196
OS 40.37494846 -39.07834196
OS 40.37957126 -39.0774174
OS 40.38511862 -39.07649284
OS 40.39066598 -39.07464372
OS 40.39621334 -39.07094548
OS 40.40268526 -39.06724724
OS 40.40730806 -39.06169988
OS 40.40823262 -39.06077532
OS 40.40915718 -39.05800164
OS 40.4110063 -39.05337884
OS 40.41377998 -39.04598236
OS 40.4156291 -39.0358122
OS 40.41655366 -39.02841572
OS 40.41747822 -39.0219438
OS 40.41840278 -39.01362276
OS 40.41840278 -39.0034526
OS 40.41932734 -38.99328244
OS 40.41932734 -38.98218772
OS 40.41932734 -38.49586916
OS 40.49791494 -38.49586916
OS 40.49791494 -38.98403684
OE
OB 41.51770462 -38.3100326 I
OS 41.52602566 -38.31095716
OS 41.53619582 -38.31188172
OS 41.54636598 -38.31280628
OS 41.55838526 -38.31557996
OS 41.58334838 -38.32112732
OS 41.61108518 -38.32944836
OS 41.62495358 -38.33499572
OS 41.63789742 -38.34146764
OS 41.65084126 -38.34978868
OS 41.6637851 -38.35810972
OS 41.66470966 -38.35903428
OS 41.66655878 -38.35995884
OS 41.67025702 -38.36273252
OS 41.67487982 -38.36735532
OS 41.67950262 -38.37197812
OS 41.68597454 -38.37845004
OS 41.69244646 -38.38584652
OS 41.69984294 -38.393243
OS 41.70723942 -38.4024886
OS 41.7146359 -38.41358332
OS 41.72295694 -38.42467804
OS 41.73035342 -38.43669732
OS 41.73682534 -38.45056572
OS 41.74422182 -38.46443412
OS 41.74976918 -38.47922708
OS 41.75531654 -38.49586916
OS 41.67210614 -38.51528492
OS 41.67210614 -38.51436036
OS 41.67118158 -38.51251124
OS 41.66933246 -38.508813
OS 41.66748334 -38.5041902
OS 41.66563422 -38.49864284
OS 41.66286054 -38.49124636
OS 41.65546406 -38.4764534
OS 41.64621846 -38.45981132
OS 41.63512374 -38.44316924
OS 41.62125534 -38.42745172
OS 41.60646238 -38.41358332
OS 41.60461326 -38.4117342
OS 41.5990659 -38.40803596
OS 41.5898203 -38.40341316
OS 41.57780102 -38.39694124
OS 41.5620835 -38.39139388
OS 41.54451686 -38.38584652
OS 41.52325198 -38.38214828
OS 41.50013798 -38.38122372
OS 41.4927415 -38.38122372
OS 41.4881187 -38.38214828
OS 41.48164678 -38.38214828
OS 41.4742503 -38.38307284
OS 41.45668366 -38.38584652
OS 41.4372679 -38.38954476
OS 41.41692758 -38.39601668
OS 41.3956627 -38.40526228
OS 41.37624694 -38.41728156
OS 41.37532238 -38.41728156
OS 41.37439782 -38.41913068
OS 41.3679259 -38.42375348
OS 41.35960486 -38.43114996
OS 41.3494347 -38.44224468
OS 41.33741542 -38.45611308
OS 41.3263207 -38.4718306
OS 41.31615054 -38.49124636
OS 41.30690494 -38.51251124
OS 41.30690494 -38.5134358
OS 41.30598038 -38.51528492
OS 41.30505582 -38.5180586
OS 41.30413126 -38.5226814
OS 41.30228214 -38.52822876
OS 41.30043302 -38.53470068
OS 41.29765934 -38.5504182
OS 41.2939611 -38.5689094
OS 41.29026286 -38.58924972
OS 41.28841374 -38.61143916
OS 41.28748918 -38.63547772
OS 41.28748918 -38.63640228
OS 41.28748918 -38.63917596
OS 41.28748918 -38.64379876
OS 41.28748918 -38.64934612
OS 41.28841374 -38.65581804
OS 41.28841374 -38.66413908
OS 41.2893383 -38.67338468
OS 41.29026286 -38.68355484
OS 41.29303654 -38.70574428
OS 41.29765934 -38.72978284
OS 41.3032067 -38.7538214
OS 41.31060318 -38.77785996
OS 41.31060318 -38.77878452
OS 41.31152774 -38.78063364
OS 41.31337686 -38.78340732
OS 41.31522598 -38.78803012
OS 41.32077334 -38.79912484
OS 41.32909438 -38.81206868
OS 41.33926454 -38.82686164
OS 41.35220838 -38.84257916
OS 41.36700134 -38.85644756
OS 41.38456798 -38.8693914
OS 41.38549254 -38.8693914
OS 41.38734166 -38.87031596
OS 41.39011534 -38.87216508
OS 41.39381358 -38.8740142
OS 41.39843638 -38.87586332
OS 41.40398374 -38.878637
OS 41.41692758 -38.88418436
OS 41.43356966 -38.88973172
OS 41.45206086 -38.89435452
OS 41.47240118 -38.89805276
OS 41.49366606 -38.89897732
OS 41.50013798 -38.89897732
OS 41.50568534 -38.89805276
OS 41.51215726 -38.89805276
OS 41.51862918 -38.8971282
OS 41.53527126 -38.89342996
OS 41.55468702 -38.88880716
OS 41.57410278 -38.88141068
OS 41.5944431 -38.87124052
OS 41.60461326 -38.86569316
OS 41.61385886 -38.85829668
OS 41.61478342 -38.85737212
OS 41.61570798 -38.85644756
OS 41.61848166 -38.85367388
OS 41.6221799 -38.8509002
OS 41.62587814 -38.8462774
OS 41.63050094 -38.84073004
OS 41.6360483 -38.83518268
OS 41.6406711 -38.8277862
OS 41.64621846 -38.81946516
OS 41.65269038 -38.81021956
OS 41.65823774 -38.80097396
OS 41.6637851 -38.78987924
OS 41.6684079 -38.77785996
OS 41.6730307 -38.76491612
OS 41.6776535 -38.75104772
OS 41.68135174 -38.73625476
OS 41.76641126 -38.75751964
OS 41.76641126 -38.7584442
OS 41.7654867 -38.76214244
OS 41.76363758 -38.7676898
OS 41.7608639 -38.77508628
OS 41.75809022 -38.78340732
OS 41.75439198 -38.79357748
OS 41.74976918 -38.8046722
OS 41.74422182 -38.81669148
OS 41.73127798 -38.84257916
OS 41.7146359 -38.86846684
OS 41.70446574 -38.88141068
OS 41.69429558 -38.89435452
OS 41.68320086 -38.90544924
OS 41.67025702 -38.91654396
OS 41.66933246 -38.91746852
OS 41.66748334 -38.91931764
OS 41.66286054 -38.92116676
OS 41.65823774 -38.924865
OS 41.65084126 -38.9294878
OS 41.64344478 -38.9341106
OS 41.63327462 -38.9387334
OS 41.62310446 -38.9433562
OS 41.61108518 -38.94890356
OS 41.59814134 -38.95352636
OS 41.58427294 -38.95814916
OS 41.56947998 -38.96277196
OS 41.55376246 -38.9664702
OS 41.53712038 -38.96831932
OS 41.51955374 -38.97016844
OS 41.50106254 -38.971093
OS 41.49089238 -38.971093
OS 41.4834959 -38.97016844
OS 41.47517486 -38.97016844
OS 41.4650047 -38.96924388
OS 41.45390998 -38.96739476
OS 41.44096614 -38.96554564
OS 41.4141539 -38.96092284
OS 41.3864171 -38.95352636
OS 41.3586803 -38.9433562
OS 41.34573646 -38.93688428
OS 41.33279262 -38.9294878
OS 41.33186806 -38.92856324
OS 41.33001894 -38.92763868
OS 41.3263207 -38.924865
OS 41.32262246 -38.92116676
OS 41.3170751 -38.91746852
OS 41.31060318 -38.91192116
OS 41.3032067 -38.90544924
OS 41.29581022 -38.89805276
OS 41.28841374 -38.88973172
OS 41.2800927 -38.88141068
OS 41.26345062 -38.8601458
OS 41.2477331 -38.83518268
OS 41.2338647 -38.80744588
OS 41.2338647 -38.80652132
OS 41.23201558 -38.80374764
OS 41.23109102 -38.79912484
OS 41.22831734 -38.79357748
OS 41.22646822 -38.786181
OS 41.22369454 -38.7769354
OS 41.2199963 -38.76676524
OS 41.21722262 -38.75567052
OS 41.21444894 -38.74365124
OS 41.2107507 -38.72978284
OS 41.2061279 -38.70112148
OS 41.20242966 -38.66876188
OS 41.20058054 -38.63547772
OS 41.20058054 -38.63455316
OS 41.20058054 -38.63085492
OS 41.20058054 -38.62530756
OS 41.2015051 -38.61883564
OS 41.2015051 -38.60959004
OS 41.20242966 -38.60034444
OS 41.20335422 -38.58832516
OS 41.20520334 -38.57630588
OS 41.20982614 -38.54949364
OS 41.21629806 -38.51990772
OS 41.22554366 -38.4903218
OS 41.2384875 -38.46166044
OS 41.23941206 -38.46073588
OS 41.24033662 -38.4579622
OS 41.24218574 -38.45426396
OS 41.24588398 -38.44964116
OS 41.24958222 -38.44316924
OS 41.25420502 -38.43577276
OS 41.2662243 -38.41913068
OS 41.28194182 -38.40063948
OS 41.30043302 -38.38214828
OS 41.3216979 -38.36365708
OS 41.34666102 -38.34793956
OS 41.34758558 -38.347015
OS 41.35035926 -38.34609044
OS 41.3540575 -38.34424132
OS 41.3586803 -38.34146764
OS 41.36607678 -38.33869396
OS 41.37347326 -38.33592028
OS 41.38271886 -38.33222204
OS 41.39288902 -38.3285238
OS 41.40398374 -38.32482556
OS 41.41600302 -38.32112732
OS 41.4418907 -38.31557996
OS 41.47147662 -38.31095716
OS 41.5019871 -38.30910804
OS 41.5112327 -38.30910804
OS 41.51770462 -38.3100326
OE
OB 42.90454462 -39.1375138 I
OS 42.38401734 -39.1375138
OS 42.38401734 -39.08111564
OS 42.90454462 -39.08111564
OS 42.90454462 -39.1375138
OE
OB 42.12514054 -38.32112732 I
OS 42.13253702 -38.32112732
OS 42.1491791 -38.32297644
OS 42.1676703 -38.32482556
OS 42.18708606 -38.3285238
OS 42.20650182 -38.3331466
OS 42.22406846 -38.33961852
OS 42.22499302 -38.33961852
OS 42.22591758 -38.34054308
OS 42.23146494 -38.34331676
OS 42.23978598 -38.34793956
OS 42.24903158 -38.35441148
OS 42.2601263 -38.36273252
OS 42.27214558 -38.37290268
OS 42.2832403 -38.38584652
OS 42.29341046 -38.39971492
OS 42.29433502 -38.40156404
OS 42.2971087 -38.4071114
OS 42.3017315 -38.41450788
OS 42.3063543 -38.4256026
OS 42.3109771 -38.43854644
OS 42.3155999 -38.45241484
OS 42.31837358 -38.46813236
OS 42.31929814 -38.48384988
OS 42.31929814 -38.485699
OS 42.31929814 -38.4903218
OS 42.31837358 -38.49864284
OS 42.31652446 -38.508813
OS 42.31375078 -38.52083228
OS 42.30912798 -38.53377612
OS 42.30358062 -38.54671996
OS 42.29618414 -38.56058836
OS 42.29525958 -38.56243748
OS 42.2924859 -38.56613572
OS 42.28693854 -38.5735322
OS 42.27954206 -38.58092868
OS 42.27029646 -38.59017428
OS 42.25920174 -38.60034444
OS 42.24533334 -38.60959004
OS 42.22961582 -38.61883564
OS 42.23054038 -38.61883564
OS 42.2323895 -38.6197602
OS 42.23516318 -38.62068476
OS 42.23886142 -38.62253388
OS 42.24995614 -38.62623212
OS 42.26289998 -38.63270404
OS 42.27676838 -38.64102508
OS 42.2924859 -38.65119524
OS 42.3063543 -38.66321452
OS 42.31929814 -38.67800748
OS 42.3202227 -38.6798566
OS 42.32392094 -38.68540396
OS 42.3294683 -38.693725
OS 42.33501566 -38.70481972
OS 42.34056302 -38.71961268
OS 42.34611038 -38.7353302
OS 42.34980862 -38.7538214
OS 42.35073318 -38.77416172
OS 42.35073318 -38.77508628
OS 42.35073318 -38.77601084
OS 42.35073318 -38.7815582
OS 42.34980862 -38.7908038
OS 42.3479595 -38.80189852
OS 42.34611038 -38.81484236
OS 42.34241214 -38.82871076
OS 42.33778934 -38.84350372
OS 42.33131742 -38.85829668
OS 42.33039286 -38.8601458
OS 42.32761918 -38.8647686
OS 42.32392094 -38.87124052
OS 42.31837358 -38.88048612
OS 42.3109771 -38.88973172
OS 42.30358062 -38.89990188
OS 42.29433502 -38.91007204
OS 42.28416486 -38.91839308
OS 42.2832403 -38.91931764
OS 42.27954206 -38.92209132
OS 42.27307014 -38.92578956
OS 42.2647491 -38.9294878
OS 42.25457894 -38.93503516
OS 42.24255966 -38.94058252
OS 42.22961582 -38.94520532
OS 42.2138983 -38.94982812
OS 42.21204918 -38.94982812
OS 42.20650182 -38.95167724
OS 42.19725622 -38.9526018
OS 42.18523694 -38.95445092
OS 42.17044398 -38.95630004
OS 42.15287734 -38.95814916
OS 42.13346158 -38.95907372
OS 42.11127214 -38.95999828
OS 41.8671883 -38.95999828
OS 41.8671883 -38.32020276
OS 42.11866862 -38.32020276
OS 42.12514054 -38.32112732
OE
OB 40.30745558 -38.48662356 I
OS 40.31762574 -38.48847268
OS 40.32964502 -38.49217092
OS 40.34258886 -38.49679372
OS 40.35738182 -38.50326564
OS 40.37309934 -38.51158668
OS 40.34443798 -38.58370236
OS 40.34351342 -38.5827778
OS 40.33981518 -38.58092868
OS 40.33426782 -38.578155
OS 40.32687134 -38.57538132
OS 40.3185503 -38.57260764
OS 40.30838014 -38.56983396
OS 40.29820998 -38.56798484
OS 40.28803982 -38.56706028
OS 40.28341702 -38.56706028
OS 40.27879422 -38.56798484
OS 40.2723223 -38.5689094
OS 40.26585038 -38.57075852
OS 40.25752934 -38.5735322
OS 40.2492083 -38.57723044
OS 40.24181182 -38.5827778
OS 40.24088726 -38.58370236
OS 40.23811358 -38.58555148
OS 40.2353399 -38.58924972
OS 40.2307171 -38.59387252
OS 40.2260943 -38.60034444
OS 40.2214715 -38.60774092
OS 40.2168487 -38.61606196
OS 40.21315046 -38.62623212
OS 40.2122259 -38.62808124
OS 40.21130134 -38.6336286
OS 40.20945222 -38.64194964
OS 40.20667854 -38.65304436
OS 40.20390486 -38.66691276
OS 40.20205574 -38.68263028
OS 40.20113118 -38.69927236
OS 40.20020662 -38.71776356
OS 40.20020662 -38.95999828
OS 40.12161902 -38.95999828
OS 40.12161902 -38.49586916
OS 40.19281014 -38.49586916
OS 40.19281014 -38.56613572
OS 40.1937347 -38.56521116
OS 40.19743294 -38.55873924
OS 40.20205574 -38.5504182
OS 40.20945222 -38.54024804
OS 40.2168487 -38.53007788
OS 40.22516974 -38.51898316
OS 40.23349078 -38.50973756
OS 40.24181182 -38.50234108
OS 40.24273638 -38.50141652
OS 40.24551006 -38.4995674
OS 40.25105742 -38.49679372
OS 40.25660478 -38.49402004
OS 40.26400126 -38.49124636
OS 40.27324686 -38.48847268
OS 40.28249246 -38.48662356
OS 40.29266262 -38.485699
OS 40.29913454 -38.485699
OS 40.30745558 -38.48662356
OE
OB 39.48829542 -38.95999828 I
OS 39.3986131 -38.95999828
OS 39.3986131 -38.87031596
OS 39.48829542 -38.87031596
OS 39.48829542 -38.95999828
OE
OB 38.6404739 -38.95999828 I
OS 38.55171614 -38.95999828
OS 38.30393406 -38.32020276
OS 38.39639006 -38.32020276
OS 38.56281086 -38.78525644
OS 38.56281086 -38.786181
OS 38.56373542 -38.78803012
OS 38.56465998 -38.7908038
OS 38.5665091 -38.79450204
OS 38.56743366 -38.8000494
OS 38.56928278 -38.80559676
OS 38.57390558 -38.81946516
OS 38.57945294 -38.83518268
OS 38.5850003 -38.85274932
OS 38.59609502 -38.88973172
OS 38.59609502 -38.88880716
OS 38.59701958 -38.88695804
OS 38.59794414 -38.88418436
OS 38.5988687 -38.88048612
OS 38.60164238 -38.87031596
OS 38.60626518 -38.85644756
OS 38.61088798 -38.84073004
OS 38.61643534 -38.8231634
OS 38.62290726 -38.8046722
OS 38.63030374 -38.78525644
OS 38.80412102 -38.32020276
OS 38.8901051 -38.32020276
OS 38.6404739 -38.95999828
OE
OB 39.27564662 -38.42745172 I
OS 39.25438174 -38.54671996
OS 39.20538006 -38.54671996
OS 39.1859643 -38.42745172
OS 39.1859643 -38.32020276
OS 39.27564662 -38.32020276
OS 39.27564662 -38.42745172
OE
OB 40.49791494 -38.4117342 I
OS 40.41932734 -38.4117342
OS 40.41932734 -38.32020276
OS 40.49791494 -38.32020276
OS 40.49791494 -38.4117342
OE
OB 39.84517558 -38.48662356 I
OS 39.8516475 -38.48754812
OS 39.8655159 -38.48939724
OS 39.88215798 -38.49309548
OS 39.89972462 -38.49864284
OS 39.91729126 -38.50696388
OS 39.9348579 -38.51713404
OS 39.93578246 -38.51713404
OS 39.93670702 -38.51898316
OS 39.94225438 -38.5226814
OS 39.95057542 -38.53007788
OS 39.96074558 -38.53932348
OS 39.9718403 -38.55134276
OS 39.98293502 -38.56613572
OS 39.99402974 -38.58370236
OS 40.00327534 -38.60311812
OS 40.00327534 -38.60404268
OS 40.0041999 -38.6058918
OS 40.00512446 -38.60866548
OS 40.00697358 -38.61236372
OS 40.0088227 -38.61791108
OS 40.01067182 -38.624383
OS 40.01529462 -38.63917596
OS 40.01991742 -38.65766716
OS 40.02361566 -38.67800748
OS 40.02638934 -38.70112148
OS 40.0273139 -38.72516004
OS 40.0273139 -38.7260846
OS 40.0273139 -38.72793372
OS 40.0273139 -38.73163196
OS 40.0273139 -38.73717932
OS 40.02638934 -38.74365124
OS 40.02638934 -38.75104772
OS 40.02454022 -38.7676898
OS 40.02084198 -38.78803012
OS 40.01621918 -38.809295
OS 40.00974726 -38.83148444
OS 40.00142622 -38.85367388
OS 40.00142622 -38.85459844
OS 40.00050166 -38.85644756
OS 39.99865254 -38.85922124
OS 39.99680342 -38.86291948
OS 39.9903315 -38.87308964
OS 39.98201046 -38.88603348
OS 39.9718403 -38.89990188
OS 39.95889646 -38.91377028
OS 39.9441035 -38.92763868
OS 39.92653686 -38.94058252
OS 39.9256123 -38.94058252
OS 39.92468774 -38.94150708
OS 39.92191406 -38.9433562
OS 39.91821582 -38.94520532
OS 39.90897022 -38.94982812
OS 39.89602638 -38.95537548
OS 39.88030886 -38.96092284
OS 39.86366678 -38.96554564
OS 39.84425102 -38.96924388
OS 39.82483526 -38.97016844
OS 39.81836334 -38.97016844
OS 39.81096686 -38.96924388
OS 39.80172126 -38.96831932
OS 39.79062654 -38.9664702
OS 39.77860726 -38.96369652
OS 39.76658798 -38.95999828
OS 39.7545687 -38.95445092
OS 39.75364414 -38.95352636
OS 39.74902134 -38.95167724
OS 39.74347398 -38.947979
OS 39.7360775 -38.94243164
OS 39.72868102 -38.93688428
OS 39.71943542 -38.9294878
OS 39.71111438 -38.92116676
OS 39.7037179 -38.91192116
OS 39.7037179 -39.1375138
OS 39.6251303 -39.1375138
OS 39.6251303 -38.49586916
OS 39.69632142 -38.49586916
OS 39.69632142 -38.55689012
OS 39.69724598 -38.555041
OS 39.70094422 -38.55134276
OS 39.70556702 -38.54487084
OS 39.7129635 -38.53747436
OS 39.72128454 -38.52822876
OS 39.73053014 -38.51990772
OS 39.74162486 -38.51158668
OS 39.75271958 -38.5041902
OS 39.7545687 -38.50326564
OS 39.75826694 -38.50141652
OS 39.76566342 -38.49864284
OS 39.77490902 -38.4949446
OS 39.78600374 -38.49124636
OS 39.79894758 -38.48847268
OS 39.81374054 -38.48662356
OS 39.83038262 -38.485699
OS 39.84055278 -38.485699
OS 39.84517558 -38.48662356
OE
OB 44.92193454 -38.40988508 I
OS 44.84334694 -38.40988508
OS 44.84334694 -38.32020276
OS 44.92193454 -38.32020276
OS 44.92193454 -38.40988508
OE
OB 45.24553054 -38.48662356 I
OS 45.25385158 -38.48754812
OS 45.26309718 -38.48939724
OS 45.27326734 -38.49124636
OS 45.28528662 -38.49309548
OS 45.31024974 -38.50141652
OS 45.32319358 -38.50603932
OS 45.33613742 -38.51251124
OS 45.34908126 -38.51898316
OS 45.3620251 -38.52822876
OS 45.37404438 -38.53747436
OS 45.38606366 -38.54856908
OS 45.38698822 -38.54949364
OS 45.38883734 -38.55134276
OS 45.39161102 -38.555041
OS 45.39530926 -38.5596638
OS 45.39993206 -38.56613572
OS 45.40547942 -38.57445676
OS 45.41102678 -38.58370236
OS 45.41657414 -38.59387252
OS 45.4221215 -38.60496724
OS 45.42766886 -38.61883564
OS 45.43321622 -38.63270404
OS 45.43783902 -38.64842156
OS 45.44153726 -38.66506364
OS 45.44431094 -38.68263028
OS 45.44616006 -38.70112148
OS 45.44708462 -38.7214618
OS 45.44708462 -38.72238636
OS 45.44708462 -38.72516004
OS 45.44708462 -38.72978284
OS 45.44708462 -38.73625476
OS 45.44616006 -38.74365124
OS 45.4452355 -38.75289684
OS 45.4452355 -38.76214244
OS 45.44338638 -38.7723126
OS 45.4406127 -38.7954266
OS 45.43506534 -38.8185406
OS 45.42859342 -38.8416546
OS 45.41934782 -38.86291948
OS 45.41934782 -38.86384404
OS 45.41842326 -38.8647686
OS 45.41657414 -38.86754228
OS 45.41472502 -38.87124052
OS 45.4082531 -38.88048612
OS 45.39993206 -38.89158084
OS 45.38883734 -38.90452468
OS 45.37496894 -38.91746852
OS 45.35925142 -38.93041236
OS 45.34076022 -38.94243164
OS 45.33983566 -38.94243164
OS 45.3389111 -38.9433562
OS 45.33613742 -38.94520532
OS 45.33151462 -38.94705444
OS 45.32689182 -38.94890356
OS 45.32134446 -38.95075268
OS 45.30747606 -38.95630004
OS 45.29175854 -38.96092284
OS 45.27234278 -38.96554564
OS 45.25200246 -38.96924388
OS 45.22981302 -38.97016844
OS 45.22056742 -38.97016844
OS 45.21317094 -38.96924388
OS 45.2048499 -38.96831932
OS 45.1956043 -38.9664702
OS 45.18450958 -38.96462108
OS 45.17341486 -38.96277196
OS 45.14845174 -38.95537548
OS 45.13458334 -38.94982812
OS 45.1216395 -38.94428076
OS 45.10869566 -38.93688428
OS 45.09575182 -38.92856324
OS 45.08373254 -38.91931764
OS 45.07171326 -38.90822292
OS 45.0707887 -38.90729836
OS 45.06893958 -38.90544924
OS 45.0661659 -38.901751
OS 45.06246766 -38.89620364
OS 45.05784486 -38.88973172
OS 45.05322206 -38.88233524
OS 45.0476747 -38.87308964
OS 45.04212734 -38.86199492
OS 45.03657998 -38.84997564
OS 45.03103262 -38.83610724
OS 45.02640982 -38.82131428
OS 45.02178702 -38.80559676
OS 45.01808878 -38.78803012
OS 45.0153151 -38.76953892
OS 45.01346598 -38.7491986
OS 45.01254142 -38.72793372
OS 45.01254142 -38.7260846
OS 45.01254142 -38.72238636
OS 45.01346598 -38.71591444
OS 45.01346598 -38.70666884
OS 45.01439054 -38.69649868
OS 45.01623966 -38.68355484
OS 45.01808878 -38.670611
OS 45.02178702 -38.65581804
OS 45.02548526 -38.64102508
OS 45.03010806 -38.62530756
OS 45.03565542 -38.60866548
OS 45.0430519 -38.59294796
OS 45.05044838 -38.578155
OS 45.06061854 -38.56336204
OS 45.0707887 -38.54949364
OS 45.08373254 -38.53747436
OS 45.0846571 -38.5365498
OS 45.08650622 -38.53562524
OS 45.09020446 -38.53285156
OS 45.09482726 -38.52915332
OS 45.10037462 -38.52545508
OS 45.1077711 -38.52083228
OS 45.11516758 -38.51620948
OS 45.12441318 -38.51158668
OS 45.13458334 -38.50696388
OS 45.14567806 -38.50234108
OS 45.17064118 -38.49402004
OS 45.19930254 -38.48754812
OS 45.2140955 -38.48662356
OS 45.22981302 -38.485699
OS 45.23905862 -38.485699
OS 45.24553054 -38.48662356
OE
OB 44.92193454 -38.95999828 I
OS 44.84334694 -38.95999828
OS 44.84334694 -38.49586916
OS 44.92193454 -38.49586916
OS 44.92193454 -38.95999828
OE
OB 46.10722046 -38.42745172 I
OS 46.08595558 -38.54671996
OS 46.0369539 -38.54671996
OS 46.01753814 -38.42745172
OS 46.01753814 -38.32020276
OS 46.10722046 -38.32020276
OS 46.10722046 -38.42745172
OE
OB 45.77160518 -38.48662356 I
OS 45.78177534 -38.48754812
OS 45.79379462 -38.48939724
OS 45.80673846 -38.49217092
OS 45.82060686 -38.49586916
OS 45.8335507 -38.50141652
OS 45.83539982 -38.50234108
OS 45.83909806 -38.5041902
OS 45.84556998 -38.50696388
OS 45.85296646 -38.51158668
OS 45.86221206 -38.51713404
OS 45.8705331 -38.52453052
OS 45.87885414 -38.531927
OS 45.88625062 -38.5411726
OS 45.88717518 -38.54209716
OS 45.8890243 -38.5457954
OS 45.89179798 -38.5504182
OS 45.89642078 -38.55689012
OS 45.90011902 -38.56613572
OS 45.90381726 -38.57538132
OS 45.90844006 -38.58647604
OS 45.91121374 -38.59849532
OS 45.91121374 -38.59941988
OS 45.9121383 -38.60311812
OS 45.91306286 -38.60866548
OS 45.91398742 -38.61606196
OS 45.91398742 -38.62715668
OS 45.91491198 -38.64010052
OS 45.91583654 -38.65581804
OS 45.91583654 -38.6752338
OS 45.91583654 -38.95999828
OS 45.83724894 -38.95999828
OS 45.83724894 -38.67893204
OS 45.83724894 -38.67800748
OS 45.83724894 -38.67708292
OS 45.83724894 -38.670611
OS 45.83724894 -38.66228996
OS 45.83632438 -38.6521198
OS 45.83539982 -38.64010052
OS 45.8335507 -38.62808124
OS 45.83077702 -38.61698652
OS 45.82800334 -38.60681636
OS 45.82800334 -38.6058918
OS 45.82615422 -38.60311812
OS 45.82338054 -38.59849532
OS 45.82060686 -38.59294796
OS 45.81598406 -38.5874006
OS 45.8104367 -38.58092868
OS 45.80304022 -38.57445676
OS 45.79471918 -38.5689094
OS 45.79379462 -38.56798484
OS 45.79102094 -38.56613572
OS 45.78547358 -38.5642866
OS 45.77900166 -38.56151292
OS 45.77160518 -38.55873924
OS 45.76235958 -38.55596556
OS 45.75126486 -38.555041
OS 45.74017014 -38.55411644
OS 45.73554734 -38.55411644
OS 45.7318491 -38.555041
OS 45.7226035 -38.55596556
OS 45.71058422 -38.55781468
OS 45.69764038 -38.56243748
OS 45.68284742 -38.56798484
OS 45.66805446 -38.57538132
OS 45.65418606 -38.58647604
OS 45.65233694 -38.58832516
OS 45.6486387 -38.59294796
OS 45.64586502 -38.5966462
OS 45.64309134 -38.601269
OS 45.6393931 -38.60681636
OS 45.63661942 -38.61328828
OS 45.63292118 -38.62068476
OS 45.62922294 -38.62993036
OS 45.62644926 -38.64010052
OS 45.62367558 -38.65119524
OS 45.62182646 -38.66321452
OS 45.61997734 -38.67615836
OS 45.61812822 -38.69187588
OS 45.61812822 -38.7075934
OS 45.61812822 -38.95999828
OS 45.53954062 -38.95999828
OS 45.53954062 -38.49586916
OS 45.60980718 -38.49586916
OS 45.60980718 -38.56243748
OS 45.61073174 -38.56151292
OS 45.61258086 -38.55873924
OS 45.61535454 -38.555041
OS 45.61905278 -38.5504182
OS 45.62460014 -38.54487084
OS 45.63107206 -38.53839892
OS 45.63846854 -38.53100244
OS 45.64771414 -38.52360596
OS 45.65695974 -38.51713404
OS 45.66805446 -38.50973756
OS 45.68007374 -38.50326564
OS 45.69301758 -38.49771828
OS 45.70781054 -38.49309548
OS 45.7226035 -38.48939724
OS 45.73924558 -38.48662356
OS 45.75681222 -38.485699
OS 45.7642087 -38.485699
OS 45.77160518 -38.48662356
OE
OB 44.2756671 -38.95999828 I
OS 44.1970795 -38.95999828
OS 44.1970795 -38.49586916
OS 44.2756671 -38.49586916
OS 44.2756671 -38.95999828
OE
OB 43.4574315 -38.48662356 I
OS 43.46482798 -38.48754812
OS 43.47407358 -38.48939724
OS 43.48424374 -38.49124636
OS 43.49626302 -38.49402004
OS 43.50735774 -38.49679372
OS 43.52030158 -38.50141652
OS 43.53232086 -38.50603932
OS 43.5452647 -38.51251124
OS 43.55820854 -38.51990772
OS 43.57115238 -38.52822876
OS 43.58317166 -38.53839892
OS 43.59426638 -38.54949364
OS 43.59519094 -38.5504182
OS 43.59704006 -38.55226732
OS 43.59981374 -38.55596556
OS 43.60351198 -38.56151292
OS 43.60813478 -38.56798484
OS 43.61275758 -38.57538132
OS 43.61830494 -38.58462692
OS 43.6238523 -38.59572164
OS 43.62939966 -38.60774092
OS 43.63494702 -38.62068476
OS 43.63956982 -38.63547772
OS 43.64419262 -38.65119524
OS 43.64789086 -38.66876188
OS 43.65066454 -38.68725308
OS 43.65251366 -38.70666884
OS 43.65343822 -38.72793372
OS 43.65343822 -38.72885828
OS 43.65343822 -38.73255652
OS 43.65343822 -38.73902844
OS 43.65251366 -38.74827404
OS 43.30580366 -38.74827404
OS 43.30580366 -38.7491986
OS 43.30580366 -38.75197228
OS 43.30672822 -38.75567052
OS 43.30672822 -38.76121788
OS 43.30765278 -38.7676898
OS 43.3095019 -38.77508628
OS 43.31227558 -38.79172836
OS 43.31782294 -38.81021956
OS 43.32521942 -38.83055988
OS 43.33538958 -38.84905108
OS 43.34833342 -38.86569316
OS 43.34925798 -38.86569316
OS 43.35018254 -38.86754228
OS 43.3557299 -38.87216508
OS 43.36405094 -38.878637
OS 43.37514566 -38.88510892
OS 43.38993862 -38.8925054
OS 43.4065807 -38.89897732
OS 43.4250719 -38.90360012
OS 43.43524206 -38.90452468
OS 43.44633678 -38.90544924
OS 43.45373326 -38.90544924
OS 43.4620543 -38.90452468
OS 43.47222446 -38.90267556
OS 43.48331918 -38.89990188
OS 43.49626302 -38.89620364
OS 43.5082823 -38.89065628
OS 43.52030158 -38.8832598
OS 43.52122614 -38.88233524
OS 43.52584894 -38.878637
OS 43.5313963 -38.87308964
OS 43.53786822 -38.86569316
OS 43.5452647 -38.855523
OS 43.55358574 -38.84257916
OS 43.56190678 -38.8277862
OS 43.56930326 -38.81021956
OS 43.65066454 -38.82038972
OS 43.65066454 -38.82131428
OS 43.64973998 -38.8231634
OS 43.64881542 -38.82686164
OS 43.6469663 -38.832409
OS 43.64419262 -38.83795636
OS 43.64141894 -38.84535284
OS 43.63402246 -38.86107036
OS 43.62477686 -38.878637
OS 43.61183302 -38.8971282
OS 43.59704006 -38.91469484
OS 43.57854886 -38.93133692
OS 43.5776243 -38.93133692
OS 43.57577518 -38.93318604
OS 43.5730015 -38.93503516
OS 43.56930326 -38.93780884
OS 43.5637559 -38.94058252
OS 43.55820854 -38.9433562
OS 43.55081206 -38.94705444
OS 43.54249102 -38.95075268
OS 43.53324542 -38.95445092
OS 43.52399982 -38.95814916
OS 43.50088582 -38.96369652
OS 43.47499814 -38.96831932
OS 43.44633678 -38.97016844
OS 43.43616662 -38.97016844
OS 43.4296947 -38.96924388
OS 43.42137366 -38.96831932
OS 43.4112035 -38.9664702
OS 43.40010878 -38.96462108
OS 43.3880895 -38.96277196
OS 43.36220182 -38.95537548
OS 43.34833342 -38.94982812
OS 43.33538958 -38.94428076
OS 43.32152118 -38.93688428
OS 43.30857734 -38.92856324
OS 43.29655806 -38.91931764
OS 43.28453878 -38.90822292
OS 43.28361422 -38.90729836
OS 43.2817651 -38.90544924
OS 43.27899142 -38.901751
OS 43.27529318 -38.89620364
OS 43.27067038 -38.88973172
OS 43.26604758 -38.88233524
OS 43.26050022 -38.87308964
OS 43.25495286 -38.86291948
OS 43.2494055 -38.8509002
OS 43.24385814 -38.83795636
OS 43.23923534 -38.8231634
OS 43.23461254 -38.80744588
OS 43.2309143 -38.7908038
OS 43.22814062 -38.7723126
OS 43.2262915 -38.75289684
OS 43.22536694 -38.73255652
OS 43.22536694 -38.73163196
OS 43.22536694 -38.72700916
OS 43.22536694 -38.7214618
OS 43.2262915 -38.71314076
OS 43.22721606 -38.7029706
OS 43.22814062 -38.69187588
OS 43.22998974 -38.67893204
OS 43.23276342 -38.6659882
OS 43.2401599 -38.63640228
OS 43.2447827 -38.62160932
OS 43.25033006 -38.6058918
OS 43.25772654 -38.59109884
OS 43.26604758 -38.57723044
OS 43.27529318 -38.56336204
OS 43.28546334 -38.5504182
OS 43.2863879 -38.54949364
OS 43.28823702 -38.54764452
OS 43.29193526 -38.54487084
OS 43.29655806 -38.54024804
OS 43.30210542 -38.53562524
OS 43.3095019 -38.53007788
OS 43.31782294 -38.52360596
OS 43.3279931 -38.5180586
OS 43.33816326 -38.51158668
OS 43.35018254 -38.50603932
OS 43.36312638 -38.50049196
OS 43.37699478 -38.49586916
OS 43.39178774 -38.49124636
OS 43.40750526 -38.48847268
OS 43.42414734 -38.48662356
OS 43.44171398 -38.485699
OS 43.45095958 -38.485699
OS 43.4574315 -38.48662356
OE
OB 43.13938286 -38.48662356 I
OS 43.14955302 -38.48847268
OS 43.1615723 -38.49217092
OS 43.17451614 -38.49679372
OS 43.1893091 -38.50326564
OS 43.20502662 -38.51158668
OS 43.17636526 -38.58370236
OS 43.1754407 -38.5827778
OS 43.17174246 -38.58092868
OS 43.1661951 -38.578155
OS 43.15879862 -38.57538132
OS 43.15047758 -38.57260764
OS 43.14030742 -38.56983396
OS 43.13013726 -38.56798484
OS 43.1199671 -38.56706028
OS 43.1153443 -38.56706028
OS 43.1107215 -38.56798484
OS 43.10424958 -38.5689094
OS 43.09777766 -38.57075852
OS 43.08945662 -38.5735322
OS 43.08113558 -38.57723044
OS 43.0737391 -38.5827778
OS 43.07281454 -38.58370236
OS 43.07004086 -38.58555148
OS 43.06726718 -38.58924972
OS 43.06264438 -38.59387252
OS 43.05802158 -38.60034444
OS 43.05339878 -38.60774092
OS 43.04877598 -38.61606196
OS 43.04507774 -38.62623212
OS 43.04415318 -38.62808124
OS 43.04322862 -38.6336286
OS 43.0413795 -38.64194964
OS 43.03860582 -38.65304436
OS 43.03583214 -38.66691276
OS 43.03398302 -38.68263028
OS 43.03305846 -38.69927236
OS 43.0321339 -38.71776356
OS 43.0321339 -38.95999828
OS 42.9535463 -38.95999828
OS 42.9535463 -38.49586916
OS 43.02473742 -38.49586916
OS 43.02473742 -38.56613572
OS 43.02566198 -38.56521116
OS 43.02936022 -38.55873924
OS 43.03398302 -38.5504182
OS 43.0413795 -38.54024804
OS 43.04877598 -38.53007788
OS 43.05709702 -38.51898316
OS 43.06541806 -38.50973756
OS 43.0737391 -38.50234108
OS 43.07466366 -38.50141652
OS 43.07743734 -38.4995674
OS 43.0829847 -38.49679372
OS 43.08853206 -38.49402004
OS 43.09592854 -38.49124636
OS 43.10517414 -38.48847268
OS 43.11441974 -38.48662356
OS 43.1245899 -38.485699
OS 43.13106182 -38.485699
OS 43.13938286 -38.48662356
OE
OB 43.95022198 -38.95999828 I
OS 43.87533262 -38.95999828
OS 43.70059078 -38.49586916
OS 43.78380118 -38.49586916
OS 43.88365366 -38.77416172
OS 43.88365366 -38.77508628
OS 43.88457822 -38.77601084
OS 43.88550278 -38.77878452
OS 43.88642734 -38.7815582
OS 43.88920102 -38.7908038
OS 43.89289926 -38.80282308
OS 43.89752206 -38.81669148
OS 43.90306942 -38.832409
OS 43.90769222 -38.84997564
OS 43.91323958 -38.86754228
OS 43.91416414 -38.86569316
OS 43.9150887 -38.86107036
OS 43.91786238 -38.85367388
OS 43.92063606 -38.84257916
OS 43.92525886 -38.83055988
OS 43.92988166 -38.81484236
OS 43.93635358 -38.79820028
OS 43.9428255 -38.77970908
OS 44.04545166 -38.49586916
OS 44.12681294 -38.49586916
OS 43.95022198 -38.95999828
OE
OB 44.2756671 -38.40988508 I
OS 44.1970795 -38.40988508
OS 44.1970795 -38.32020276
OS 44.2756671 -38.32020276
OS 44.2756671 -38.40988508
OE
OB 44.5669035 -38.48662356 I
OS 44.5807719 -38.48754812
OS 44.59556486 -38.48939724
OS 44.61128238 -38.49309548
OS 44.62792446 -38.49679372
OS 44.64364198 -38.50234108
OS 44.64456654 -38.50234108
OS 44.6454911 -38.50326564
OS 44.6501139 -38.50511476
OS 44.65751038 -38.508813
OS 44.66675598 -38.5134358
OS 44.67692614 -38.51990772
OS 44.6870963 -38.5273042
OS 44.6963419 -38.53562524
OS 44.70466294 -38.54487084
OS 44.7055875 -38.5457954
OS 44.70743662 -38.54949364
OS 44.71113486 -38.55596556
OS 44.71575766 -38.56336204
OS 44.72038046 -38.57445676
OS 44.72500326 -38.58647604
OS 44.7287015 -38.60034444
OS 44.73239974 -38.61606196
OS 44.65566126 -38.62623212
OS 44.65566126 -38.624383
OS 44.6547367 -38.62068476
OS 44.65288758 -38.61421284
OS 44.6501139 -38.6058918
OS 44.6454911 -38.59757076
OS 44.63994374 -38.58832516
OS 44.63347182 -38.57907956
OS 44.62422622 -38.57075852
OS 44.62330166 -38.56983396
OS 44.61960342 -38.56798484
OS 44.61405606 -38.5642866
OS 44.60573502 -38.56058836
OS 44.59648942 -38.55689012
OS 44.58447014 -38.55319188
OS 44.56967718 -38.55134276
OS 44.55395966 -38.5504182
OS 44.54471406 -38.5504182
OS 44.53546846 -38.55134276
OS 44.52344918 -38.55226732
OS 44.5114299 -38.555041
OS 44.49848606 -38.55781468
OS 44.48646678 -38.56243748
OS 44.47629662 -38.5689094
OS 44.47537206 -38.56983396
OS 44.47259838 -38.57168308
OS 44.46890014 -38.57538132
OS 44.4652019 -38.58092868
OS 44.4605791 -38.58647604
OS 44.45688086 -38.59387252
OS 44.45410718 -38.60219356
OS 44.45318262 -38.6105146
OS 44.45318262 -38.61143916
OS 44.45318262 -38.61328828
OS 44.45410718 -38.61606196
OS 44.45410718 -38.6197602
OS 44.45688086 -38.6290058
OS 44.46242822 -38.6382514
OS 44.46335278 -38.63917596
OS 44.46427734 -38.64010052
OS 44.46612646 -38.6428742
OS 44.4698247 -38.64564788
OS 44.47352294 -38.64842156
OS 44.4790703 -38.6521198
OS 44.48554222 -38.65489348
OS 44.4929387 -38.65859172
OS 44.49386326 -38.65859172
OS 44.49571238 -38.65951628
OS 44.49941062 -38.66044084
OS 44.50588254 -38.66321452
OS 44.51512814 -38.6659882
OS 44.52714742 -38.66876188
OS 44.5345439 -38.67153556
OS 44.54286494 -38.67338468
OS 44.55211054 -38.67615836
OS 44.5622807 -38.67893204
OS 44.56320526 -38.67893204
OS 44.56597894 -38.6798566
OS 44.57060174 -38.68078116
OS 44.5761491 -38.68263028
OS 44.58262102 -38.6844794
OS 44.59094206 -38.68632852
OS 44.6085087 -38.69187588
OS 44.62792446 -38.69742324
OS 44.64734022 -38.70389516
OS 44.66490686 -38.71036708
OS 44.67230334 -38.71314076
OS 44.67877526 -38.71591444
OS 44.68062438 -38.716839
OS 44.68432262 -38.71868812
OS 44.68986998 -38.7214618
OS 44.69819102 -38.7260846
OS 44.70651206 -38.73163196
OS 44.7148331 -38.73902844
OS 44.72315414 -38.74734948
OS 44.73055062 -38.75659508
OS 44.73147518 -38.75751964
OS 44.7333243 -38.76121788
OS 44.73702254 -38.76676524
OS 44.74072078 -38.77508628
OS 44.74349446 -38.78525644
OS 44.7471927 -38.79635116
OS 44.74904182 -38.809295
OS 44.74996638 -38.82408796
OS 44.74996638 -38.82593708
OS 44.74996638 -38.83055988
OS 44.74904182 -38.83795636
OS 44.7471927 -38.84812652
OS 44.74441902 -38.85922124
OS 44.73979622 -38.87124052
OS 44.73424886 -38.88510892
OS 44.72685238 -38.89805276
OS 44.72592782 -38.89990188
OS 44.72222958 -38.90360012
OS 44.71760678 -38.91007204
OS 44.7102103 -38.91746852
OS 44.70004014 -38.92578956
OS 44.68894542 -38.93503516
OS 44.67600158 -38.9433562
OS 44.66028406 -38.95167724
OS 44.6593595 -38.95167724
OS 44.65843494 -38.9526018
OS 44.65288758 -38.95445092
OS 44.64364198 -38.9572246
OS 44.6316227 -38.96092284
OS 44.61682974 -38.96462108
OS 44.60018766 -38.96739476
OS 44.58262102 -38.96924388
OS 44.5622807 -38.97016844
OS 44.55395966 -38.97016844
OS 44.54748774 -38.96924388
OS 44.54009126 -38.96924388
OS 44.53084566 -38.96831932
OS 44.52160006 -38.96739476
OS 44.5114299 -38.96554564
OS 44.48924046 -38.96092284
OS 44.46612646 -38.95445092
OS 44.44393702 -38.94520532
OS 44.43376686 -38.93965796
OS 44.42452126 -38.93318604
OS 44.4235967 -38.93226148
OS 44.42267214 -38.93133692
OS 44.41712478 -38.92578956
OS 44.40880374 -38.91746852
OS 44.39955814 -38.90452468
OS 44.38938798 -38.88880716
OS 44.37921782 -38.87031596
OS 44.37089678 -38.84720196
OS 44.36442486 -38.82131428
OS 44.4420879 -38.809295
OS 44.4420879 -38.81021956
OS 44.4420879 -38.81114412
OS 44.44393702 -38.81669148
OS 44.44578614 -38.82593708
OS 44.44948438 -38.83610724
OS 44.45410718 -38.84720196
OS 44.45965454 -38.85922124
OS 44.46797558 -38.87124052
OS 44.47814574 -38.88141068
OS 44.47999486 -38.88233524
OS 44.4836931 -38.88510892
OS 44.49108958 -38.88880716
OS 44.50033518 -38.89342996
OS 44.51235446 -38.89805276
OS 44.52622286 -38.901751
OS 44.54286494 -38.90452468
OS 44.5622807 -38.90544924
OS 44.5715263 -38.90544924
OS 44.5807719 -38.90452468
OS 44.59279118 -38.90267556
OS 44.60573502 -38.89990188
OS 44.61960342 -38.89620364
OS 44.6316227 -38.89158084
OS 44.64271742 -38.88418436
OS 44.64364198 -38.8832598
OS 44.64734022 -38.88048612
OS 44.65103846 -38.87586332
OS 44.65658582 -38.8693914
OS 44.66120862 -38.86199492
OS 44.66583142 -38.85274932
OS 44.6686051 -38.84350372
OS 44.66952966 -38.832409
OS 44.66952966 -38.83148444
OS 44.66952966 -38.8277862
OS 44.6686051 -38.8231634
OS 44.66675598 -38.81669148
OS 44.6639823 -38.81021956
OS 44.6593595 -38.80374764
OS 44.65381214 -38.79635116
OS 44.6454911 -38.7908038
OS 44.64456654 -38.78987924
OS 44.64179286 -38.78895468
OS 44.63717006 -38.786181
OS 44.62977358 -38.78340732
OS 44.61867886 -38.77970908
OS 44.61220694 -38.7769354
OS 44.60481046 -38.77508628
OS 44.59648942 -38.7723126
OS 44.58724382 -38.76953892
OS 44.57707366 -38.76676524
OS 44.56505438 -38.76399156
OS 44.56412982 -38.76399156
OS 44.56135614 -38.763067
OS 44.55673334 -38.76214244
OS 44.55118598 -38.76029332
OS 44.5437895 -38.7584442
OS 44.53546846 -38.75567052
OS 44.51790182 -38.75104772
OS 44.4975615 -38.7445758
OS 44.47814574 -38.73902844
OS 44.45965454 -38.73255652
OS 44.4513335 -38.72885828
OS 44.44486158 -38.7260846
OS 44.44301246 -38.72516004
OS 44.43931422 -38.72331092
OS 44.43376686 -38.71961268
OS 44.42637038 -38.71498988
OS 44.41804934 -38.70851796
OS 44.4097283 -38.70112148
OS 44.40140726 -38.69280044
OS 44.39401078 -38.68263028
OS 44.39308622 -38.68170572
OS 44.3912371 -38.67800748
OS 44.38846342 -38.67153556
OS 44.38568974 -38.66413908
OS 44.38291606 -38.65489348
OS 44.38014238 -38.64379876
OS 44.37829326 -38.63270404
OS 44.3773687 -38.6197602
OS 44.3773687 -38.61791108
OS 44.3773687 -38.61421284
OS 44.37829326 -38.60866548
OS 44.37921782 -38.60034444
OS 44.38106694 -38.5920234
OS 44.38291606 -38.58185324
OS 44.3866143 -38.57260764
OS 44.3912371 -38.56243748
OS 44.39216166 -38.56151292
OS 44.39401078 -38.55781468
OS 44.39678446 -38.55319188
OS 44.40140726 -38.54671996
OS 44.40695462 -38.54024804
OS 44.41342654 -38.531927
OS 44.42082302 -38.52453052
OS 44.43006862 -38.5180586
OS 44.43099318 -38.51713404
OS 44.43376686 -38.51620948
OS 44.4374651 -38.5134358
OS 44.44301246 -38.51066212
OS 44.45040894 -38.50696388
OS 44.45872998 -38.50326564
OS 44.46890014 -38.4995674
OS 44.47999486 -38.49586916
OS 44.48184398 -38.4949446
OS 44.48554222 -38.49402004
OS 44.49201414 -38.49217092
OS 44.50033518 -38.4903218
OS 44.51050534 -38.48847268
OS 44.52160006 -38.48754812
OS 44.5345439 -38.485699
OS 44.55673334 -38.485699
OS 44.5669035 -38.48662356
OE
OB 33.15968222 -38.32112732 I
OS 33.17539974 -38.32205188
OS 33.19204182 -38.32297644
OS 33.20775934 -38.32482556
OS 33.22162774 -38.32667468
OS 33.22347686 -38.32667468
OS 33.22994878 -38.3285238
OS 33.23826982 -38.33037292
OS 33.24936454 -38.3331466
OS 33.26138382 -38.3377694
OS 33.27432766 -38.34331676
OS 33.28819606 -38.34978868
OS 33.30021534 -38.35718516
OS 33.30206446 -38.35810972
OS 33.3057627 -38.3608834
OS 33.31131006 -38.36643076
OS 33.31870654 -38.37290268
OS 33.32702758 -38.38122372
OS 33.33534862 -38.39231844
OS 33.34459422 -38.40433772
OS 33.3519907 -38.41820612
OS 33.35291526 -38.42005524
OS 33.35476438 -38.42467804
OS 33.35846262 -38.43299908
OS 33.36216086 -38.4440938
OS 33.36493454 -38.45703764
OS 33.36863278 -38.4718306
OS 33.3704819 -38.48847268
OS 33.37140646 -38.50603932
OS 33.37140646 -38.50696388
OS 33.37140646 -38.50973756
OS 33.37140646 -38.5134358
OS 33.3704819 -38.51990772
OS 33.36955734 -38.52637964
OS 33.36863278 -38.53470068
OS 33.36678366 -38.54394628
OS 33.36493454 -38.55411644
OS 33.35846262 -38.57538132
OS 33.35476438 -38.58647604
OS 33.34921702 -38.59849532
OS 33.3427451 -38.6105146
OS 33.33627318 -38.62160932
OS 33.32795214 -38.63270404
OS 33.31870654 -38.64379876
OS 33.31778198 -38.64472332
OS 33.31593286 -38.64657244
OS 33.31315918 -38.64934612
OS 33.30853638 -38.6521198
OS 33.30298902 -38.6567426
OS 33.29559254 -38.6613654
OS 33.28634694 -38.66691276
OS 33.27617678 -38.67153556
OS 33.2641575 -38.67708292
OS 33.2502891 -38.68263028
OS 33.23549614 -38.68725308
OS 33.2179295 -38.69095132
OS 33.1994383 -38.69464956
OS 33.17909798 -38.69742324
OS 33.15598398 -38.69927236
OS 33.13194542 -38.70019692
OS 32.9682983 -38.70019692
OS 32.9682983 -38.95999828
OS 32.88323878 -38.95999828
OS 32.88323878 -38.32020276
OS 33.14581382 -38.32020276
OS 33.15968222 -38.32112732
OE
OB 32.75195126 -38.98403684 I
OS 32.75195126 -38.9849614
OS 32.75195126 -38.98773508
OS 32.75195126 -38.99235788
OS 32.75195126 -38.99790524
OS 32.7510267 -39.00530172
OS 32.7510267 -39.0126982
OS 32.74917758 -39.0311894
OS 32.7464039 -39.05060516
OS 32.74270566 -39.07094548
OS 32.7371583 -39.08851212
OS 32.73346006 -39.09683316
OS 32.72976182 -39.10330508
OS 32.72976182 -39.10422964
OS 32.72883726 -39.1051542
OS 32.72421446 -39.109777
OS 32.71681798 -39.11717348
OS 32.70757238 -39.12549452
OS 32.69462854 -39.13381556
OS 32.67798646 -39.14028748
OS 32.6585707 -39.14583484
OS 32.64747598 -39.1467594
OS 32.6354567 -39.14768396
OS 32.62990934 -39.14768396
OS 32.62436198 -39.1467594
OS 32.61604094 -39.1467594
OS 32.60679534 -39.14583484
OS 32.59662518 -39.14398572
OS 32.57443574 -39.13843836
OS 32.5892287 -39.07187004
OS 32.59015326 -39.07187004
OS 32.59292694 -39.0727946
OS 32.59754974 -39.07371916
OS 32.60217254 -39.07464372
OS 32.61419182 -39.0774174
OS 32.61973918 -39.07834196
OS 32.62898478 -39.07834196
OS 32.63360758 -39.0774174
OS 32.63915494 -39.07649284
OS 32.6447023 -39.07464372
OS 32.65024966 -39.07094548
OS 32.65672158 -39.06724724
OS 32.66134438 -39.06169988
OS 32.66226894 -39.06077532
OS 32.6631935 -39.05800164
OS 32.66504262 -39.05337884
OS 32.6678163 -39.04598236
OS 32.66966542 -39.0358122
OS 32.67058998 -39.02841572
OS 32.67151454 -39.0219438
OS 32.6724391 -39.01362276
OS 32.6724391 -39.0034526
OS 32.67336366 -38.99328244
OS 32.67336366 -38.98218772
OS 32.67336366 -38.49586916
OS 32.75195126 -38.49586916
OS 32.75195126 -38.98403684
OE
OB 33.77174094 -38.3100326 I
OS 33.78006198 -38.31095716
OS 33.79023214 -38.31188172
OS 33.8004023 -38.31280628
OS 33.81242158 -38.31557996
OS 33.8373847 -38.32112732
OS 33.8651215 -38.32944836
OS 33.8789899 -38.33499572
OS 33.89193374 -38.34146764
OS 33.90487758 -38.34978868
OS 33.91782142 -38.35810972
OS 33.91874598 -38.35903428
OS 33.9205951 -38.35995884
OS 33.92429334 -38.36273252
OS 33.92891614 -38.36735532
OS 33.93353894 -38.37197812
OS 33.94001086 -38.37845004
OS 33.94648278 -38.38584652
OS 33.95387926 -38.393243
OS 33.96127574 -38.4024886
OS 33.96867222 -38.41358332
OS 33.97699326 -38.42467804
OS 33.98438974 -38.43669732
OS 33.99086166 -38.45056572
OS 33.99825814 -38.46443412
OS 34.0038055 -38.47922708
OS 34.00935286 -38.49586916
OS 33.92614246 -38.51528492
OS 33.92614246 -38.51436036
OS 33.9252179 -38.51251124
OS 33.92336878 -38.508813
OS 33.92151966 -38.5041902
OS 33.91967054 -38.49864284
OS 33.91689686 -38.49124636
OS 33.90950038 -38.4764534
OS 33.90025478 -38.45981132
OS 33.88916006 -38.44316924
OS 33.87529166 -38.42745172
OS 33.8604987 -38.41358332
OS 33.85864958 -38.4117342
OS 33.85310222 -38.40803596
OS 33.84385662 -38.40341316
OS 33.83183734 -38.39694124
OS 33.81611982 -38.39139388
OS 33.79855318 -38.38584652
OS 33.7772883 -38.38214828
OS 33.7541743 -38.38122372
OS 33.74677782 -38.38122372
OS 33.74215502 -38.38214828
OS 33.7356831 -38.38214828
OS 33.72828662 -38.38307284
OS 33.71071998 -38.38584652
OS 33.69130422 -38.38954476
OS 33.6709639 -38.39601668
OS 33.64969902 -38.40526228
OS 33.63028326 -38.41728156
OS 33.6293587 -38.41728156
OS 33.62843414 -38.41913068
OS 33.62196222 -38.42375348
OS 33.61364118 -38.43114996
OS 33.60347102 -38.44224468
OS 33.59145174 -38.45611308
OS 33.58035702 -38.4718306
OS 33.57018686 -38.49124636
OS 33.56094126 -38.51251124
OS 33.56094126 -38.5134358
OS 33.5600167 -38.51528492
OS 33.55909214 -38.5180586
OS 33.55816758 -38.5226814
OS 33.55631846 -38.52822876
OS 33.55446934 -38.53470068
OS 33.55169566 -38.5504182
OS 33.54799742 -38.5689094
OS 33.54429918 -38.58924972
OS 33.54245006 -38.61143916
OS 33.5415255 -38.63547772
OS 33.5415255 -38.63640228
OS 33.5415255 -38.63917596
OS 33.5415255 -38.64379876
OS 33.5415255 -38.64934612
OS 33.54245006 -38.65581804
OS 33.54245006 -38.66413908
OS 33.54337462 -38.67338468
OS 33.54429918 -38.68355484
OS 33.54707286 -38.70574428
OS 33.55169566 -38.72978284
OS 33.55724302 -38.7538214
OS 33.5646395 -38.77785996
OS 33.5646395 -38.77878452
OS 33.56556406 -38.78063364
OS 33.56741318 -38.78340732
OS 33.5692623 -38.78803012
OS 33.57480966 -38.79912484
OS 33.5831307 -38.81206868
OS 33.59330086 -38.82686164
OS 33.6062447 -38.84257916
OS 33.62103766 -38.85644756
OS 33.6386043 -38.8693914
OS 33.63952886 -38.8693914
OS 33.64137798 -38.87031596
OS 33.64415166 -38.87216508
OS 33.6478499 -38.8740142
OS 33.6524727 -38.87586332
OS 33.65802006 -38.878637
OS 33.6709639 -38.88418436
OS 33.68760598 -38.88973172
OS 33.70609718 -38.89435452
OS 33.7264375 -38.89805276
OS 33.74770238 -38.89897732
OS 33.7541743 -38.89897732
OS 33.75972166 -38.89805276
OS 33.76619358 -38.89805276
OS 33.7726655 -38.8971282
OS 33.78930758 -38.89342996
OS 33.80872334 -38.88880716
OS 33.8281391 -38.88141068
OS 33.84847942 -38.87124052
OS 33.85864958 -38.86569316
OS 33.86789518 -38.85829668
OS 33.86881974 -38.85737212
OS 33.8697443 -38.85644756
OS 33.87251798 -38.85367388
OS 33.87621622 -38.8509002
OS 33.87991446 -38.8462774
OS 33.88453726 -38.84073004
OS 33.89008462 -38.83518268
OS 33.89470742 -38.8277862
OS 33.90025478 -38.81946516
OS 33.9067267 -38.81021956
OS 33.91227406 -38.80097396
OS 33.91782142 -38.78987924
OS 33.92244422 -38.77785996
OS 33.92706702 -38.76491612
OS 33.93168982 -38.75104772
OS 33.93538806 -38.73625476
OS 34.02044758 -38.75751964
OS 34.02044758 -38.7584442
OS 34.01952302 -38.76214244
OS 34.0176739 -38.7676898
OS 34.01490022 -38.77508628
OS 34.01212654 -38.78340732
OS 34.0084283 -38.79357748
OS 34.0038055 -38.8046722
OS 33.99825814 -38.81669148
OS 33.9853143 -38.84257916
OS 33.96867222 -38.86846684
OS 33.95850206 -38.88141068
OS 33.9483319 -38.89435452
OS 33.93723718 -38.90544924
OS 33.92429334 -38.91654396
OS 33.92336878 -38.91746852
OS 33.92151966 -38.91931764
OS 33.91689686 -38.92116676
OS 33.91227406 -38.924865
OS 33.90487758 -38.9294878
OS 33.8974811 -38.9341106
OS 33.88731094 -38.9387334
OS 33.87714078 -38.9433562
OS 33.8651215 -38.94890356
OS 33.85217766 -38.95352636
OS 33.83830926 -38.95814916
OS 33.8235163 -38.96277196
OS 33.80779878 -38.9664702
OS 33.7911567 -38.96831932
OS 33.77359006 -38.97016844
OS 33.75509886 -38.971093
OS 33.7449287 -38.971093
OS 33.73753222 -38.97016844
OS 33.72921118 -38.97016844
OS 33.71904102 -38.96924388
OS 33.7079463 -38.96739476
OS 33.69500246 -38.96554564
OS 33.66819022 -38.96092284
OS 33.64045342 -38.95352636
OS 33.61271662 -38.9433562
OS 33.59977278 -38.93688428
OS 33.58682894 -38.9294878
OS 33.58590438 -38.92856324
OS 33.58405526 -38.92763868
OS 33.58035702 -38.924865
OS 33.57665878 -38.92116676
OS 33.57111142 -38.91746852
OS 33.5646395 -38.91192116
OS 33.55724302 -38.90544924
OS 33.54984654 -38.89805276
OS 33.54245006 -38.88973172
OS 33.53412902 -38.88141068
OS 33.51748694 -38.8601458
OS 33.50176942 -38.83518268
OS 33.48790102 -38.80744588
OS 33.48790102 -38.80652132
OS 33.4860519 -38.80374764
OS 33.48512734 -38.79912484
OS 33.48235366 -38.79357748
OS 33.48050454 -38.786181
OS 33.47773086 -38.7769354
OS 33.47403262 -38.76676524
OS 33.47125894 -38.75567052
OS 33.46848526 -38.74365124
OS 33.46478702 -38.72978284
OS 33.46016422 -38.70112148
OS 33.45646598 -38.66876188
OS 33.45461686 -38.63547772
OS 33.45461686 -38.63455316
OS 33.45461686 -38.63085492
OS 33.45461686 -38.62530756
OS 33.45554142 -38.61883564
OS 33.45554142 -38.60959004
OS 33.45646598 -38.60034444
OS 33.45739054 -38.58832516
OS 33.45923966 -38.57630588
OS 33.46386246 -38.54949364
OS 33.47033438 -38.51990772
OS 33.47957998 -38.4903218
OS 33.49252382 -38.46166044
OS 33.49344838 -38.46073588
OS 33.49437294 -38.4579622
OS 33.49622206 -38.45426396
OS 33.4999203 -38.44964116
OS 33.50361854 -38.44316924
OS 33.50824134 -38.43577276
OS 33.52026062 -38.41913068
OS 33.53597814 -38.40063948
OS 33.55446934 -38.38214828
OS 33.57573422 -38.36365708
OS 33.60069734 -38.34793956
OS 33.6016219 -38.347015
OS 33.60439558 -38.34609044
OS 33.60809382 -38.34424132
OS 33.61271662 -38.34146764
OS 33.6201131 -38.33869396
OS 33.62750958 -38.33592028
OS 33.63675518 -38.33222204
OS 33.64692534 -38.3285238
OS 33.65802006 -38.32482556
OS 33.67003934 -38.32112732
OS 33.69592702 -38.31557996
OS 33.72551294 -38.31095716
OS 33.75602342 -38.30910804
OS 33.76526902 -38.30910804
OS 33.77174094 -38.3100326
OE
OB 35.15858094 -39.1375138 I
OS 34.63805366 -39.1375138
OS 34.63805366 -39.08111564
OS 35.15858094 -39.08111564
OS 35.15858094 -39.1375138
OE
OB 34.37917686 -38.32112732 I
OS 34.38657334 -38.32112732
OS 34.40321542 -38.32297644
OS 34.42170662 -38.32482556
OS 34.44112238 -38.3285238
OS 34.46053814 -38.3331466
OS 34.47810478 -38.33961852
OS 34.47902934 -38.33961852
OS 34.4799539 -38.34054308
OS 34.48550126 -38.34331676
OS 34.4938223 -38.34793956
OS 34.5030679 -38.35441148
OS 34.51416262 -38.36273252
OS 34.5261819 -38.37290268
OS 34.53727662 -38.38584652
OS 34.54744678 -38.39971492
OS 34.54837134 -38.40156404
OS 34.55114502 -38.4071114
OS 34.55576782 -38.41450788
OS 34.56039062 -38.4256026
OS 34.56501342 -38.43854644
OS 34.56963622 -38.45241484
OS 34.5724099 -38.46813236
OS 34.57333446 -38.48384988
OS 34.57333446 -38.485699
OS 34.57333446 -38.4903218
OS 34.5724099 -38.49864284
OS 34.57056078 -38.508813
OS 34.5677871 -38.52083228
OS 34.5631643 -38.53377612
OS 34.55761694 -38.54671996
OS 34.55022046 -38.56058836
OS 34.5492959 -38.56243748
OS 34.54652222 -38.56613572
OS 34.54097486 -38.5735322
OS 34.53357838 -38.58092868
OS 34.52433278 -38.59017428
OS 34.51323806 -38.60034444
OS 34.49936966 -38.60959004
OS 34.48365214 -38.61883564
OS 34.4845767 -38.61883564
OS 34.48642582 -38.6197602
OS 34.4891995 -38.62068476
OS 34.49289774 -38.62253388
OS 34.50399246 -38.62623212
OS 34.5169363 -38.63270404
OS 34.5308047 -38.64102508
OS 34.54652222 -38.65119524
OS 34.56039062 -38.66321452
OS 34.57333446 -38.67800748
OS 34.57425902 -38.6798566
OS 34.57795726 -38.68540396
OS 34.58350462 -38.693725
OS 34.58905198 -38.70481972
OS 34.59459934 -38.71961268
OS 34.6001467 -38.7353302
OS 34.60384494 -38.7538214
OS 34.6047695 -38.77416172
OS 34.6047695 -38.77508628
OS 34.6047695 -38.77601084
OS 34.6047695 -38.7815582
OS 34.60384494 -38.7908038
OS 34.60199582 -38.80189852
OS 34.6001467 -38.81484236
OS 34.59644846 -38.82871076
OS 34.59182566 -38.84350372
OS 34.58535374 -38.85829668
OS 34.58442918 -38.8601458
OS 34.5816555 -38.8647686
OS 34.57795726 -38.87124052
OS 34.5724099 -38.88048612
OS 34.56501342 -38.88973172
OS 34.55761694 -38.89990188
OS 34.54837134 -38.91007204
OS 34.53820118 -38.91839308
OS 34.53727662 -38.91931764
OS 34.53357838 -38.92209132
OS 34.52710646 -38.92578956
OS 34.51878542 -38.9294878
OS 34.50861526 -38.93503516
OS 34.49659598 -38.94058252
OS 34.48365214 -38.94520532
OS 34.46793462 -38.94982812
OS 34.4660855 -38.94982812
OS 34.46053814 -38.95167724
OS 34.45129254 -38.9526018
OS 34.43927326 -38.95445092
OS 34.4244803 -38.95630004
OS 34.40691366 -38.95814916
OS 34.3874979 -38.95907372
OS 34.36530846 -38.95999828
OS 34.12122462 -38.95999828
OS 34.12122462 -38.32020276
OS 34.37270494 -38.32020276
OS 34.37917686 -38.32112732
OE
OB 31.74233174 -38.95999828 I
OS 31.65264942 -38.95999828
OS 31.65264942 -38.87031596
OS 31.74233174 -38.87031596
OS 31.74233174 -38.95999828
OE
OB 31.52968294 -38.42745172 I
OS 31.50841806 -38.54671996
OS 31.45941638 -38.54671996
OS 31.44000062 -38.42745172
OS 31.44000062 -38.32020276
OS 31.52968294 -38.32020276
OS 31.52968294 -38.42745172
OE
OB 32.0992119 -38.48662356 I
OS 32.10568382 -38.48754812
OS 32.11955222 -38.48939724
OS 32.1361943 -38.49309548
OS 32.15376094 -38.49864284
OS 32.17132758 -38.50696388
OS 32.18889422 -38.51713404
OS 32.18981878 -38.51713404
OS 32.19074334 -38.51898316
OS 32.1962907 -38.5226814
OS 32.20461174 -38.53007788
OS 32.2147819 -38.53932348
OS 32.22587662 -38.55134276
OS 32.23697134 -38.56613572
OS 32.24806606 -38.58370236
OS 32.25731166 -38.60311812
OS 32.25731166 -38.60404268
OS 32.25823622 -38.6058918
OS 32.25916078 -38.60866548
OS 32.2610099 -38.61236372
OS 32.26285902 -38.61791108
OS 32.26470814 -38.624383
OS 32.26933094 -38.63917596
OS 32.27395374 -38.65766716
OS 32.27765198 -38.67800748
OS 32.28042566 -38.70112148
OS 32.28135022 -38.72516004
OS 32.28135022 -38.7260846
OS 32.28135022 -38.72793372
OS 32.28135022 -38.73163196
OS 32.28135022 -38.73717932
OS 32.28042566 -38.74365124
OS 32.28042566 -38.75104772
OS 32.27857654 -38.7676898
OS 32.2748783 -38.78803012
OS 32.2702555 -38.809295
OS 32.26378358 -38.83148444
OS 32.25546254 -38.85367388
OS 32.25546254 -38.85459844
OS 32.25453798 -38.85644756
OS 32.25268886 -38.85922124
OS 32.25083974 -38.86291948
OS 32.24436782 -38.87308964
OS 32.23604678 -38.88603348
OS 32.22587662 -38.89990188
OS 32.21293278 -38.91377028
OS 32.19813982 -38.92763868
OS 32.18057318 -38.94058252
OS 32.17964862 -38.94058252
OS 32.17872406 -38.94150708
OS 32.17595038 -38.9433562
OS 32.17225214 -38.94520532
OS 32.16300654 -38.94982812
OS 32.1500627 -38.95537548
OS 32.13434518 -38.96092284
OS 32.1177031 -38.96554564
OS 32.09828734 -38.96924388
OS 32.07887158 -38.97016844
OS 32.07239966 -38.97016844
OS 32.06500318 -38.96924388
OS 32.05575758 -38.96831932
OS 32.04466286 -38.9664702
OS 32.03264358 -38.96369652
OS 32.0206243 -38.95999828
OS 32.00860502 -38.95445092
OS 32.00768046 -38.95352636
OS 32.00305766 -38.95167724
OS 31.9975103 -38.947979
OS 31.99011382 -38.94243164
OS 31.98271734 -38.93688428
OS 31.97347174 -38.9294878
OS 31.9651507 -38.92116676
OS 31.95775422 -38.91192116
OS 31.95775422 -39.1375138
OS 31.87916662 -39.1375138
OS 31.87916662 -38.49586916
OS 31.95035774 -38.49586916
OS 31.95035774 -38.55689012
OS 31.9512823 -38.555041
OS 31.95498054 -38.55134276
OS 31.95960334 -38.54487084
OS 31.96699982 -38.53747436
OS 31.97532086 -38.52822876
OS 31.98456646 -38.51990772
OS 31.99566118 -38.51158668
OS 32.0067559 -38.5041902
OS 32.00860502 -38.50326564
OS 32.01230326 -38.50141652
OS 32.01969974 -38.49864284
OS 32.02894534 -38.4949446
OS 32.04004006 -38.49124636
OS 32.0529839 -38.48847268
OS 32.06777686 -38.48662356
OS 32.08441894 -38.485699
OS 32.0945891 -38.485699
OS 32.0992119 -38.48662356
OE
OB 32.5614919 -38.48662356 I
OS 32.57166206 -38.48847268
OS 32.58368134 -38.49217092
OS 32.59662518 -38.49679372
OS 32.61141814 -38.50326564
OS 32.62713566 -38.51158668
OS 32.5984743 -38.58370236
OS 32.59754974 -38.5827778
OS 32.5938515 -38.58092868
OS 32.58830414 -38.578155
OS 32.58090766 -38.57538132
OS 32.57258662 -38.57260764
OS 32.56241646 -38.56983396
OS 32.5522463 -38.56798484
OS 32.54207614 -38.56706028
OS 32.53745334 -38.56706028
OS 32.53283054 -38.56798484
OS 32.52635862 -38.5689094
OS 32.5198867 -38.57075852
OS 32.51156566 -38.5735322
OS 32.50324462 -38.57723044
OS 32.49584814 -38.5827778
OS 32.49492358 -38.58370236
OS 32.4921499 -38.58555148
OS 32.48937622 -38.58924972
OS 32.48475342 -38.59387252
OS 32.48013062 -38.60034444
OS 32.47550782 -38.60774092
OS 32.47088502 -38.61606196
OS 32.46718678 -38.62623212
OS 32.46626222 -38.62808124
OS 32.46533766 -38.6336286
OS 32.46348854 -38.64194964
OS 32.46071486 -38.65304436
OS 32.45794118 -38.66691276
OS 32.45609206 -38.68263028
OS 32.4551675 -38.69927236
OS 32.45424294 -38.71776356
OS 32.45424294 -38.95999828
OS 32.37565534 -38.95999828
OS 32.37565534 -38.49586916
OS 32.44684646 -38.49586916
OS 32.44684646 -38.56613572
OS 32.44777102 -38.56521116
OS 32.45146926 -38.55873924
OS 32.45609206 -38.5504182
OS 32.46348854 -38.54024804
OS 32.47088502 -38.53007788
OS 32.47920606 -38.51898316
OS 32.4875271 -38.50973756
OS 32.49584814 -38.50234108
OS 32.4967727 -38.50141652
OS 32.49954638 -38.4995674
OS 32.50509374 -38.49679372
OS 32.5106411 -38.49402004
OS 32.51803758 -38.49124636
OS 32.52728318 -38.48847268
OS 32.53652878 -38.48662356
OS 32.54669894 -38.485699
OS 32.55317086 -38.485699
OS 32.5614919 -38.48662356
OE
OB 32.75195126 -38.4117342 I
OS 32.67336366 -38.4117342
OS 32.67336366 -38.32020276
OS 32.75195126 -38.32020276
OS 32.75195126 -38.4117342
OE
OB 36.56668582 -38.95999828 I
OS 36.47885262 -38.95999828
OS 36.1441619 -38.4579622
OS 36.1441619 -38.95999828
OS 36.06280062 -38.95999828
OS 36.06280062 -38.32020276
OS 36.14970926 -38.32020276
OS 36.48532454 -38.8231634
OS 36.48532454 -38.32020276
OS 36.56668582 -38.32020276
OS 36.56668582 -38.95999828
OE
OB 35.74382742 -38.32112732 I
OS 35.75954494 -38.32205188
OS 35.77618702 -38.32297644
OS 35.79190454 -38.32482556
OS 35.80577294 -38.32667468
OS 35.80762206 -38.32667468
OS 35.81409398 -38.3285238
OS 35.82241502 -38.33037292
OS 35.83350974 -38.3331466
OS 35.84552902 -38.3377694
OS 35.85847286 -38.34331676
OS 35.87234126 -38.34978868
OS 35.88436054 -38.35718516
OS 35.88620966 -38.35810972
OS 35.8899079 -38.3608834
OS 35.89545526 -38.36643076
OS 35.90285174 -38.37290268
OS 35.91117278 -38.38122372
OS 35.91949382 -38.39231844
OS 35.92873942 -38.40433772
OS 35.9361359 -38.41820612
OS 35.93706046 -38.42005524
OS 35.93890958 -38.42467804
OS 35.94260782 -38.43299908
OS 35.94630606 -38.4440938
OS 35.94907974 -38.45703764
OS 35.95277798 -38.4718306
OS 35.9546271 -38.48847268
OS 35.95555166 -38.50603932
OS 35.95555166 -38.50696388
OS 35.95555166 -38.50973756
OS 35.95555166 -38.5134358
OS 35.9546271 -38.51990772
OS 35.95370254 -38.52637964
OS 35.95277798 -38.53470068
OS 35.95092886 -38.54394628
OS 35.94907974 -38.55411644
OS 35.94260782 -38.57538132
OS 35.93890958 -38.58647604
OS 35.93336222 -38.59849532
OS 35.9268903 -38.6105146
OS 35.92041838 -38.62160932
OS 35.91209734 -38.63270404
OS 35.90285174 -38.64379876
OS 35.90192718 -38.64472332
OS 35.90007806 -38.64657244
OS 35.89730438 -38.64934612
OS 35.89268158 -38.6521198
OS 35.88713422 -38.6567426
OS 35.87973774 -38.6613654
OS 35.87049214 -38.66691276
OS 35.86032198 -38.67153556
OS 35.8483027 -38.67708292
OS 35.8344343 -38.68263028
OS 35.81964134 -38.68725308
OS 35.8020747 -38.69095132
OS 35.7835835 -38.69464956
OS 35.76324318 -38.69742324
OS 35.74012918 -38.69927236
OS 35.71609062 -38.70019692
OS 35.5524435 -38.70019692
OS 35.5524435 -38.95999828
OS 35.46738398 -38.95999828
OS 35.46738398 -38.32020276
OS 35.72995902 -38.32020276
OS 35.74382742 -38.32112732
OE
OB 36.76916446 -38.42745172 I
OS 36.74789958 -38.54671996
OS 36.6988979 -38.54671996
OS 36.67948214 -38.42745172
OS 36.67948214 -38.32020276
OS 36.76916446 -38.32020276
OS 36.76916446 -38.42745172
OE
OB 38.2382903 -38.39601668 I
OS 37.86014526 -38.39601668
OS 37.86014526 -38.59109884
OS 38.21425174 -38.59109884
OS 38.21425174 -38.66691276
OS 37.86014526 -38.66691276
OS 37.86014526 -38.88418436
OS 38.25308326 -38.88418436
OS 38.25308326 -38.95999828
OS 37.77508574 -38.95999828
OS 37.77508574 -38.32020276
OS 38.2382903 -38.32020276
OS 38.2382903 -38.39601668
OE
OB 37.4339231 -38.32112732 I
OS 37.44224414 -38.32112732
OS 37.4616599 -38.32205188
OS 37.48200022 -38.32482556
OS 37.50418966 -38.32759924
OS 37.52452998 -38.33222204
OS 37.53470014 -38.33499572
OS 37.54302118 -38.3377694
OS 37.54394574 -38.3377694
OS 37.5448703 -38.33869396
OS 37.55041766 -38.34146764
OS 37.5587387 -38.34516588
OS 37.56890886 -38.3516378
OS 37.58000358 -38.35995884
OS 37.59202286 -38.37105356
OS 37.60311758 -38.3839974
OS 37.6142123 -38.39879036
OS 37.6142123 -38.39971492
OS 37.61513686 -38.40063948
OS 37.6188351 -38.40618684
OS 37.62253334 -38.41543244
OS 37.6280807 -38.42745172
OS 37.6327035 -38.44132012
OS 37.6373263 -38.4579622
OS 37.64009998 -38.47552884
OS 37.64102454 -38.4949446
OS 37.64102454 -38.49586916
OS 37.64102454 -38.49771828
OS 37.64102454 -38.50141652
OS 37.64009998 -38.50603932
OS 37.64009998 -38.51251124
OS 37.63917542 -38.51898316
OS 37.63547718 -38.53470068
OS 37.62992982 -38.55319188
OS 37.62253334 -38.57260764
OS 37.61143862 -38.5920234
OS 37.60404214 -38.601269
OS 37.59664566 -38.6105146
OS 37.5957211 -38.61143916
OS 37.59479654 -38.61236372
OS 37.59202286 -38.6151374
OS 37.58832462 -38.61791108
OS 37.58370182 -38.62160932
OS 37.57815446 -38.62530756
OS 37.57075798 -38.62993036
OS 37.5633615 -38.63547772
OS 37.5541159 -38.64010052
OS 37.54394574 -38.64472332
OS 37.53285102 -38.65027068
OS 37.52083174 -38.65489348
OS 37.50696334 -38.65859172
OS 37.49309494 -38.66321452
OS 37.47737742 -38.6659882
OS 37.46073534 -38.66876188
OS 37.46258446 -38.66968644
OS 37.4662827 -38.67153556
OS 37.47183006 -38.6752338
OS 37.47922654 -38.67893204
OS 37.49586862 -38.6891022
OS 37.50418966 -38.69557412
OS 37.51158614 -38.70112148
OS 37.51343526 -38.7029706
OS 37.51805806 -38.7075934
OS 37.52545454 -38.71498988
OS 37.53470014 -38.72423548
OS 37.5448703 -38.73717932
OS 37.55688958 -38.75104772
OS 37.56890886 -38.7676898
OS 37.5818527 -38.786181
OS 37.69187534 -38.95999828
OS 37.5864755 -38.95999828
OS 37.50234054 -38.82686164
OS 37.50234054 -38.82593708
OS 37.50049142 -38.82408796
OS 37.4986423 -38.82131428
OS 37.49586862 -38.81761604
OS 37.4893967 -38.80744588
OS 37.48107566 -38.79450204
OS 37.4709055 -38.78063364
OS 37.46073534 -38.76584068
OS 37.45056518 -38.75197228
OS 37.44131958 -38.73902844
OS 37.44039502 -38.73810388
OS 37.43762134 -38.73440564
OS 37.43299854 -38.72885828
OS 37.42652662 -38.72238636
OS 37.41265822 -38.70851796
OS 37.40526174 -38.70204604
OS 37.39786526 -38.69649868
OS 37.3969407 -38.69557412
OS 37.39509158 -38.69464956
OS 37.39139334 -38.69280044
OS 37.38584598 -38.69002676
OS 37.38029862 -38.68725308
OS 37.3738267 -38.6844794
OS 37.35903374 -38.6798566
OS 37.35810918 -38.6798566
OS 37.35626006 -38.67893204
OS 37.35256182 -38.67893204
OS 37.34793902 -38.67800748
OS 37.3414671 -38.67708292
OS 37.33407062 -38.67708292
OS 37.32390046 -38.67615836
OS 37.21480238 -38.67615836
OS 37.21480238 -38.95999828
OS 37.12974286 -38.95999828
OS 37.12974286 -38.32020276
OS 37.42652662 -38.32020276
OS 37.4339231 -38.32112732
OE
OB 35.31760526 -38.95999828 I
OS 35.23254574 -38.95999828
OS 35.23254574 -38.32020276
OS 35.31760526 -38.32020276
OS 35.31760526 -38.95999828
OE
OB 42.12051774 -38.66413908 H
OS 41.95224782 -38.66413908
OS 41.95224782 -38.88418436
OS 42.13438614 -38.88418436
OS 42.1538019 -38.8832598
OS 42.16212294 -38.88233524
OS 42.16951942 -38.88141068
OS 42.17044398 -38.88141068
OS 42.17414222 -38.88048612
OS 42.17968958 -38.87956156
OS 42.1861615 -38.87771244
OS 42.20187902 -38.87216508
OS 42.21759654 -38.8647686
OS 42.2185211 -38.86384404
OS 42.22129478 -38.86199492
OS 42.22499302 -38.85922124
OS 42.22961582 -38.855523
OS 42.23423862 -38.84997564
OS 42.24071054 -38.84442828
OS 42.24533334 -38.8370318
OS 42.2508807 -38.82871076
OS 42.25180526 -38.8277862
OS 42.25272982 -38.82501252
OS 42.25457894 -38.81946516
OS 42.25735262 -38.81299324
OS 42.2601263 -38.80559676
OS 42.26197542 -38.79635116
OS 42.26289998 -38.78525644
OS 42.26382454 -38.77416172
OS 42.26382454 -38.7723126
OS 42.26382454 -38.76861436
OS 42.26289998 -38.76121788
OS 42.26105086 -38.75289684
OS 42.25920174 -38.74365124
OS 42.2555035 -38.73348108
OS 42.2508807 -38.72331092
OS 42.24440878 -38.71314076
OS 42.24348422 -38.7122162
OS 42.24071054 -38.70851796
OS 42.2370123 -38.70389516
OS 42.23146494 -38.6983478
OS 42.22406846 -38.69187588
OS 42.21482286 -38.68540396
OS 42.2046527 -38.6798566
OS 42.19263342 -38.6752338
OS 42.1907843 -38.67430924
OS 42.18708606 -38.67338468
OS 42.17876502 -38.67153556
OS 42.16859486 -38.66968644
OS 42.15565102 -38.66783732
OS 42.1399335 -38.6659882
OS 42.12051774 -38.66413908
OE
OB 45.22981302 -38.5504182 H
OS 45.22426566 -38.5504182
OS 45.21964286 -38.55134276
OS 45.2094727 -38.55226732
OS 45.1956043 -38.55596556
OS 45.17988678 -38.56151292
OS 45.1632447 -38.5689094
OS 45.14752718 -38.58000412
OS 45.13920614 -38.5874006
OS 45.13180966 -38.59479708
OS 45.13180966 -38.59572164
OS 45.12996054 -38.5966462
OS 45.12811142 -38.59941988
OS 45.12533774 -38.60311812
OS 45.12256406 -38.60774092
OS 45.11979038 -38.61328828
OS 45.11609214 -38.62068476
OS 45.1123939 -38.62808124
OS 45.10869566 -38.63732684
OS 45.10499742 -38.64657244
OS 45.10222374 -38.65766716
OS 45.09945006 -38.66968644
OS 45.09667638 -38.68263028
OS 45.09482726 -38.69649868
OS 45.0939027 -38.7122162
OS 45.09297814 -38.72793372
OS 45.09297814 -38.72885828
OS 45.09297814 -38.73163196
OS 45.09297814 -38.73625476
OS 45.0939027 -38.74272668
OS 45.0939027 -38.75012316
OS 45.09482726 -38.7584442
OS 45.09760094 -38.77785996
OS 45.10222374 -38.8000494
OS 45.10962022 -38.82223884
OS 45.11886582 -38.84350372
OS 45.12533774 -38.85274932
OS 45.13180966 -38.86199492
OS 45.13273422 -38.86199492
OS 45.13365878 -38.86384404
OS 45.13920614 -38.86846684
OS 45.14752718 -38.87586332
OS 45.1586219 -38.8832598
OS 45.1724903 -38.89158084
OS 45.18913238 -38.89897732
OS 45.20854814 -38.90360012
OS 45.2187183 -38.90452468
OS 45.22981302 -38.90544924
OS 45.23536038 -38.90544924
OS 45.23998318 -38.90452468
OS 45.25015334 -38.90267556
OS 45.26402174 -38.89990188
OS 45.2788147 -38.89435452
OS 45.29545678 -38.88695804
OS 45.3111743 -38.87586332
OS 45.31949534 -38.86846684
OS 45.32689182 -38.86107036
OS 45.32781638 -38.8601458
OS 45.32874094 -38.85922124
OS 45.33059006 -38.85644756
OS 45.33336374 -38.85274932
OS 45.33613742 -38.84812652
OS 45.33983566 -38.84257916
OS 45.3435339 -38.83518268
OS 45.34723214 -38.8277862
OS 45.35093038 -38.8185406
OS 45.35370406 -38.80837044
OS 45.3574023 -38.79727572
OS 45.36017598 -38.78525644
OS 45.36294966 -38.77138804
OS 45.36479878 -38.75751964
OS 45.3666479 -38.74180212
OS 45.3666479 -38.72516004
OS 45.3666479 -38.72423548
OS 45.3666479 -38.7214618
OS 45.3666479 -38.716839
OS 45.36572334 -38.71129164
OS 45.36572334 -38.70389516
OS 45.36479878 -38.69557412
OS 45.3620251 -38.67615836
OS 45.3574023 -38.65581804
OS 45.35000582 -38.6336286
OS 45.33983566 -38.61328828
OS 45.3342883 -38.60311812
OS 45.32689182 -38.59479708
OS 45.32689182 -38.59387252
OS 45.3250427 -38.59294796
OS 45.31949534 -38.5874006
OS 45.3111743 -38.58092868
OS 45.30007958 -38.57260764
OS 45.28621118 -38.5642866
OS 45.2695691 -38.55689012
OS 45.2510779 -38.55226732
OS 45.24090774 -38.55134276
OS 45.22981302 -38.5504182
OE
OB 32.07702246 -38.54764452 H
OS 32.07239966 -38.54764452
OS 32.06870142 -38.54856908
OS 32.05945582 -38.5504182
OS 32.04743654 -38.55319188
OS 32.03356814 -38.55873924
OS 32.01877518 -38.56706028
OS 32.01045414 -38.57260764
OS 32.00305766 -38.57907956
OS 31.99566118 -38.58647604
OS 31.9882647 -38.59479708
OS 31.9882647 -38.59572164
OS 31.98641558 -38.5966462
OS 31.98456646 -38.59941988
OS 31.98271734 -38.60311812
OS 31.97994366 -38.60866548
OS 31.97624542 -38.61421284
OS 31.97254718 -38.62160932
OS 31.9697735 -38.6290058
OS 31.96607526 -38.6382514
OS 31.96237702 -38.64842156
OS 31.95960334 -38.65951628
OS 31.9559051 -38.67153556
OS 31.95405598 -38.68540396
OS 31.95220686 -38.69927236
OS 31.95035774 -38.71406532
OS 31.95035774 -38.7307074
OS 31.95035774 -38.73163196
OS 31.95035774 -38.73440564
OS 31.95035774 -38.73902844
OS 31.9512823 -38.74550036
OS 31.9512823 -38.75289684
OS 31.95220686 -38.76121788
OS 31.95498054 -38.78063364
OS 31.95960334 -38.80282308
OS 31.9651507 -38.82408796
OS 31.9743963 -38.84535284
OS 31.97994366 -38.85459844
OS 31.98641558 -38.86291948
OS 31.9882647 -38.8647686
OS 31.9928875 -38.8693914
OS 32.00028398 -38.87678788
OS 32.01045414 -38.88418436
OS 32.02339798 -38.89158084
OS 32.03819094 -38.89897732
OS 32.05483302 -38.90360012
OS 32.06407862 -38.90452468
OS 32.07332422 -38.90544924
OS 32.07887158 -38.90544924
OS 32.08256982 -38.90452468
OS 32.09181542 -38.90267556
OS 32.10475926 -38.89990188
OS 32.11862766 -38.89435452
OS 32.13342062 -38.88695804
OS 32.14821358 -38.87586332
OS 32.15561006 -38.8693914
OS 32.16300654 -38.86199492
OS 32.16300654 -38.86107036
OS 32.16485566 -38.8601458
OS 32.16670478 -38.85737212
OS 32.1685539 -38.85367388
OS 32.17225214 -38.84905108
OS 32.17502582 -38.84257916
OS 32.17872406 -38.83610724
OS 32.1824223 -38.8277862
OS 32.18519598 -38.81946516
OS 32.18889422 -38.80837044
OS 32.19259246 -38.79727572
OS 32.19536614 -38.78525644
OS 32.19721526 -38.77138804
OS 32.19906438 -38.75659508
OS 32.2009135 -38.74087756
OS 32.2009135 -38.72423548
OS 32.2009135 -38.72331092
OS 32.2009135 -38.72053724
OS 32.2009135 -38.71591444
OS 32.19998894 -38.70944252
OS 32.19998894 -38.70204604
OS 32.19906438 -38.693725
OS 32.1962907 -38.67430924
OS 32.1916679 -38.65304436
OS 32.18519598 -38.63177948
OS 32.17595038 -38.6105146
OS 32.17040302 -38.60034444
OS 32.1639311 -38.5920234
OS 32.1639311 -38.59109884
OS 32.16208198 -38.59017428
OS 32.15745918 -38.58462692
OS 32.1500627 -38.578155
OS 32.13989254 -38.56983396
OS 32.1269487 -38.56151292
OS 32.11215574 -38.55411644
OS 32.09551366 -38.54949364
OS 32.08626806 -38.54856908
OS 32.07702246 -38.54764452
OE
OB 42.10387566 -38.39601668 H
OS 41.95224782 -38.39601668
OS 41.95224782 -38.58832516
OS 42.10942302 -38.58832516
OS 42.1214423 -38.5874006
OS 42.13438614 -38.58647604
OS 42.14732998 -38.58555148
OS 42.16027382 -38.58370236
OS 42.17044398 -38.58185324
OS 42.1722931 -38.58092868
OS 42.17599134 -38.58000412
OS 42.1815387 -38.57723044
OS 42.18893518 -38.5735322
OS 42.19633166 -38.56983396
OS 42.2046527 -38.5642866
OS 42.21297374 -38.55689012
OS 42.21944566 -38.54949364
OS 42.22037022 -38.54856908
OS 42.22221934 -38.5457954
OS 42.22499302 -38.54024804
OS 42.2277667 -38.53377612
OS 42.23054038 -38.52637964
OS 42.23331406 -38.51713404
OS 42.23516318 -38.50603932
OS 42.23608774 -38.49402004
OS 42.23608774 -38.49217092
OS 42.23608774 -38.48847268
OS 42.23516318 -38.48292532
OS 42.23423862 -38.47552884
OS 42.2323895 -38.46628324
OS 42.22961582 -38.45703764
OS 42.22591758 -38.44779204
OS 42.22037022 -38.43854644
OS 42.21944566 -38.43762188
OS 42.21759654 -38.4348482
OS 42.2138983 -38.4302254
OS 42.2092755 -38.4256026
OS 42.20280358 -38.42005524
OS 42.1954071 -38.41450788
OS 42.1861615 -38.40896052
OS 42.17599134 -38.40526228
OS 42.17506678 -38.40526228
OS 42.17044398 -38.40341316
OS 42.16397206 -38.4024886
OS 42.1538019 -38.40063948
OS 42.1399335 -38.39879036
OS 42.12421598 -38.3978658
OS 42.10387566 -38.39601668
OE
OB 37.41635646 -38.39139388 H
OS 37.21480238 -38.39139388
OS 37.21480238 -38.60311812
OS 37.40526174 -38.60311812
OS 37.41635646 -38.60219356
OS 37.4293003 -38.601269
OS 37.44409326 -38.60034444
OS 37.45888622 -38.59849532
OS 37.47367918 -38.59572164
OS 37.48662302 -38.5920234
OS 37.48847214 -38.59109884
OS 37.49217038 -38.58924972
OS 37.49771774 -38.58647604
OS 37.50511422 -38.5827778
OS 37.51343526 -38.57723044
OS 37.5217563 -38.57075852
OS 37.53007734 -38.56243748
OS 37.53654926 -38.55319188
OS 37.53747382 -38.55226732
OS 37.53932294 -38.54856908
OS 37.54209662 -38.54302172
OS 37.54579486 -38.53562524
OS 37.54856854 -38.5273042
OS 37.55134222 -38.5180586
OS 37.55319134 -38.50696388
OS 37.5541159 -38.49586916
OS 37.5541159 -38.4949446
OS 37.5541159 -38.49402004
OS 37.55319134 -38.48847268
OS 37.55226678 -38.48015164
OS 37.55041766 -38.46905692
OS 37.54579486 -38.4579622
OS 37.5402475 -38.44501836
OS 37.53192646 -38.43299908
OS 37.52083174 -38.4209798
OS 37.51898262 -38.42005524
OS 37.51435982 -38.416357
OS 37.50696334 -38.4117342
OS 37.49494406 -38.40618684
OS 37.48107566 -38.40063948
OS 37.46258446 -38.39601668
OS 37.44131958 -38.39231844
OS 37.41635646 -38.39139388
OE
OB 39.82298614 -38.54764452 H
OS 39.81836334 -38.54764452
OS 39.8146651 -38.54856908
OS 39.8054195 -38.5504182
OS 39.79340022 -38.55319188
OS 39.77953182 -38.55873924
OS 39.76473886 -38.56706028
OS 39.75641782 -38.57260764
OS 39.74902134 -38.57907956
OS 39.74162486 -38.58647604
OS 39.73422838 -38.59479708
OS 39.73422838 -38.59572164
OS 39.73237926 -38.5966462
OS 39.73053014 -38.59941988
OS 39.72868102 -38.60311812
OS 39.72590734 -38.60866548
OS 39.7222091 -38.61421284
OS 39.71851086 -38.62160932
OS 39.71573718 -38.6290058
OS 39.71203894 -38.6382514
OS 39.7083407 -38.64842156
OS 39.70556702 -38.65951628
OS 39.70186878 -38.67153556
OS 39.70001966 -38.68540396
OS 39.69817054 -38.69927236
OS 39.69632142 -38.71406532
OS 39.69632142 -38.7307074
OS 39.69632142 -38.73163196
OS 39.69632142 -38.73440564
OS 39.69632142 -38.73902844
OS 39.69724598 -38.74550036
OS 39.69724598 -38.75289684
OS 39.69817054 -38.76121788
OS 39.70094422 -38.78063364
OS 39.70556702 -38.80282308
OS 39.71111438 -38.82408796
OS 39.72035998 -38.84535284
OS 39.72590734 -38.85459844
OS 39.73237926 -38.86291948
OS 39.73422838 -38.8647686
OS 39.73885118 -38.8693914
OS 39.74624766 -38.87678788
OS 39.75641782 -38.88418436
OS 39.76936166 -38.89158084
OS 39.78415462 -38.89897732
OS 39.8007967 -38.90360012
OS 39.8100423 -38.90452468
OS 39.8192879 -38.90544924
OS 39.82483526 -38.90544924
OS 39.8285335 -38.90452468
OS 39.8377791 -38.90267556
OS 39.85072294 -38.89990188
OS 39.86459134 -38.89435452
OS 39.8793843 -38.88695804
OS 39.89417726 -38.87586332
OS 39.90157374 -38.8693914
OS 39.90897022 -38.86199492
OS 39.90897022 -38.86107036
OS 39.91081934 -38.8601458
OS 39.91266846 -38.85737212
OS 39.91451758 -38.85367388
OS 39.91821582 -38.84905108
OS 39.9209895 -38.84257916
OS 39.92468774 -38.83610724
OS 39.92838598 -38.8277862
OS 39.93115966 -38.81946516
OS 39.9348579 -38.80837044
OS 39.93855614 -38.79727572
OS 39.94132982 -38.78525644
OS 39.94317894 -38.77138804
OS 39.94502806 -38.75659508
OS 39.94687718 -38.74087756
OS 39.94687718 -38.72423548
OS 39.94687718 -38.72331092
OS 39.94687718 -38.72053724
OS 39.94687718 -38.71591444
OS 39.94595262 -38.70944252
OS 39.94595262 -38.70204604
OS 39.94502806 -38.693725
OS 39.94225438 -38.67430924
OS 39.93763158 -38.65304436
OS 39.93115966 -38.63177948
OS 39.92191406 -38.6105146
OS 39.9163667 -38.60034444
OS 39.90989478 -38.5920234
OS 39.90989478 -38.59109884
OS 39.90804566 -38.59017428
OS 39.90342286 -38.58462692
OS 39.89602638 -38.578155
OS 39.88585622 -38.56983396
OS 39.87291238 -38.56151292
OS 39.85811942 -38.55411644
OS 39.84147734 -38.54949364
OS 39.83223174 -38.54856908
OS 39.82298614 -38.54764452
OE
OB 35.73550638 -38.39601668 H
OS 35.5524435 -38.39601668
OS 35.5524435 -38.624383
OS 35.72441166 -38.624383
OS 35.73088358 -38.62345844
OS 35.7373555 -38.62345844
OS 35.74475198 -38.62253388
OS 35.76231862 -38.62068476
OS 35.78173438 -38.61698652
OS 35.80115014 -38.61143916
OS 35.81871678 -38.60404268
OS 35.82703782 -38.59941988
OS 35.83350974 -38.59387252
OS 35.83535886 -38.5920234
OS 35.8390571 -38.58832516
OS 35.84460446 -38.58092868
OS 35.85107638 -38.57168308
OS 35.8575483 -38.5596638
OS 35.86309566 -38.54487084
OS 35.8667939 -38.52822876
OS 35.86864302 -38.508813
OS 35.86864302 -38.50788844
OS 35.86864302 -38.50696388
OS 35.86864302 -38.50234108
OS 35.86771846 -38.49402004
OS 35.86586934 -38.48477444
OS 35.86402022 -38.47460428
OS 35.86032198 -38.462585
OS 35.85477462 -38.45149028
OS 35.8483027 -38.44039556
OS 35.84737814 -38.439471
OS 35.84460446 -38.43577276
OS 35.83998166 -38.43114996
OS 35.8344343 -38.42467804
OS 35.82611326 -38.41820612
OS 35.81686766 -38.41265876
OS 35.8066975 -38.4071114
OS 35.79467822 -38.4024886
OS 35.79375366 -38.4024886
OS 35.79005542 -38.40156404
OS 35.78450806 -38.40063948
OS 35.77711158 -38.39879036
OS 35.76601686 -38.3978658
OS 35.75214846 -38.39694124
OS 35.73550638 -38.39601668
OE
OB 43.44263854 -38.5504182 H
OS 43.43709118 -38.5504182
OS 43.43339294 -38.55134276
OS 43.42322278 -38.55226732
OS 43.4112035 -38.555041
OS 43.39641054 -38.5596638
OS 43.38069302 -38.56613572
OS 43.36590006 -38.57538132
OS 43.3511071 -38.5874006
OS 43.34925798 -38.58924972
OS 43.34555974 -38.59387252
OS 43.33908782 -38.60219356
OS 43.3326159 -38.61328828
OS 43.32521942 -38.62623212
OS 43.3187475 -38.6428742
OS 43.31320014 -38.66228996
OS 43.31042646 -38.68355484
OS 43.57022782 -38.68355484
OS 43.57022782 -38.68263028
OS 43.57022782 -38.68078116
OS 43.56930326 -38.67800748
OS 43.56930326 -38.67430924
OS 43.56745414 -38.66321452
OS 43.56468046 -38.65119524
OS 43.56005766 -38.63640228
OS 43.55543486 -38.62253388
OS 43.54803838 -38.60866548
OS 43.53971734 -38.5966462
OS 43.53971734 -38.59572164
OS 43.53786822 -38.59479708
OS 43.53324542 -38.58924972
OS 43.52492438 -38.58185324
OS 43.51382966 -38.5735322
OS 43.49996126 -38.56521116
OS 43.48331918 -38.55781468
OS 43.46390342 -38.55226732
OS 43.45373326 -38.55134276
OS 43.44263854 -38.5504182
OE
OB 34.35791198 -38.39601668 H
OS 34.20628414 -38.39601668
OS 34.20628414 -38.58832516
OS 34.36345934 -38.58832516
OS 34.37547862 -38.5874006
OS 34.38842246 -38.58647604
OS 34.4013663 -38.58555148
OS 34.41431014 -38.58370236
OS 34.4244803 -38.58185324
OS 34.42632942 -38.58092868
OS 34.43002766 -38.58000412
OS 34.43557502 -38.57723044
OS 34.4429715 -38.5735322
OS 34.45036798 -38.56983396
OS 34.45868902 -38.5642866
OS 34.46701006 -38.55689012
OS 34.47348198 -38.54949364
OS 34.47440654 -38.54856908
OS 34.47625566 -38.5457954
OS 34.47902934 -38.54024804
OS 34.48180302 -38.53377612
OS 34.4845767 -38.52637964
OS 34.48735038 -38.51713404
OS 34.4891995 -38.50603932
OS 34.49012406 -38.49402004
OS 34.49012406 -38.49217092
OS 34.49012406 -38.48847268
OS 34.4891995 -38.48292532
OS 34.48827494 -38.47552884
OS 34.48642582 -38.46628324
OS 34.48365214 -38.45703764
OS 34.4799539 -38.44779204
OS 34.47440654 -38.43854644
OS 34.47348198 -38.43762188
OS 34.47163286 -38.4348482
OS 34.46793462 -38.4302254
OS 34.46331182 -38.4256026
OS 34.4568399 -38.42005524
OS 34.44944342 -38.41450788
OS 34.44019782 -38.40896052
OS 34.43002766 -38.40526228
OS 34.4291031 -38.40526228
OS 34.4244803 -38.40341316
OS 34.41800838 -38.4024886
OS 34.40783822 -38.40063948
OS 34.39396982 -38.39879036
OS 34.3782523 -38.3978658
OS 34.35791198 -38.39601668
OE
OB 40.89732486 -38.39601668 H
OS 40.71426198 -38.39601668
OS 40.71426198 -38.624383
OS 40.88623014 -38.624383
OS 40.89270206 -38.62345844
OS 40.89917398 -38.62345844
OS 40.90657046 -38.62253388
OS 40.9241371 -38.62068476
OS 40.94355286 -38.61698652
OS 40.96296862 -38.61143916
OS 40.98053526 -38.60404268
OS 40.9888563 -38.59941988
OS 40.99532822 -38.59387252
OS 40.99717734 -38.5920234
OS 41.00087558 -38.58832516
OS 41.00642294 -38.58092868
OS 41.01289486 -38.57168308
OS 41.01936678 -38.5596638
OS 41.02491414 -38.54487084
OS 41.02861238 -38.52822876
OS 41.0304615 -38.508813
OS 41.0304615 -38.50788844
OS 41.0304615 -38.50696388
OS 41.0304615 -38.50234108
OS 41.02953694 -38.49402004
OS 41.02768782 -38.48477444
OS 41.0258387 -38.47460428
OS 41.02214046 -38.462585
OS 41.0165931 -38.45149028
OS 41.01012118 -38.44039556
OS 41.00919662 -38.439471
OS 41.00642294 -38.43577276
OS 41.00180014 -38.43114996
OS 40.99625278 -38.42467804
OS 40.98793174 -38.41820612
OS 40.97868614 -38.41265876
OS 40.96851598 -38.4071114
OS 40.9564967 -38.4024886
OS 40.95557214 -38.4024886
OS 40.9518739 -38.40156404
OS 40.94632654 -38.40063948
OS 40.93893006 -38.39879036
OS 40.92783534 -38.3978658
OS 40.91396694 -38.39694124
OS 40.89732486 -38.39601668
OE
OB 33.15136118 -38.39601668 H
OS 32.9682983 -38.39601668
OS 32.9682983 -38.624383
OS 33.14026646 -38.624383
OS 33.14673838 -38.62345844
OS 33.1532103 -38.62345844
OS 33.16060678 -38.62253388
OS 33.17817342 -38.62068476
OS 33.19758918 -38.61698652
OS 33.21700494 -38.61143916
OS 33.23457158 -38.60404268
OS 33.24289262 -38.59941988
OS 33.24936454 -38.59387252
OS 33.25121366 -38.5920234
OS 33.2549119 -38.58832516
OS 33.26045926 -38.58092868
OS 33.26693118 -38.57168308
OS 33.2734031 -38.5596638
OS 33.27895046 -38.54487084
OS 33.2826487 -38.52822876
OS 33.28449782 -38.508813
OS 33.28449782 -38.50788844
OS 33.28449782 -38.50696388
OS 33.28449782 -38.50234108
OS 33.28357326 -38.49402004
OS 33.28172414 -38.48477444
OS 33.27987502 -38.47460428
OS 33.27617678 -38.462585
OS 33.27062942 -38.45149028
OS 33.2641575 -38.44039556
OS 33.26323294 -38.439471
OS 33.26045926 -38.43577276
OS 33.25583646 -38.43114996
OS 33.2502891 -38.42467804
OS 33.24196806 -38.41820612
OS 33.23272246 -38.41265876
OS 33.2225523 -38.4071114
OS 33.21053302 -38.4024886
OS 33.20960846 -38.4024886
OS 33.20591022 -38.40156404
OS 33.20036286 -38.40063948
OS 33.19296638 -38.39879036
OS 33.18187166 -38.3978658
OS 33.16800326 -38.39694124
OS 33.15136118 -38.39601668
OE
OB 34.37455406 -38.66413908 H
OS 34.20628414 -38.66413908
OS 34.20628414 -38.88418436
OS 34.38842246 -38.88418436
OS 34.40783822 -38.8832598
OS 34.41615926 -38.88233524
OS 34.42355574 -38.88141068
OS 34.4244803 -38.88141068
OS 34.42817854 -38.88048612
OS 34.4337259 -38.87956156
OS 34.44019782 -38.87771244
OS 34.45591534 -38.87216508
OS 34.47163286 -38.8647686
OS 34.47255742 -38.86384404
OS 34.4753311 -38.86199492
OS 34.47902934 -38.85922124
OS 34.48365214 -38.855523
OS 34.48827494 -38.84997564
OS 34.49474686 -38.84442828
OS 34.49936966 -38.8370318
OS 34.50491702 -38.82871076
OS 34.50584158 -38.8277862
OS 34.50676614 -38.82501252
OS 34.50861526 -38.81946516
OS 34.51138894 -38.81299324
OS 34.51416262 -38.80559676
OS 34.51601174 -38.79635116
OS 34.5169363 -38.78525644
OS 34.51786086 -38.77416172
OS 34.51786086 -38.7723126
OS 34.51786086 -38.76861436
OS 34.5169363 -38.76121788
OS 34.51508718 -38.75289684
OS 34.51323806 -38.74365124
OS 34.50953982 -38.73348108
OS 34.50491702 -38.72331092
OS 34.4984451 -38.71314076
OS 34.49752054 -38.7122162
OS 34.49474686 -38.70851796
OS 34.49104862 -38.70389516
OS 34.48550126 -38.6983478
OS 34.47810478 -38.69187588
OS 34.46885918 -38.68540396
OS 34.45868902 -38.6798566
OS 34.44666974 -38.6752338
OS 34.44482062 -38.67430924
OS 34.44112238 -38.67338468
OS 34.43280134 -38.67153556
OS 34.42263118 -38.66968644
OS 34.40968734 -38.66783732
OS 34.39396982 -38.6659882
OS 34.37455406 -38.66413908
OE
SE
S P 0
OB 48.49040086 -36.61402634 I
OS 48.17420134 -36.61402634
OS 48.17420134 -37.45999874
OS 48.04661206 -37.45999874
OS 48.04661206 -36.61402634
OS 47.73041254 -36.61402634
OS 47.73041254 -36.50030546
OS 48.49040086 -36.50030546
OS 48.49040086 -36.61402634
OE
OB 47.69990206 -37.45999874 I
OS 47.5556707 -37.45999874
OS 47.44333666 -37.16876234
OS 47.04115306 -37.16876234
OS 46.93714006 -37.45999874
OS 46.80261658 -37.45999874
OS 47.16874234 -36.50030546
OS 47.30742634 -36.50030546
OS 47.69990206 -37.45999874
OE
OB 49.31834434 -36.61402634 I
OS 48.75112678 -36.61402634
OS 48.75112678 -36.90664958
OS 49.2822865 -36.90664958
OS 49.2822865 -37.02037046
OS 48.75112678 -37.02037046
OS 48.75112678 -37.34627786
OS 49.34053378 -37.34627786
OS 49.34053378 -37.45999874
OS 48.6235375 -37.45999874
OS 48.6235375 -36.50030546
OS 49.31834434 -36.50030546
OS 49.31834434 -36.61402634
OE
OB 46.33386466 -36.5016923 I
OS 46.36160146 -36.50307914
OS 46.38933826 -36.50585282
OS 46.41707506 -36.51001334
OS 46.44065134 -36.51417386
OS 46.44203818 -36.51417386
OS 46.44481186 -36.5155607
OS 46.44897238 -36.5155607
OS 46.45451974 -36.51833438
OS 46.46977498 -36.5224949
OS 46.48919074 -36.5294291
OS 46.51138018 -36.53913698
OS 46.53495646 -36.55161854
OS 46.55853274 -36.56548694
OS 46.58072218 -36.58351586
OS 46.58210902 -36.5849027
OS 46.58349586 -36.58628954
OS 46.58765638 -36.59045006
OS 46.59320374 -36.59461058
OS 46.60707214 -36.60847898
OS 46.62371422 -36.62789474
OS 46.64174314 -36.65147102
OS 46.6611589 -36.67920782
OS 46.67918782 -36.71110514
OS 46.69444306 -36.74716298
OS 46.69444306 -36.74854982
OS 46.6958299 -36.7513235
OS 46.69860358 -36.75687086
OS 46.69999042 -36.7651919
OS 46.70415094 -36.77489978
OS 46.70692462 -36.7859945
OS 46.7096983 -36.79847606
OS 46.71385882 -36.8137313
OS 46.71801934 -36.82898654
OS 46.72079302 -36.84701546
OS 46.72772722 -36.88584698
OS 46.73188774 -36.92883902
OS 46.73327458 -36.97599158
OS 46.73327458 -36.97737842
OS 46.73327458 -36.9801521
OS 46.73327458 -36.9870863
OS 46.73327458 -36.9940205
OS 46.73188774 -37.00372838
OS 46.73188774 -37.0148231
OS 46.7305009 -37.04117306
OS 46.72634038 -37.07168354
OS 46.72217986 -37.10358086
OS 46.71524566 -37.13686502
OS 46.70692462 -37.17014918
OS 46.70692462 -37.17153602
OS 46.70553778 -37.1743097
OS 46.70415094 -37.17847022
OS 46.7027641 -37.18401758
OS 46.69721674 -37.19927282
OS 46.6888957 -37.21868858
OS 46.68057466 -37.24087802
OS 46.66947994 -37.26306746
OS 46.65561154 -37.28664374
OS 46.64174314 -37.30883318
OS 46.6403563 -37.31160686
OS 46.63480894 -37.31854106
OS 46.6264879 -37.32824894
OS 46.61539318 -37.3407305
OS 46.60291162 -37.3545989
OS 46.58765638 -37.3684673
OS 46.57240114 -37.38372254
OS 46.55437222 -37.3962041
OS 46.55159854 -37.39759094
OS 46.54605118 -37.40175146
OS 46.5363433 -37.40729882
OS 46.5224749 -37.41423302
OS 46.50583282 -37.42255406
OS 46.48641706 -37.42948826
OS 46.46422762 -37.4378093
OS 46.4392645 -37.4447435
OS 46.43649082 -37.4447435
OS 46.4323303 -37.44613034
OS 46.42816978 -37.44751718
OS 46.41430138 -37.44890402
OS 46.39488562 -37.4516777
OS 46.37269618 -37.45445138
OS 46.34634622 -37.45722506
OS 46.31722258 -37.4586119
OS 46.28532526 -37.45999874
OS 45.9400021 -37.45999874
OS 45.9400021 -36.50030546
OS 46.30890154 -36.50030546
OS 46.33386466 -36.5016923
OE
OB 46.28948578 -36.61402634 H
OS 46.06759138 -36.61402634
OS 46.06759138 -37.34627786
OS 46.29503314 -37.34627786
OS 46.30474102 -37.34489102
OS 46.32554362 -37.34350418
OS 46.3491199 -37.34211734
OS 46.37408302 -37.33934366
OS 46.39904614 -37.33518314
OS 46.41984874 -37.32963578
OS 46.42262242 -37.32824894
OS 46.42955662 -37.3268621
OS 46.4392645 -37.32270158
OS 46.45174606 -37.31715422
OS 46.46561446 -37.30883318
OS 46.47948286 -37.30051214
OS 46.49335126 -37.29080426
OS 46.50721966 -37.27970954
OS 46.5086065 -37.27693586
OS 46.51415386 -37.2713885
OS 46.5224749 -37.26168062
OS 46.53218278 -37.24781222
OS 46.5432775 -37.2297833
OS 46.55575906 -37.2089807
OS 46.56685378 -37.18540442
OS 46.57656166 -37.15905446
OS 46.57656166 -37.15766762
OS 46.5779485 -37.15489394
OS 46.57933534 -37.15073342
OS 46.58072218 -37.14518606
OS 46.58210902 -37.13825186
OS 46.5848827 -37.12854398
OS 46.58765638 -37.1188361
OS 46.59043006 -37.10774138
OS 46.59459058 -37.08000458
OS 46.5987511 -37.04810726
OS 46.60152478 -37.01204942
OS 46.60291162 -36.9732179
OS 46.60291162 -36.97183106
OS 46.60291162 -36.9662837
OS 46.60291162 -36.9593495
OS 46.60152478 -36.94825478
OS 46.60152478 -36.93577322
OS 46.60013794 -36.92190482
OS 46.5987511 -36.90526274
OS 46.59736426 -36.88862066
OS 46.59043006 -36.85117598
OS 46.58210902 -36.81234446
OS 46.56962746 -36.77628662
OS 46.56130642 -36.7582577
OS 46.55298538 -36.74300246
OS 46.55298538 -36.74161562
OS 46.5502117 -36.73884194
OS 46.54743802 -36.73468142
OS 46.54466434 -36.72913406
OS 46.53356962 -36.71526566
OS 46.51970122 -36.69862358
OS 46.5016723 -36.68059466
OS 46.4808697 -36.66256574
OS 46.45729342 -36.6473105
OS 46.4323303 -36.63482894
OS 46.42955662 -36.6334421
OS 46.42262242 -36.63205526
OS 46.41014086 -36.62789474
OS 46.39211194 -36.62373422
OS 46.3699225 -36.62096054
OS 46.3421857 -36.61680002
OS 46.32554362 -36.61541318
OS 46.3075147 -36.61541318
OS 46.28948578 -36.61402634
OE
OB 47.23531066 -36.60015794 H
OS 47.23531066 -36.60154478
OS 47.23392382 -36.60431846
OS 47.23392382 -36.60986582
OS 47.23115014 -36.61541318
OS 47.2297633 -36.62512106
OS 47.22698962 -36.63482894
OS 47.22144226 -36.65840522
OS 47.21450806 -36.68614202
OS 47.20480018 -36.7166525
OS 47.1950923 -36.74993666
OS 47.18261074 -36.78460766
OS 47.07859774 -37.06474934
OS 47.4031183 -37.06474934
OS 47.30326582 -36.80124974
OS 47.30326582 -36.7998629
OS 47.30187898 -36.79570238
OS 47.2991053 -36.78876818
OS 47.29633162 -36.78044714
OS 47.2921711 -36.77073926
OS 47.28801058 -36.7582577
OS 47.28385006 -36.7443893
OS 47.2783027 -36.7305209
OS 47.26720798 -36.69862358
OS 47.25611326 -36.66533942
OS 47.24501854 -36.63205526
OS 47.23531066 -36.60015794
OE
SE
S P 0
OB 53.57408132 -38.30725892 I
OS 53.5861006 -38.30910804
OS 53.60089356 -38.31188172
OS 53.61753564 -38.31650452
OS 53.63417772 -38.32205188
OS 53.6508198 -38.32944836
OS 53.65174436 -38.32944836
OS 53.65266892 -38.33037292
OS 53.65821628 -38.3331466
OS 53.66653732 -38.33869396
OS 53.67578292 -38.34516588
OS 53.68687764 -38.35441148
OS 53.69797236 -38.36458164
OS 53.70906708 -38.37660092
OS 53.71831268 -38.39046932
OS 53.71923724 -38.39231844
OS 53.72201092 -38.39694124
OS 53.72570916 -38.40526228
OS 53.73033196 -38.41543244
OS 53.73495476 -38.42745172
OS 53.738653 -38.44132012
OS 53.74142668 -38.45703764
OS 53.74235124 -38.47275516
OS 53.74235124 -38.47460428
OS 53.74235124 -38.48015164
OS 53.74142668 -38.48754812
OS 53.73957756 -38.49771828
OS 53.73680388 -38.50973756
OS 53.73218108 -38.5226814
OS 53.72663372 -38.53562524
OS 53.71923724 -38.54856908
OS 53.71831268 -38.5504182
OS 53.715539 -38.55411644
OS 53.70999164 -38.56058836
OS 53.70259516 -38.56798484
OS 53.69334956 -38.57630588
OS 53.68225484 -38.58555148
OS 53.669311 -38.59387252
OS 53.65359348 -38.60219356
OS 53.65451804 -38.60219356
OS 53.65636716 -38.60311812
OS 53.65914084 -38.60404268
OS 53.66283908 -38.60496724
OS 53.67300924 -38.60866548
OS 53.68595308 -38.61421284
OS 53.70074604 -38.62160932
OS 53.715539 -38.63085492
OS 53.7294074 -38.6428742
OS 53.74235124 -38.6567426
OS 53.7432758 -38.65859172
OS 53.74697404 -38.66413908
OS 53.7525214 -38.67338468
OS 53.75806876 -38.68540396
OS 53.76361612 -38.70019692
OS 53.76916348 -38.71776356
OS 53.77286172 -38.73810388
OS 53.77378628 -38.76029332
OS 53.77378628 -38.76121788
OS 53.77378628 -38.76399156
OS 53.77378628 -38.76861436
OS 53.77286172 -38.77416172
OS 53.77193716 -38.7815582
OS 53.77008804 -38.78987924
OS 53.76823892 -38.79912484
OS 53.7663898 -38.809295
OS 53.75899332 -38.83148444
OS 53.75344596 -38.84350372
OS 53.7478986 -38.85459844
OS 53.74050212 -38.86661772
OS 53.73218108 -38.878637
OS 53.72293548 -38.89065628
OS 53.71184076 -38.901751
OS 53.7109162 -38.90267556
OS 53.70906708 -38.90452468
OS 53.70536884 -38.90729836
OS 53.70074604 -38.9109966
OS 53.69519868 -38.9156194
OS 53.6878022 -38.9202422
OS 53.67948116 -38.92578956
OS 53.669311 -38.93041236
OS 53.65914084 -38.93595972
OS 53.64712156 -38.94150708
OS 53.63510228 -38.94612988
OS 53.62123388 -38.95075268
OS 53.60644092 -38.95445092
OS 53.5907234 -38.9572246
OS 53.57500588 -38.95907372
OS 53.55743924 -38.95999828
OS 53.5491182 -38.95999828
OS 53.54357084 -38.95907372
OS 53.53617436 -38.95814916
OS 53.52785332 -38.9572246
OS 53.51860772 -38.95537548
OS 53.50843756 -38.95352636
OS 53.48624812 -38.947979
OS 53.46313412 -38.9387334
OS 53.45111484 -38.93318604
OS 53.44002012 -38.92671412
OS 53.4289254 -38.91839308
OS 53.41783068 -38.91007204
OS 53.41690612 -38.90914748
OS 53.415057 -38.90729836
OS 53.41228332 -38.90452468
OS 53.40950964 -38.90082644
OS 53.40488684 -38.89620364
OS 53.40026404 -38.88973172
OS 53.39471668 -38.8832598
OS 53.38916932 -38.87493876
OS 53.38362196 -38.86569316
OS 53.3780746 -38.85644756
OS 53.36790444 -38.83425812
OS 53.3595834 -38.80837044
OS 53.35680972 -38.79450204
OS 53.3549606 -38.77970908
OS 53.4335482 -38.76953892
OS 53.4335482 -38.77046348
OS 53.43447276 -38.7723126
OS 53.43539732 -38.77601084
OS 53.43632188 -38.78063364
OS 53.43724644 -38.786181
OS 53.43909556 -38.79265292
OS 53.44371836 -38.80652132
OS 53.45019028 -38.8231634
OS 53.45851132 -38.83888092
OS 53.46775692 -38.85367388
OS 53.47885164 -38.86661772
OS 53.48070076 -38.86754228
OS 53.484399 -38.87124052
OS 53.49179548 -38.87586332
OS 53.50104108 -38.88048612
OS 53.5121358 -38.88603348
OS 53.5260042 -38.89065628
OS 53.54172172 -38.89435452
OS 53.5583638 -38.89527908
OS 53.56391116 -38.89527908
OS 53.5676094 -38.89435452
OS 53.57777956 -38.89342996
OS 53.5907234 -38.89065628
OS 53.60551636 -38.88603348
OS 53.62123388 -38.87956156
OS 53.6369514 -38.87031596
OS 53.65174436 -38.85737212
OS 53.65359348 -38.855523
OS 53.65821628 -38.84997564
OS 53.66376364 -38.8416546
OS 53.67116012 -38.83055988
OS 53.6785566 -38.81669148
OS 53.68410396 -38.80097396
OS 53.68872676 -38.78248276
OS 53.69057588 -38.76214244
OS 53.69057588 -38.76121788
OS 53.69057588 -38.75936876
OS 53.69057588 -38.75659508
OS 53.68965132 -38.75289684
OS 53.68872676 -38.74272668
OS 53.68595308 -38.7307074
OS 53.68225484 -38.71591444
OS 53.67578292 -38.70112148
OS 53.66653732 -38.68632852
OS 53.65451804 -38.67246012
OS 53.65266892 -38.670611
OS 53.64804612 -38.66691276
OS 53.64064964 -38.6613654
OS 53.63047948 -38.65489348
OS 53.61753564 -38.64842156
OS 53.60181812 -38.6428742
OS 53.58425148 -38.63917596
OS 53.56483572 -38.63732684
OS 53.55651468 -38.63732684
OS 53.55004276 -38.6382514
OS 53.54172172 -38.63917596
OS 53.53247612 -38.64102508
OS 53.5213814 -38.6428742
OS 53.50936212 -38.64564788
OS 53.51860772 -38.57630588
OS 53.52323052 -38.57630588
OS 53.52692876 -38.57723044
OS 53.53894804 -38.57723044
OS 53.5491182 -38.57538132
OS 53.56113748 -38.5735322
OS 53.57500588 -38.57075852
OS 53.5907234 -38.56613572
OS 53.60551636 -38.5596638
OS 53.62123388 -38.55134276
OS 53.62215844 -38.55134276
OS 53.623083 -38.5504182
OS 53.6277058 -38.54671996
OS 53.63417772 -38.54024804
OS 53.6415742 -38.531927
OS 53.64897068 -38.51990772
OS 53.6554426 -38.50603932
OS 53.6600654 -38.4903218
OS 53.66191452 -38.4810762
OS 53.66191452 -38.47090604
OS 53.66191452 -38.46998148
OS 53.66191452 -38.46905692
OS 53.66191452 -38.46350956
OS 53.6600654 -38.45611308
OS 53.65821628 -38.44594292
OS 53.65451804 -38.4348482
OS 53.64989524 -38.42282892
OS 53.64249876 -38.41080964
OS 53.6323286 -38.39971492
OS 53.63140404 -38.39879036
OS 53.62678124 -38.39509212
OS 53.62030932 -38.39046932
OS 53.61198828 -38.38492196
OS 53.60089356 -38.38029916
OS 53.58794972 -38.37567636
OS 53.57315676 -38.37197812
OS 53.55651468 -38.37105356
OS 53.5491182 -38.37105356
OS 53.54079716 -38.37290268
OS 53.52970244 -38.3747518
OS 53.51768316 -38.37845004
OS 53.50566388 -38.38307284
OS 53.49272004 -38.39046932
OS 53.48070076 -38.39971492
OS 53.4797762 -38.40063948
OS 53.47607796 -38.40526228
OS 53.4705306 -38.4117342
OS 53.46405868 -38.4209798
OS 53.45758676 -38.43299908
OS 53.45111484 -38.44779204
OS 53.44556748 -38.46535868
OS 53.44186924 -38.485699
OS 53.36328164 -38.4718306
OS 53.36328164 -38.47090604
OS 53.3642062 -38.46813236
OS 53.36513076 -38.46443412
OS 53.36605532 -38.45888676
OS 53.36790444 -38.45241484
OS 53.37067812 -38.44501836
OS 53.37622548 -38.42745172
OS 53.38547108 -38.4071114
OS 53.3965658 -38.38677108
OS 53.4104342 -38.36735532
OS 53.42800084 -38.34978868
OS 53.4289254 -38.34886412
OS 53.43077452 -38.34793956
OS 53.4335482 -38.34609044
OS 53.43724644 -38.34331676
OS 53.44186924 -38.33961852
OS 53.44834116 -38.33592028
OS 53.45481308 -38.33222204
OS 53.46313412 -38.32759924
OS 53.48162532 -38.32020276
OS 53.5028902 -38.31280628
OS 53.52785332 -38.30818348
OS 53.54079716 -38.30633436
OS 53.56391116 -38.30633436
OS 53.57408132 -38.30725892
OE
OB 54.07889108 -38.30725892 I
OS 54.09091036 -38.30910804
OS 54.10477876 -38.31188172
OS 54.11957172 -38.31557996
OS 54.13528924 -38.32020276
OS 54.1500822 -38.32759924
OS 54.15100676 -38.32759924
OS 54.15193132 -38.3285238
OS 54.15655412 -38.33129748
OS 54.1639506 -38.33592028
OS 54.1731962 -38.3423922
OS 54.18336636 -38.3516378
OS 54.19446108 -38.36180796
OS 54.20463124 -38.37382724
OS 54.2148014 -38.38769564
OS 54.21572596 -38.38954476
OS 54.2194242 -38.39416756
OS 54.22312244 -38.4024886
OS 54.22959436 -38.41450788
OS 54.23514172 -38.42837628
OS 54.2425382 -38.4440938
OS 54.24901012 -38.462585
OS 54.25455748 -38.48292532
OS 54.25455748 -38.48384988
OS 54.25548204 -38.485699
OS 54.2564066 -38.48847268
OS 54.25733116 -38.49309548
OS 54.25825572 -38.49864284
OS 54.25918028 -38.50511476
OS 54.2610294 -38.5134358
OS 54.26195396 -38.5226814
OS 54.26380308 -38.53285156
OS 54.26472764 -38.54394628
OS 54.2656522 -38.55689012
OS 54.26750132 -38.56983396
OS 54.26842588 -38.58462692
OS 54.26842588 -38.59941988
OS 54.26935044 -38.61606196
OS 54.26935044 -38.6336286
OS 54.26935044 -38.63455316
OS 54.26935044 -38.6382514
OS 54.26935044 -38.64472332
OS 54.26935044 -38.6521198
OS 54.26842588 -38.66228996
OS 54.26842588 -38.67338468
OS 54.26750132 -38.68540396
OS 54.26657676 -38.6983478
OS 54.26380308 -38.72793372
OS 54.25918028 -38.7584442
OS 54.25363292 -38.78803012
OS 54.24993468 -38.80189852
OS 54.24531188 -38.81576692
OS 54.24531188 -38.81669148
OS 54.24438732 -38.8185406
OS 54.2425382 -38.82223884
OS 54.24068908 -38.82686164
OS 54.23883996 -38.83333356
OS 54.23514172 -38.83980548
OS 54.22774524 -38.855523
OS 54.21849964 -38.87216508
OS 54.20648036 -38.89065628
OS 54.19261196 -38.90729836
OS 54.17596988 -38.92301588
OS 54.17504532 -38.92301588
OS 54.17412076 -38.924865
OS 54.17134708 -38.92671412
OS 54.16764884 -38.92856324
OS 54.16302604 -38.93133692
OS 54.15840324 -38.93503516
OS 54.14453484 -38.94150708
OS 54.12789276 -38.947979
OS 54.108477 -38.95445092
OS 54.085363 -38.95814916
OS 54.06039988 -38.95999828
OS 54.05115428 -38.95999828
OS 54.04468236 -38.95907372
OS 54.03728588 -38.95814916
OS 54.02804028 -38.95630004
OS 54.01787012 -38.95445092
OS 54.0067754 -38.95167724
OS 53.99568068 -38.947979
OS 53.9836614 -38.94428076
OS 53.97164212 -38.9387334
OS 53.95962284 -38.93226148
OS 53.94760356 -38.924865
OS 53.93558428 -38.9156194
OS 53.92448956 -38.90544924
OS 53.9143194 -38.89435452
OS 53.91339484 -38.89342996
OS 53.91154572 -38.89065628
OS 53.90877204 -38.88603348
OS 53.90414924 -38.878637
OS 53.89952644 -38.87031596
OS 53.89490364 -38.85922124
OS 53.88843172 -38.8462774
OS 53.88288436 -38.83148444
OS 53.877337 -38.81484236
OS 53.87178964 -38.7954266
OS 53.86624228 -38.77416172
OS 53.86161948 -38.75012316
OS 53.85699668 -38.72423548
OS 53.854223 -38.69649868
OS 53.85237388 -38.6659882
OS 53.85144932 -38.6336286
OS 53.85144932 -38.63270404
OS 53.85144932 -38.6290058
OS 53.85144932 -38.62253388
OS 53.85144932 -38.6151374
OS 53.85237388 -38.60496724
OS 53.85237388 -38.59387252
OS 53.85329844 -38.58185324
OS 53.854223 -38.56798484
OS 53.85699668 -38.53932348
OS 53.86161948 -38.508813
OS 53.86716684 -38.47830252
OS 53.87086508 -38.46443412
OS 53.87456332 -38.45056572
OS 53.87456332 -38.44964116
OS 53.87548788 -38.44779204
OS 53.877337 -38.4440938
OS 53.87918612 -38.439471
OS 53.88103524 -38.43299908
OS 53.88473348 -38.42652716
OS 53.89212996 -38.41080964
OS 53.90137556 -38.39416756
OS 53.91339484 -38.37660092
OS 53.92726324 -38.35903428
OS 53.94390532 -38.34424132
OS 53.94482988 -38.34424132
OS 53.94575444 -38.3423922
OS 53.94852812 -38.34054308
OS 53.95222636 -38.33869396
OS 53.95684916 -38.33499572
OS 53.96239652 -38.33222204
OS 53.97626492 -38.32482556
OS 53.992907 -38.31835364
OS 54.01232276 -38.31188172
OS 54.03543676 -38.30818348
OS 54.06039988 -38.30633436
OS 54.06872092 -38.30633436
OS 54.07889108 -38.30725892
OE
OB 53.23846604 -38.94890356 I
OS 53.14878372 -38.94890356
OS 53.14878372 -38.85922124
OS 53.23846604 -38.85922124
OS 53.23846604 -38.94890356
OE
OB 53.00177868 -38.39231844 I
OS 52.74567556 -38.39231844
OS 52.71146684 -38.56521116
OS 52.7123914 -38.5642866
OS 52.71424052 -38.56336204
OS 52.7170142 -38.56151292
OS 52.721637 -38.55873924
OS 52.72718436 -38.55596556
OS 52.73365628 -38.55226732
OS 52.74844924 -38.54487084
OS 52.76694044 -38.53747436
OS 52.78728076 -38.53100244
OS 52.8094702 -38.52637964
OS 52.82056492 -38.52453052
OS 52.84090524 -38.52453052
OS 52.8464526 -38.52545508
OS 52.85384908 -38.52637964
OS 52.86217012 -38.5273042
OS 52.87141572 -38.52915332
OS 52.88158588 -38.531927
OS 52.90377532 -38.53839892
OS 52.9157946 -38.54302172
OS 52.92781388 -38.54949364
OS 52.93983316 -38.55596556
OS 52.95185244 -38.56336204
OS 52.96294716 -38.57260764
OS 52.97404188 -38.5827778
OS 52.97496644 -38.58370236
OS 52.97681556 -38.58555148
OS 52.97958924 -38.58832516
OS 52.98328748 -38.59294796
OS 52.98791028 -38.59941988
OS 52.99253308 -38.6058918
OS 52.99808044 -38.61421284
OS 53.0036278 -38.62345844
OS 53.0082506 -38.6336286
OS 53.01379796 -38.64472332
OS 53.01842076 -38.65766716
OS 53.02304356 -38.670611
OS 53.0267418 -38.6844794
OS 53.02951548 -38.70019692
OS 53.0313646 -38.71591444
OS 53.03228916 -38.73255652
OS 53.03228916 -38.73348108
OS 53.03228916 -38.73625476
OS 53.03228916 -38.74087756
OS 53.0313646 -38.74734948
OS 53.03044004 -38.75474596
OS 53.02951548 -38.763067
OS 53.02766636 -38.77323716
OS 53.02581724 -38.78340732
OS 53.02026988 -38.80744588
OS 53.01102428 -38.832409
OS 53.00547692 -38.84535284
OS 52.99808044 -38.85737212
OS 52.99068396 -38.87031596
OS 52.98143836 -38.88233524
OS 52.9805138 -38.8832598
OS 52.97866468 -38.88603348
OS 52.97496644 -38.88973172
OS 52.97034364 -38.89435452
OS 52.96387172 -38.89990188
OS 52.95647524 -38.90729836
OS 52.94722964 -38.91377028
OS 52.93705948 -38.92116676
OS 52.92596476 -38.92856324
OS 52.91302092 -38.93503516
OS 52.89915252 -38.94150708
OS 52.88435956 -38.947979
OS 52.86864204 -38.9526018
OS 52.8510754 -38.95630004
OS 52.8325842 -38.95907372
OS 52.81316844 -38.95999828
OS 52.8048474 -38.95999828
OS 52.79837548 -38.95907372
OS 52.790979 -38.95814916
OS 52.78265796 -38.9572246
OS 52.7724878 -38.95630004
OS 52.76231764 -38.95352636
OS 52.73920364 -38.947979
OS 52.71608964 -38.93965796
OS 52.70407036 -38.9341106
OS 52.69205108 -38.92763868
OS 52.68095636 -38.9202422
OS 52.66986164 -38.91192116
OS 52.66893708 -38.9109966
OS 52.66708796 -38.91007204
OS 52.66523884 -38.9063738
OS 52.6615406 -38.90267556
OS 52.6569178 -38.89805276
OS 52.652295 -38.8925054
OS 52.64674764 -38.88510892
OS 52.64212484 -38.87678788
OS 52.63657748 -38.86846684
OS 52.63103012 -38.85829668
OS 52.62085996 -38.83610724
OS 52.61253892 -38.81021956
OS 52.60976524 -38.79635116
OS 52.60791612 -38.7815582
OS 52.69020196 -38.77508628
OS 52.69020196 -38.77601084
OS 52.69020196 -38.77785996
OS 52.69112652 -38.78063364
OS 52.69205108 -38.78525644
OS 52.69482476 -38.7954266
OS 52.698523 -38.809295
OS 52.70407036 -38.8231634
OS 52.71146684 -38.83888092
OS 52.72071244 -38.85274932
OS 52.73180716 -38.86569316
OS 52.73365628 -38.86661772
OS 52.73735452 -38.87031596
OS 52.744751 -38.87493876
OS 52.75492116 -38.88048612
OS 52.76601588 -38.88603348
OS 52.77988428 -38.89065628
OS 52.7956018 -38.89435452
OS 52.81316844 -38.89527908
OS 52.8187158 -38.89527908
OS 52.82241404 -38.89435452
OS 52.83350876 -38.89342996
OS 52.8464526 -38.88973172
OS 52.86217012 -38.88510892
OS 52.87788764 -38.87771244
OS 52.89452972 -38.86661772
OS 52.9019262 -38.8601458
OS 52.90932268 -38.85274932
OS 52.91024724 -38.85182476
OS 52.9111718 -38.8509002
OS 52.91302092 -38.84812652
OS 52.9157946 -38.84535284
OS 52.92226652 -38.83518268
OS 52.929663 -38.82223884
OS 52.93613492 -38.80652132
OS 52.94260684 -38.78710556
OS 52.94722964 -38.76399156
OS 52.94907876 -38.75197228
OS 52.94907876 -38.73902844
OS 52.94907876 -38.73810388
OS 52.94907876 -38.73625476
OS 52.94907876 -38.73255652
OS 52.9481542 -38.72793372
OS 52.9481542 -38.72238636
OS 52.94722964 -38.71591444
OS 52.94445596 -38.70112148
OS 52.93983316 -38.68355484
OS 52.93336124 -38.6659882
OS 52.92411564 -38.64934612
OS 52.9111718 -38.6336286
OS 52.9111718 -38.63270404
OS 52.90932268 -38.63177948
OS 52.90469988 -38.62715668
OS 52.89637884 -38.62068476
OS 52.88528412 -38.61328828
OS 52.87049116 -38.60681636
OS 52.85384908 -38.60034444
OS 52.83443332 -38.59572164
OS 52.8233386 -38.59387252
OS 52.80577196 -38.59387252
OS 52.79837548 -38.59479708
OS 52.78912988 -38.59572164
OS 52.77803516 -38.59849532
OS 52.76694044 -38.601269
OS 52.75492116 -38.6058918
OS 52.74290188 -38.61143916
OS 52.74197732 -38.61236372
OS 52.73827908 -38.61421284
OS 52.73273172 -38.61883564
OS 52.72533524 -38.62345844
OS 52.71793876 -38.62993036
OS 52.71054228 -38.6382514
OS 52.70222124 -38.64657244
OS 52.69574932 -38.6567426
OS 52.62178452 -38.64657244
OS 52.68373004 -38.31742908
OS 53.00177868 -38.31742908
OS 53.00177868 -38.39231844
OE
OB 53.23846604 -38.57445676 I
OS 53.14878372 -38.57445676
OS 53.14878372 -38.48477444
OS 53.23846604 -38.48477444
OS 53.23846604 -38.57445676
OE
OB 54.48199924 -38.57445676 I
OS 54.39231692 -38.57445676
OS 54.39231692 -38.48477444
OS 54.48199924 -38.48477444
OS 54.48199924 -38.57445676
OE
OB 56.14990548 -38.3100326 I
OS 56.165623 -38.31095716
OS 56.18226508 -38.31188172
OS 56.1979826 -38.31373084
OS 56.211851 -38.31557996
OS 56.21370012 -38.31557996
OS 56.22017204 -38.31742908
OS 56.22849308 -38.3192782
OS 56.2395878 -38.32205188
OS 56.25160708 -38.32667468
OS 56.26455092 -38.33222204
OS 56.27841932 -38.33869396
OS 56.2904386 -38.34609044
OS 56.29228772 -38.347015
OS 56.29598596 -38.34978868
OS 56.30153332 -38.35533604
OS 56.3089298 -38.36180796
OS 56.31725084 -38.370129
OS 56.32557188 -38.38122372
OS 56.33481748 -38.393243
OS 56.34221396 -38.4071114
OS 56.34313852 -38.40896052
OS 56.34498764 -38.41358332
OS 56.34868588 -38.42190436
OS 56.35238412 -38.43299908
OS 56.3551578 -38.44594292
OS 56.35885604 -38.46073588
OS 56.36070516 -38.47737796
OS 56.36162972 -38.4949446
OS 56.36162972 -38.49586916
OS 56.36162972 -38.49864284
OS 56.36162972 -38.50234108
OS 56.36070516 -38.508813
OS 56.3597806 -38.51528492
OS 56.35885604 -38.52360596
OS 56.35700692 -38.53285156
OS 56.3551578 -38.54302172
OS 56.34868588 -38.5642866
OS 56.34498764 -38.57538132
OS 56.33944028 -38.5874006
OS 56.33296836 -38.59941988
OS 56.32649644 -38.6105146
OS 56.3181754 -38.62160932
OS 56.3089298 -38.63270404
OS 56.30800524 -38.6336286
OS 56.30615612 -38.63547772
OS 56.30338244 -38.6382514
OS 56.29875964 -38.64102508
OS 56.29321228 -38.64564788
OS 56.2858158 -38.65027068
OS 56.2765702 -38.65581804
OS 56.26640004 -38.66044084
OS 56.25438076 -38.6659882
OS 56.24051236 -38.67153556
OS 56.2257194 -38.67615836
OS 56.20815276 -38.6798566
OS 56.18966156 -38.68355484
OS 56.16932124 -38.68632852
OS 56.14620724 -38.68817764
OS 56.12216868 -38.6891022
OS 55.95852156 -38.6891022
OS 55.95852156 -38.94890356
OS 55.87346204 -38.94890356
OS 55.87346204 -38.30910804
OS 56.13603708 -38.30910804
OS 56.14990548 -38.3100326
OE
OB 57.07723916 -38.94890356 I
OS 56.99587788 -38.94890356
OS 56.99587788 -38.41358332
OS 56.80911676 -38.94890356
OS 56.73330284 -38.94890356
OS 56.54839084 -38.40433772
OS 56.54839084 -38.94890356
OS 56.46702956 -38.94890356
OS 56.46702956 -38.30910804
OS 56.59369428 -38.30910804
OS 56.74532212 -38.763067
OS 56.74532212 -38.76399156
OS 56.74624668 -38.76584068
OS 56.74717124 -38.76861436
OS 56.74902036 -38.77323716
OS 56.7527186 -38.78433188
OS 56.7573414 -38.79820028
OS 56.7619642 -38.8139178
OS 56.76751156 -38.82963532
OS 56.77213436 -38.84442828
OS 56.7758326 -38.85737212
OS 56.77675716 -38.855523
OS 56.77768172 -38.8509002
OS 56.7804554 -38.84257916
OS 56.78415364 -38.83148444
OS 56.78877644 -38.81669148
OS 56.79524836 -38.79912484
OS 56.80172028 -38.77878452
OS 56.81004132 -38.75474596
OS 56.96351828 -38.30910804
OS 57.07723916 -38.30910804
OS 57.07723916 -38.94890356
OE
OB 55.3150278 -38.30725892 I
OS 55.32704708 -38.30910804
OS 55.34184004 -38.31188172
OS 55.35848212 -38.31650452
OS 55.3751242 -38.32205188
OS 55.39176628 -38.32944836
OS 55.39269084 -38.32944836
OS 55.3936154 -38.33037292
OS 55.39916276 -38.3331466
OS 55.4074838 -38.33869396
OS 55.4167294 -38.34516588
OS 55.42782412 -38.35441148
OS 55.43891884 -38.36458164
OS 55.45001356 -38.37660092
OS 55.45925916 -38.39046932
OS 55.46018372 -38.39231844
OS 55.4629574 -38.39694124
OS 55.46665564 -38.40526228
OS 55.47127844 -38.41543244
OS 55.47590124 -38.42745172
OS 55.47959948 -38.44132012
OS 55.48237316 -38.45703764
OS 55.48329772 -38.47275516
OS 55.48329772 -38.47460428
OS 55.48329772 -38.48015164
OS 55.48237316 -38.48754812
OS 55.48052404 -38.49771828
OS 55.47775036 -38.50973756
OS 55.47312756 -38.5226814
OS 55.4675802 -38.53562524
OS 55.46018372 -38.54856908
OS 55.45925916 -38.5504182
OS 55.45648548 -38.55411644
OS 55.45093812 -38.56058836
OS 55.44354164 -38.56798484
OS 55.43429604 -38.57630588
OS 55.42320132 -38.58555148
OS 55.41025748 -38.59387252
OS 55.39453996 -38.60219356
OS 55.39546452 -38.60219356
OS 55.39731364 -38.60311812
OS 55.40008732 -38.60404268
OS 55.40378556 -38.60496724
OS 55.41395572 -38.60866548
OS 55.42689956 -38.61421284
OS 55.44169252 -38.62160932
OS 55.45648548 -38.63085492
OS 55.47035388 -38.6428742
OS 55.48329772 -38.6567426
OS 55.48422228 -38.65859172
OS 55.48792052 -38.66413908
OS 55.49346788 -38.67338468
OS 55.49901524 -38.68540396
OS 55.5045626 -38.70019692
OS 55.51010996 -38.71776356
OS 55.5138082 -38.73810388
OS 55.51473276 -38.76029332
OS 55.51473276 -38.76121788
OS 55.51473276 -38.76399156
OS 55.51473276 -38.76861436
OS 55.5138082 -38.77416172
OS 55.51288364 -38.7815582
OS 55.51103452 -38.78987924
OS 55.5091854 -38.79912484
OS 55.50733628 -38.809295
OS 55.4999398 -38.83148444
OS 55.49439244 -38.84350372
OS 55.48884508 -38.85459844
OS 55.4814486 -38.86661772
OS 55.47312756 -38.878637
OS 55.46388196 -38.89065628
OS 55.45278724 -38.901751
OS 55.45186268 -38.90267556
OS 55.45001356 -38.90452468
OS 55.44631532 -38.90729836
OS 55.44169252 -38.9109966
OS 55.43614516 -38.9156194
OS 55.42874868 -38.9202422
OS 55.42042764 -38.92578956
OS 55.41025748 -38.93041236
OS 55.40008732 -38.93595972
OS 55.38806804 -38.94150708
OS 55.37604876 -38.94612988
OS 55.36218036 -38.95075268
OS 55.3473874 -38.95445092
OS 55.33166988 -38.9572246
OS 55.31595236 -38.95907372
OS 55.29838572 -38.95999828
OS 55.29006468 -38.95999828
OS 55.28451732 -38.95907372
OS 55.27712084 -38.95814916
OS 55.2687998 -38.9572246
OS 55.2595542 -38.95537548
OS 55.24938404 -38.95352636
OS 55.2271946 -38.947979
OS 55.2040806 -38.9387334
OS 55.19206132 -38.93318604
OS 55.1809666 -38.92671412
OS 55.16987188 -38.91839308
OS 55.15877716 -38.91007204
OS 55.1578526 -38.90914748
OS 55.15600348 -38.90729836
OS 55.1532298 -38.90452468
OS 55.15045612 -38.90082644
OS 55.14583332 -38.89620364
OS 55.14121052 -38.88973172
OS 55.13566316 -38.8832598
OS 55.1301158 -38.87493876
OS 55.12456844 -38.86569316
OS 55.11902108 -38.85644756
OS 55.10885092 -38.83425812
OS 55.10052988 -38.80837044
OS 55.0977562 -38.79450204
OS 55.09590708 -38.77970908
OS 55.17449468 -38.76953892
OS 55.17449468 -38.77046348
OS 55.17541924 -38.7723126
OS 55.1763438 -38.77601084
OS 55.17726836 -38.78063364
OS 55.17819292 -38.786181
OS 55.18004204 -38.79265292
OS 55.18466484 -38.80652132
OS 55.19113676 -38.8231634
OS 55.1994578 -38.83888092
OS 55.2087034 -38.85367388
OS 55.21979812 -38.86661772
OS 55.22164724 -38.86754228
OS 55.22534548 -38.87124052
OS 55.23274196 -38.87586332
OS 55.24198756 -38.88048612
OS 55.25308228 -38.88603348
OS 55.26695068 -38.89065628
OS 55.2826682 -38.89435452
OS 55.29931028 -38.89527908
OS 55.30485764 -38.89527908
OS 55.30855588 -38.89435452
OS 55.31872604 -38.89342996
OS 55.33166988 -38.89065628
OS 55.34646284 -38.88603348
OS 55.36218036 -38.87956156
OS 55.37789788 -38.87031596
OS 55.39269084 -38.85737212
OS 55.39453996 -38.855523
OS 55.39916276 -38.84997564
OS 55.40471012 -38.8416546
OS 55.4121066 -38.83055988
OS 55.41950308 -38.81669148
OS 55.42505044 -38.80097396
OS 55.42967324 -38.78248276
OS 55.43152236 -38.76214244
OS 55.43152236 -38.76121788
OS 55.43152236 -38.75936876
OS 55.43152236 -38.75659508
OS 55.4305978 -38.75289684
OS 55.42967324 -38.74272668
OS 55.42689956 -38.7307074
OS 55.42320132 -38.71591444
OS 55.4167294 -38.70112148
OS 55.4074838 -38.68632852
OS 55.39546452 -38.67246012
OS 55.3936154 -38.670611
OS 55.3889926 -38.66691276
OS 55.38159612 -38.6613654
OS 55.37142596 -38.65489348
OS 55.35848212 -38.64842156
OS 55.3427646 -38.6428742
OS 55.32519796 -38.63917596
OS 55.3057822 -38.63732684
OS 55.29746116 -38.63732684
OS 55.29098924 -38.6382514
OS 55.2826682 -38.63917596
OS 55.2734226 -38.64102508
OS 55.26232788 -38.6428742
OS 55.2503086 -38.64564788
OS 55.2595542 -38.57630588
OS 55.264177 -38.57630588
OS 55.26787524 -38.57723044
OS 55.27989452 -38.57723044
OS 55.29006468 -38.57538132
OS 55.30208396 -38.5735322
OS 55.31595236 -38.57075852
OS 55.33166988 -38.56613572
OS 55.34646284 -38.5596638
OS 55.36218036 -38.55134276
OS 55.36310492 -38.55134276
OS 55.36402948 -38.5504182
OS 55.36865228 -38.54671996
OS 55.3751242 -38.54024804
OS 55.38252068 -38.531927
OS 55.38991716 -38.51990772
OS 55.39638908 -38.50603932
OS 55.40101188 -38.4903218
OS 55.402861 -38.4810762
OS 55.402861 -38.47090604
OS 55.402861 -38.46998148
OS 55.402861 -38.46905692
OS 55.402861 -38.46350956
OS 55.40101188 -38.45611308
OS 55.39916276 -38.44594292
OS 55.39546452 -38.4348482
OS 55.39084172 -38.42282892
OS 55.38344524 -38.41080964
OS 55.37327508 -38.39971492
OS 55.37235052 -38.39879036
OS 55.36772772 -38.39509212
OS 55.3612558 -38.39046932
OS 55.35293476 -38.38492196
OS 55.34184004 -38.38029916
OS 55.3288962 -38.37567636
OS 55.31410324 -38.37197812
OS 55.29746116 -38.37105356
OS 55.29006468 -38.37105356
OS 55.28174364 -38.37290268
OS 55.27064892 -38.3747518
OS 55.25862964 -38.37845004
OS 55.24661036 -38.38307284
OS 55.23366652 -38.39046932
OS 55.22164724 -38.39971492
OS 55.22072268 -38.40063948
OS 55.21702444 -38.40526228
OS 55.21147708 -38.4117342
OS 55.20500516 -38.4209798
OS 55.19853324 -38.43299908
OS 55.19206132 -38.44779204
OS 55.18651396 -38.46535868
OS 55.18281572 -38.485699
OS 55.10422812 -38.4718306
OS 55.10422812 -38.47090604
OS 55.10515268 -38.46813236
OS 55.10607724 -38.46443412
OS 55.1070018 -38.45888676
OS 55.10885092 -38.45241484
OS 55.1116246 -38.44501836
OS 55.11717196 -38.42745172
OS 55.12641756 -38.4071114
OS 55.13751228 -38.38677108
OS 55.15138068 -38.36735532
OS 55.16894732 -38.34978868
OS 55.16987188 -38.34886412
OS 55.171721 -38.34793956
OS 55.17449468 -38.34609044
OS 55.17819292 -38.34331676
OS 55.18281572 -38.33961852
OS 55.18928764 -38.33592028
OS 55.19575956 -38.33222204
OS 55.2040806 -38.32759924
OS 55.2225718 -38.32020276
OS 55.24383668 -38.31280628
OS 55.2687998 -38.30818348
OS 55.28174364 -38.30633436
OS 55.30485764 -38.30633436
OS 55.3150278 -38.30725892
OE
OB 54.48199924 -38.94890356 I
OS 54.39231692 -38.94890356
OS 54.39231692 -38.85922124
OS 54.48199924 -38.85922124
OS 54.48199924 -38.94890356
OE
OB 54.9914318 -38.39231844 I
OS 54.73532868 -38.39231844
OS 54.70111996 -38.56521116
OS 54.70204452 -38.5642866
OS 54.70389364 -38.56336204
OS 54.70666732 -38.56151292
OS 54.71129012 -38.55873924
OS 54.71683748 -38.55596556
OS 54.7233094 -38.55226732
OS 54.73810236 -38.54487084
OS 54.75659356 -38.53747436
OS 54.77693388 -38.53100244
OS 54.79912332 -38.52637964
OS 54.81021804 -38.52453052
OS 54.83055836 -38.52453052
OS 54.83610572 -38.52545508
OS 54.8435022 -38.52637964
OS 54.85182324 -38.5273042
OS 54.86106884 -38.52915332
OS 54.871239 -38.531927
OS 54.89342844 -38.53839892
OS 54.90544772 -38.54302172
OS 54.917467 -38.54949364
OS 54.92948628 -38.55596556
OS 54.94150556 -38.56336204
OS 54.95260028 -38.57260764
OS 54.963695 -38.5827778
OS 54.96461956 -38.58370236
OS 54.96646868 -38.58555148
OS 54.96924236 -38.58832516
OS 54.9729406 -38.59294796
OS 54.9775634 -38.59941988
OS 54.9821862 -38.6058918
OS 54.98773356 -38.61421284
OS 54.99328092 -38.62345844
OS 54.99790372 -38.6336286
OS 55.00345108 -38.64472332
OS 55.00807388 -38.65766716
OS 55.01269668 -38.670611
OS 55.01639492 -38.6844794
OS 55.0191686 -38.70019692
OS 55.02101772 -38.71591444
OS 55.02194228 -38.73255652
OS 55.02194228 -38.73348108
OS 55.02194228 -38.73625476
OS 55.02194228 -38.74087756
OS 55.02101772 -38.74734948
OS 55.02009316 -38.75474596
OS 55.0191686 -38.763067
OS 55.01731948 -38.77323716
OS 55.01547036 -38.78340732
OS 55.009923 -38.80744588
OS 55.0006774 -38.832409
OS 54.99513004 -38.84535284
OS 54.98773356 -38.85737212
OS 54.98033708 -38.87031596
OS 54.97109148 -38.88233524
OS 54.97016692 -38.8832598
OS 54.9683178 -38.88603348
OS 54.96461956 -38.88973172
OS 54.95999676 -38.89435452
OS 54.95352484 -38.89990188
OS 54.94612836 -38.90729836
OS 54.93688276 -38.91377028
OS 54.9267126 -38.92116676
OS 54.91561788 -38.92856324
OS 54.90267404 -38.93503516
OS 54.88880564 -38.94150708
OS 54.87401268 -38.947979
OS 54.85829516 -38.9526018
OS 54.84072852 -38.95630004
OS 54.82223732 -38.95907372
OS 54.80282156 -38.95999828
OS 54.79450052 -38.95999828
OS 54.7880286 -38.95907372
OS 54.78063212 -38.95814916
OS 54.77231108 -38.9572246
OS 54.76214092 -38.95630004
OS 54.75197076 -38.95352636
OS 54.72885676 -38.947979
OS 54.70574276 -38.93965796
OS 54.69372348 -38.9341106
OS 54.6817042 -38.92763868
OS 54.67060948 -38.9202422
OS 54.65951476 -38.91192116
OS 54.6585902 -38.9109966
OS 54.65674108 -38.91007204
OS 54.65489196 -38.9063738
OS 54.65119372 -38.90267556
OS 54.64657092 -38.89805276
OS 54.64194812 -38.8925054
OS 54.63640076 -38.88510892
OS 54.63177796 -38.87678788
OS 54.6262306 -38.86846684
OS 54.62068324 -38.85829668
OS 54.61051308 -38.83610724
OS 54.60219204 -38.81021956
OS 54.59941836 -38.79635116
OS 54.59756924 -38.7815582
OS 54.67985508 -38.77508628
OS 54.67985508 -38.77601084
OS 54.67985508 -38.77785996
OS 54.68077964 -38.78063364
OS 54.6817042 -38.78525644
OS 54.68447788 -38.7954266
OS 54.68817612 -38.809295
OS 54.69372348 -38.8231634
OS 54.70111996 -38.83888092
OS 54.71036556 -38.85274932
OS 54.72146028 -38.86569316
OS 54.7233094 -38.86661772
OS 54.72700764 -38.87031596
OS 54.73440412 -38.87493876
OS 54.74457428 -38.88048612
OS 54.755669 -38.88603348
OS 54.7695374 -38.89065628
OS 54.78525492 -38.89435452
OS 54.80282156 -38.89527908
OS 54.80836892 -38.89527908
OS 54.81206716 -38.89435452
OS 54.82316188 -38.89342996
OS 54.83610572 -38.88973172
OS 54.85182324 -38.88510892
OS 54.86754076 -38.87771244
OS 54.88418284 -38.86661772
OS 54.89157932 -38.8601458
OS 54.8989758 -38.85274932
OS 54.89990036 -38.85182476
OS 54.90082492 -38.8509002
OS 54.90267404 -38.84812652
OS 54.90544772 -38.84535284
OS 54.91191964 -38.83518268
OS 54.91931612 -38.82223884
OS 54.92578804 -38.80652132
OS 54.93225996 -38.78710556
OS 54.93688276 -38.76399156
OS 54.93873188 -38.75197228
OS 54.93873188 -38.73902844
OS 54.93873188 -38.73810388
OS 54.93873188 -38.73625476
OS 54.93873188 -38.73255652
OS 54.93780732 -38.72793372
OS 54.93780732 -38.72238636
OS 54.93688276 -38.71591444
OS 54.93410908 -38.70112148
OS 54.92948628 -38.68355484
OS 54.92301436 -38.6659882
OS 54.91376876 -38.64934612
OS 54.90082492 -38.6336286
OS 54.90082492 -38.63270404
OS 54.8989758 -38.63177948
OS 54.894353 -38.62715668
OS 54.88603196 -38.62068476
OS 54.87493724 -38.61328828
OS 54.86014428 -38.60681636
OS 54.8435022 -38.60034444
OS 54.82408644 -38.59572164
OS 54.81299172 -38.59387252
OS 54.79542508 -38.59387252
OS 54.7880286 -38.59479708
OS 54.778783 -38.59572164
OS 54.76768828 -38.59849532
OS 54.75659356 -38.601269
OS 54.74457428 -38.6058918
OS 54.732555 -38.61143916
OS 54.73163044 -38.61236372
OS 54.7279322 -38.61421284
OS 54.72238484 -38.61883564
OS 54.71498836 -38.62345844
OS 54.70759188 -38.62993036
OS 54.7001954 -38.6382514
OS 54.69187436 -38.64657244
OS 54.68540244 -38.6567426
OS 54.61143764 -38.64657244
OS 54.67338316 -38.31742908
OS 54.9914318 -38.31742908
OS 54.9914318 -38.39231844
OE
OB 49.95350436 -38.72331092 I
OS 50.040413 -38.72331092
OS 50.040413 -38.7954266
OS 49.95350436 -38.7954266
OS 49.95350436 -38.94890356
OS 49.87491676 -38.94890356
OS 49.87491676 -38.7954266
OS 49.5966242 -38.7954266
OS 49.5966242 -38.72331092
OS 49.88970972 -38.30910804
OS 49.95350436 -38.30910804
OS 49.95350436 -38.72331092
OE
OB 50.1467374 -38.95999828 I
OS 50.08386732 -38.95999828
OS 50.26970388 -38.29801332
OS 50.33257396 -38.29801332
OS 50.1467374 -38.95999828
OE
OB 49.35346492 -38.30725892 I
OS 49.3608614 -38.30818348
OS 49.370107 -38.30910804
OS 49.38027716 -38.31095716
OS 49.39044732 -38.31280628
OS 49.41448588 -38.3192782
OS 49.43852444 -38.3285238
OS 49.45054372 -38.33407116
OS 49.462563 -38.34054308
OS 49.47365772 -38.34886412
OS 49.48382788 -38.35810972
OS 49.48475244 -38.35903428
OS 49.48660156 -38.35995884
OS 49.48845068 -38.36365708
OS 49.49214892 -38.36735532
OS 49.49677172 -38.37197812
OS 49.50139452 -38.37845004
OS 49.50601732 -38.38492196
OS 49.51156468 -38.393243
OS 49.52081028 -38.41080964
OS 49.53005588 -38.43299908
OS 49.53375412 -38.4440938
OS 49.53560324 -38.45703764
OS 49.53745236 -38.46998148
OS 49.53837692 -38.48384988
OS 49.53837692 -38.485699
OS 49.53837692 -38.4903218
OS 49.53745236 -38.49771828
OS 49.5365278 -38.50788844
OS 49.53467868 -38.51898316
OS 49.53098044 -38.531927
OS 49.5272822 -38.5457954
OS 49.52173484 -38.5596638
OS 49.52081028 -38.56151292
OS 49.51896116 -38.56613572
OS 49.51526292 -38.5735322
OS 49.50971556 -38.58370236
OS 49.50231908 -38.59479708
OS 49.49307348 -38.60866548
OS 49.48197876 -38.62253388
OS 49.46903492 -38.6382514
OS 49.4671858 -38.64010052
OS 49.462563 -38.64564788
OS 49.4579402 -38.65027068
OS 49.4533174 -38.65489348
OS 49.44777004 -38.66044084
OS 49.44037356 -38.66783732
OS 49.43297708 -38.6752338
OS 49.42373148 -38.68355484
OS 49.41448588 -38.69280044
OS 49.40339116 -38.7029706
OS 49.39137188 -38.71314076
OS 49.37842804 -38.72516004
OS 49.36363508 -38.73717932
OS 49.34884212 -38.75012316
OS 49.34791756 -38.75104772
OS 49.34606844 -38.75289684
OS 49.3423702 -38.75567052
OS 49.3377474 -38.75936876
OS 49.33220004 -38.76491612
OS 49.32572812 -38.77046348
OS 49.31093516 -38.78248276
OS 49.29521764 -38.79635116
OS 49.28042468 -38.81021956
OS 49.26748084 -38.82223884
OS 49.26193348 -38.82686164
OS 49.25731068 -38.83148444
OS 49.25638612 -38.832409
OS 49.25361244 -38.83518268
OS 49.2499142 -38.83888092
OS 49.2452914 -38.84442828
OS 49.2406686 -38.8509002
OS 49.23512124 -38.85737212
OS 49.22402652 -38.87308964
OS 49.53930148 -38.87308964
OS 49.53930148 -38.94890356
OS 49.11492844 -38.94890356
OS 49.11492844 -38.947979
OS 49.11492844 -38.94428076
OS 49.11492844 -38.9387334
OS 49.115853 -38.93133692
OS 49.11677756 -38.92301588
OS 49.11862668 -38.91377028
OS 49.1204758 -38.90452468
OS 49.12417404 -38.89435452
OS 49.12417404 -38.89342996
OS 49.1250986 -38.8925054
OS 49.12694772 -38.88695804
OS 49.13064596 -38.878637
OS 49.13619332 -38.86754228
OS 49.1435898 -38.85459844
OS 49.1528354 -38.83980548
OS 49.16300556 -38.82501252
OS 49.1759494 -38.809295
OS 49.1759494 -38.80837044
OS 49.17779852 -38.80744588
OS 49.18242132 -38.80189852
OS 49.19074236 -38.79357748
OS 49.20276164 -38.7815582
OS 49.21663004 -38.7676898
OS 49.23419668 -38.75104772
OS 49.25546156 -38.73255652
OS 49.27857556 -38.71314076
OS 49.27950012 -38.7122162
OS 49.28319836 -38.70944252
OS 49.28874572 -38.70481972
OS 49.29521764 -38.69927236
OS 49.30353868 -38.69187588
OS 49.31370884 -38.68355484
OS 49.323879 -38.67430924
OS 49.33589828 -38.66413908
OS 49.35901228 -38.64194964
OS 49.38212628 -38.6197602
OS 49.393221 -38.60866548
OS 49.40339116 -38.59757076
OS 49.41263676 -38.5874006
OS 49.42003324 -38.57723044
OS 49.42003324 -38.57630588
OS 49.42188236 -38.57538132
OS 49.42373148 -38.57260764
OS 49.4255806 -38.5689094
OS 49.43205252 -38.55873924
OS 49.439449 -38.54671996
OS 49.44592092 -38.531927
OS 49.45239284 -38.51620948
OS 49.45609108 -38.49864284
OS 49.4579402 -38.48200076
OS 49.4579402 -38.4810762
OS 49.4579402 -38.48015164
OS 49.45701564 -38.47460428
OS 49.45609108 -38.46535868
OS 49.4533174 -38.45518852
OS 49.44961916 -38.44224468
OS 49.44314724 -38.42930084
OS 49.4348262 -38.416357
OS 49.42373148 -38.40341316
OS 49.42188236 -38.40156404
OS 49.41725956 -38.3978658
OS 49.41078764 -38.393243
OS 49.40061748 -38.38677108
OS 49.38767364 -38.38122372
OS 49.37288068 -38.37567636
OS 49.35531404 -38.37197812
OS 49.33589828 -38.37105356
OS 49.33035092 -38.37105356
OS 49.32665268 -38.37197812
OS 49.31555796 -38.37290268
OS 49.30261412 -38.37567636
OS 49.28874572 -38.3793746
OS 49.2730282 -38.38584652
OS 49.25823524 -38.39416756
OS 49.24436684 -38.40526228
OS 49.24251772 -38.4071114
OS 49.23881948 -38.4117342
OS 49.23327212 -38.41913068
OS 49.22772476 -38.4302254
OS 49.22125284 -38.44316924
OS 49.21570548 -38.45981132
OS 49.21200724 -38.47830252
OS 49.21015812 -38.4995674
OS 49.1297214 -38.49124636
OS 49.1297214 -38.4903218
OS 49.13064596 -38.48754812
OS 49.13064596 -38.48292532
OS 49.13157052 -38.4764534
OS 49.13341964 -38.46905692
OS 49.13526876 -38.46073588
OS 49.13804244 -38.45056572
OS 49.14081612 -38.44039556
OS 49.1482126 -38.41820612
OS 49.15930732 -38.39601668
OS 49.16577924 -38.38492196
OS 49.17410028 -38.37382724
OS 49.18242132 -38.36365708
OS 49.19166692 -38.35441148
OS 49.19259148 -38.35348692
OS 49.1944406 -38.35256236
OS 49.19721428 -38.34978868
OS 49.20183708 -38.347015
OS 49.20738444 -38.34331676
OS 49.21385636 -38.33961852
OS 49.22125284 -38.33499572
OS 49.23049844 -38.33037292
OS 49.2406686 -38.32575012
OS 49.25176332 -38.32112732
OS 49.2637826 -38.31742908
OS 49.27672644 -38.31373084
OS 49.29059484 -38.31095716
OS 49.3053878 -38.30818348
OS 49.32110532 -38.30725892
OS 49.3377474 -38.30633436
OS 49.346993 -38.30633436
OS 49.35346492 -38.30725892
OE
OB 48.67576244 -38.94890356 I
OS 48.59717484 -38.94890356
OS 48.59717484 -38.4487166
OS 48.59625028 -38.44964116
OS 48.59162748 -38.4533394
OS 48.58608012 -38.45888676
OS 48.57683452 -38.46535868
OS 48.56666436 -38.47367972
OS 48.55372052 -38.48292532
OS 48.53892756 -38.49309548
OS 48.52228548 -38.50326564
OS 48.52136092 -38.50326564
OS 48.52043636 -38.5041902
OS 48.514889 -38.50788844
OS 48.5056434 -38.51251124
OS 48.49454868 -38.5180586
OS 48.48160484 -38.52453052
OS 48.46773644 -38.53100244
OS 48.45386804 -38.53747436
OS 48.43999964 -38.54302172
OS 48.43999964 -38.4672078
OS 48.4409242 -38.4672078
OS 48.44277332 -38.46535868
OS 48.44647156 -38.46443412
OS 48.45109436 -38.46166044
OS 48.45664172 -38.45888676
OS 48.46311364 -38.45518852
OS 48.47883116 -38.44594292
OS 48.49732236 -38.43577276
OS 48.51581356 -38.42282892
OS 48.53522932 -38.40803596
OS 48.55464508 -38.39231844
OS 48.55556964 -38.39139388
OS 48.5564942 -38.39046932
OS 48.55926788 -38.38769564
OS 48.56296612 -38.38492196
OS 48.57128716 -38.37567636
OS 48.58238188 -38.36458164
OS 48.5934766 -38.3516378
OS 48.60549588 -38.33684484
OS 48.61566604 -38.32205188
OS 48.62491164 -38.30633436
OS 48.67576244 -38.30633436
OS 48.67576244 -38.94890356
OE
OB 48.9032042 -38.95999828 I
OS 48.84033412 -38.95999828
OS 49.02617068 -38.29801332
OS 49.08904076 -38.29801332
OS 48.9032042 -38.95999828
OE
OB 50.59699812 -38.30725892 I
OS 50.6043946 -38.30818348
OS 50.6136402 -38.30910804
OS 50.62381036 -38.31095716
OS 50.63398052 -38.31280628
OS 50.65801908 -38.3192782
OS 50.68205764 -38.3285238
OS 50.69407692 -38.33407116
OS 50.7060962 -38.34054308
OS 50.71719092 -38.34886412
OS 50.72736108 -38.35810972
OS 50.72828564 -38.35903428
OS 50.73013476 -38.35995884
OS 50.73198388 -38.36365708
OS 50.73568212 -38.36735532
OS 50.74030492 -38.37197812
OS 50.74492772 -38.37845004
OS 50.74955052 -38.38492196
OS 50.75509788 -38.393243
OS 50.76434348 -38.41080964
OS 50.77358908 -38.43299908
OS 50.77728732 -38.4440938
OS 50.77913644 -38.45703764
OS 50.78098556 -38.46998148
OS 50.78191012 -38.48384988
OS 50.78191012 -38.485699
OS 50.78191012 -38.4903218
OS 50.78098556 -38.49771828
OS 50.780061 -38.50788844
OS 50.77821188 -38.51898316
OS 50.77451364 -38.531927
OS 50.7708154 -38.5457954
OS 50.76526804 -38.5596638
OS 50.76434348 -38.56151292
OS 50.76249436 -38.56613572
OS 50.75879612 -38.5735322
OS 50.75324876 -38.58370236
OS 50.74585228 -38.59479708
OS 50.73660668 -38.60866548
OS 50.72551196 -38.62253388
OS 50.71256812 -38.6382514
OS 50.710719 -38.64010052
OS 50.7060962 -38.64564788
OS 50.7014734 -38.65027068
OS 50.6968506 -38.65489348
OS 50.69130324 -38.66044084
OS 50.68390676 -38.66783732
OS 50.67651028 -38.6752338
OS 50.66726468 -38.68355484
OS 50.65801908 -38.69280044
OS 50.64692436 -38.7029706
OS 50.63490508 -38.71314076
OS 50.62196124 -38.72516004
OS 50.60716828 -38.73717932
OS 50.59237532 -38.75012316
OS 50.59145076 -38.75104772
OS 50.58960164 -38.75289684
OS 50.5859034 -38.75567052
OS 50.5812806 -38.75936876
OS 50.57573324 -38.76491612
OS 50.56926132 -38.77046348
OS 50.55446836 -38.78248276
OS 50.53875084 -38.79635116
OS 50.52395788 -38.81021956
OS 50.51101404 -38.82223884
OS 50.50546668 -38.82686164
OS 50.50084388 -38.83148444
OS 50.49991932 -38.832409
OS 50.49714564 -38.83518268
OS 50.4934474 -38.83888092
OS 50.4888246 -38.84442828
OS 50.4842018 -38.8509002
OS 50.47865444 -38.85737212
OS 50.46755972 -38.87308964
OS 50.78283468 -38.87308964
OS 50.78283468 -38.94890356
OS 50.35846164 -38.94890356
OS 50.35846164 -38.947979
OS 50.35846164 -38.94428076
OS 50.35846164 -38.9387334
OS 50.3593862 -38.93133692
OS 50.36031076 -38.92301588
OS 50.36215988 -38.91377028
OS 50.364009 -38.90452468
OS 50.36770724 -38.89435452
OS 50.36770724 -38.89342996
OS 50.3686318 -38.8925054
OS 50.37048092 -38.88695804
OS 50.37417916 -38.878637
OS 50.37972652 -38.86754228
OS 50.387123 -38.85459844
OS 50.3963686 -38.83980548
OS 50.40653876 -38.82501252
OS 50.4194826 -38.809295
OS 50.4194826 -38.80837044
OS 50.42133172 -38.80744588
OS 50.42595452 -38.80189852
OS 50.43427556 -38.79357748
OS 50.44629484 -38.7815582
OS 50.46016324 -38.7676898
OS 50.47772988 -38.75104772
OS 50.49899476 -38.73255652
OS 50.52210876 -38.71314076
OS 50.52303332 -38.7122162
OS 50.52673156 -38.70944252
OS 50.53227892 -38.70481972
OS 50.53875084 -38.69927236
OS 50.54707188 -38.69187588
OS 50.55724204 -38.68355484
OS 50.5674122 -38.67430924
OS 50.57943148 -38.66413908
OS 50.60254548 -38.64194964
OS 50.62565948 -38.6197602
OS 50.6367542 -38.60866548
OS 50.64692436 -38.59757076
OS 50.65616996 -38.5874006
OS 50.66356644 -38.57723044
OS 50.66356644 -38.57630588
OS 50.66541556 -38.57538132
OS 50.66726468 -38.57260764
OS 50.6691138 -38.5689094
OS 50.67558572 -38.55873924
OS 50.6829822 -38.54671996
OS 50.68945412 -38.531927
OS 50.69592604 -38.51620948
OS 50.69962428 -38.49864284
OS 50.7014734 -38.48200076
OS 50.7014734 -38.4810762
OS 50.7014734 -38.48015164
OS 50.70054884 -38.47460428
OS 50.69962428 -38.46535868
OS 50.6968506 -38.45518852
OS 50.69315236 -38.44224468
OS 50.68668044 -38.42930084
OS 50.6783594 -38.416357
OS 50.66726468 -38.40341316
OS 50.66541556 -38.40156404
OS 50.66079276 -38.3978658
OS 50.65432084 -38.393243
OS 50.64415068 -38.38677108
OS 50.63120684 -38.38122372
OS 50.61641388 -38.37567636
OS 50.59884724 -38.37197812
OS 50.57943148 -38.37105356
OS 50.57388412 -38.37105356
OS 50.57018588 -38.37197812
OS 50.55909116 -38.37290268
OS 50.54614732 -38.37567636
OS 50.53227892 -38.3793746
OS 50.5165614 -38.38584652
OS 50.50176844 -38.39416756
OS 50.48790004 -38.40526228
OS 50.48605092 -38.4071114
OS 50.48235268 -38.4117342
OS 50.47680532 -38.41913068
OS 50.47125796 -38.4302254
OS 50.46478604 -38.44316924
OS 50.45923868 -38.45981132
OS 50.45554044 -38.47830252
OS 50.45369132 -38.4995674
OS 50.3732546 -38.49124636
OS 50.3732546 -38.4903218
OS 50.37417916 -38.48754812
OS 50.37417916 -38.48292532
OS 50.37510372 -38.4764534
OS 50.37695284 -38.46905692
OS 50.37880196 -38.46073588
OS 50.38157564 -38.45056572
OS 50.38434932 -38.44039556
OS 50.3917458 -38.41820612
OS 50.40284052 -38.39601668
OS 50.40931244 -38.38492196
OS 50.41763348 -38.37382724
OS 50.42595452 -38.36365708
OS 50.43520012 -38.35441148
OS 50.43612468 -38.35348692
OS 50.4379738 -38.35256236
OS 50.44074748 -38.34978868
OS 50.44537028 -38.347015
OS 50.45091764 -38.34331676
OS 50.45738956 -38.33961852
OS 50.46478604 -38.33499572
OS 50.47403164 -38.33037292
OS 50.4842018 -38.32575012
OS 50.49529652 -38.32112732
OS 50.5073158 -38.31742908
OS 50.52025964 -38.31373084
OS 50.53412804 -38.31095716
OS 50.548921 -38.30818348
OS 50.56463852 -38.30725892
OS 50.5812806 -38.30633436
OS 50.5905262 -38.30633436
OS 50.59699812 -38.30725892
OE
OB 51.0944114 -38.30725892 I
OS 51.10643068 -38.30910804
OS 51.12029908 -38.31188172
OS 51.13509204 -38.31557996
OS 51.15080956 -38.32020276
OS 51.16560252 -38.32759924
OS 51.16652708 -38.32759924
OS 51.16745164 -38.3285238
OS 51.17207444 -38.33129748
OS 51.17947092 -38.33592028
OS 51.18871652 -38.3423922
OS 51.19888668 -38.3516378
OS 51.2099814 -38.36180796
OS 51.22015156 -38.37382724
OS 51.23032172 -38.38769564
OS 51.23124628 -38.38954476
OS 51.23494452 -38.39416756
OS 51.23864276 -38.4024886
OS 51.24511468 -38.41450788
OS 51.25066204 -38.42837628
OS 51.25805852 -38.4440938
OS 51.26453044 -38.462585
OS 51.2700778 -38.48292532
OS 51.2700778 -38.48384988
OS 51.27100236 -38.485699
OS 51.27192692 -38.48847268
OS 51.27285148 -38.49309548
OS 51.27377604 -38.49864284
OS 51.2747006 -38.50511476
OS 51.27654972 -38.5134358
OS 51.27747428 -38.5226814
OS 51.2793234 -38.53285156
OS 51.28024796 -38.54394628
OS 51.28117252 -38.55689012
OS 51.28302164 -38.56983396
OS 51.2839462 -38.58462692
OS 51.2839462 -38.59941988
OS 51.28487076 -38.61606196
OS 51.28487076 -38.6336286
OS 51.28487076 -38.63455316
OS 51.28487076 -38.6382514
OS 51.28487076 -38.64472332
OS 51.28487076 -38.6521198
OS 51.2839462 -38.66228996
OS 51.2839462 -38.67338468
OS 51.28302164 -38.68540396
OS 51.28209708 -38.6983478
OS 51.2793234 -38.72793372
OS 51.2747006 -38.7584442
OS 51.26915324 -38.78803012
OS 51.265455 -38.80189852
OS 51.2608322 -38.81576692
OS 51.2608322 -38.81669148
OS 51.25990764 -38.8185406
OS 51.25805852 -38.82223884
OS 51.2562094 -38.82686164
OS 51.25436028 -38.83333356
OS 51.25066204 -38.83980548
OS 51.24326556 -38.855523
OS 51.23401996 -38.87216508
OS 51.22200068 -38.89065628
OS 51.20813228 -38.90729836
OS 51.1914902 -38.92301588
OS 51.19056564 -38.92301588
OS 51.18964108 -38.924865
OS 51.1868674 -38.92671412
OS 51.18316916 -38.92856324
OS 51.17854636 -38.93133692
OS 51.17392356 -38.93503516
OS 51.16005516 -38.94150708
OS 51.14341308 -38.947979
OS 51.12399732 -38.95445092
OS 51.10088332 -38.95814916
OS 51.0759202 -38.95999828
OS 51.0666746 -38.95999828
OS 51.06020268 -38.95907372
OS 51.0528062 -38.95814916
OS 51.0435606 -38.95630004
OS 51.03339044 -38.95445092
OS 51.02229572 -38.95167724
OS 51.011201 -38.947979
OS 50.99918172 -38.94428076
OS 50.98716244 -38.9387334
OS 50.97514316 -38.93226148
OS 50.96312388 -38.924865
OS 50.9511046 -38.9156194
OS 50.94000988 -38.90544924
OS 50.92983972 -38.89435452
OS 50.92891516 -38.89342996
OS 50.92706604 -38.89065628
OS 50.92429236 -38.88603348
OS 50.91966956 -38.878637
OS 50.91504676 -38.87031596
OS 50.91042396 -38.85922124
OS 50.90395204 -38.8462774
OS 50.89840468 -38.83148444
OS 50.89285732 -38.81484236
OS 50.88730996 -38.7954266
OS 50.8817626 -38.77416172
OS 50.8771398 -38.75012316
OS 50.872517 -38.72423548
OS 50.86974332 -38.69649868
OS 50.8678942 -38.6659882
OS 50.86696964 -38.6336286
OS 50.86696964 -38.63270404
OS 50.86696964 -38.6290058
OS 50.86696964 -38.62253388
OS 50.86696964 -38.6151374
OS 50.8678942 -38.60496724
OS 50.8678942 -38.59387252
OS 50.86881876 -38.58185324
OS 50.86974332 -38.56798484
OS 50.872517 -38.53932348
OS 50.8771398 -38.508813
OS 50.88268716 -38.47830252
OS 50.8863854 -38.46443412
OS 50.89008364 -38.45056572
OS 50.89008364 -38.44964116
OS 50.8910082 -38.44779204
OS 50.89285732 -38.4440938
OS 50.89470644 -38.439471
OS 50.89655556 -38.43299908
OS 50.9002538 -38.42652716
OS 50.90765028 -38.41080964
OS 50.91689588 -38.39416756
OS 50.92891516 -38.37660092
OS 50.94278356 -38.35903428
OS 50.95942564 -38.34424132
OS 50.9603502 -38.34424132
OS 50.96127476 -38.3423922
OS 50.96404844 -38.34054308
OS 50.96774668 -38.33869396
OS 50.97236948 -38.33499572
OS 50.97791684 -38.33222204
OS 50.99178524 -38.32482556
OS 51.00842732 -38.31835364
OS 51.02784308 -38.31188172
OS 51.05095708 -38.30818348
OS 51.0759202 -38.30633436
OS 51.08424124 -38.30633436
OS 51.0944114 -38.30725892
OE
OB 51.59182468 -38.30725892 I
OS 51.59922116 -38.30818348
OS 51.60846676 -38.30910804
OS 51.61863692 -38.31095716
OS 51.62880708 -38.31280628
OS 51.65284564 -38.3192782
OS 51.6768842 -38.3285238
OS 51.68890348 -38.33407116
OS 51.70092276 -38.34054308
OS 51.71201748 -38.34886412
OS 51.72218764 -38.35810972
OS 51.7231122 -38.35903428
OS 51.72496132 -38.35995884
OS 51.72681044 -38.36365708
OS 51.73050868 -38.36735532
OS 51.73513148 -38.37197812
OS 51.73975428 -38.37845004
OS 51.74437708 -38.38492196
OS 51.74992444 -38.393243
OS 51.75917004 -38.41080964
OS 51.76841564 -38.43299908
OS 51.77211388 -38.4440938
OS 51.773963 -38.45703764
OS 51.77581212 -38.46998148
OS 51.77673668 -38.48384988
OS 51.77673668 -38.485699
OS 51.77673668 -38.4903218
OS 51.77581212 -38.49771828
OS 51.77488756 -38.50788844
OS 51.77303844 -38.51898316
OS 51.7693402 -38.531927
OS 51.76564196 -38.5457954
OS 51.7600946 -38.5596638
OS 51.75917004 -38.56151292
OS 51.75732092 -38.56613572
OS 51.75362268 -38.5735322
OS 51.74807532 -38.58370236
OS 51.74067884 -38.59479708
OS 51.73143324 -38.60866548
OS 51.72033852 -38.62253388
OS 51.70739468 -38.6382514
OS 51.70554556 -38.64010052
OS 51.70092276 -38.64564788
OS 51.69629996 -38.65027068
OS 51.69167716 -38.65489348
OS 51.6861298 -38.66044084
OS 51.67873332 -38.66783732
OS 51.67133684 -38.6752338
OS 51.66209124 -38.68355484
OS 51.65284564 -38.69280044
OS 51.64175092 -38.7029706
OS 51.62973164 -38.71314076
OS 51.6167878 -38.72516004
OS 51.60199484 -38.73717932
OS 51.58720188 -38.75012316
OS 51.58627732 -38.75104772
OS 51.5844282 -38.75289684
OS 51.58072996 -38.75567052
OS 51.57610716 -38.75936876
OS 51.5705598 -38.76491612
OS 51.56408788 -38.77046348
OS 51.54929492 -38.78248276
OS 51.5335774 -38.79635116
OS 51.51878444 -38.81021956
OS 51.5058406 -38.82223884
OS 51.50029324 -38.82686164
OS 51.49567044 -38.83148444
OS 51.49474588 -38.832409
OS 51.4919722 -38.83518268
OS 51.48827396 -38.83888092
OS 51.48365116 -38.84442828
OS 51.47902836 -38.8509002
OS 51.473481 -38.85737212
OS 51.46238628 -38.87308964
OS 51.77766124 -38.87308964
OS 51.77766124 -38.94890356
OS 51.3532882 -38.94890356
OS 51.3532882 -38.947979
OS 51.3532882 -38.94428076
OS 51.3532882 -38.9387334
OS 51.35421276 -38.93133692
OS 51.35513732 -38.92301588
OS 51.35698644 -38.91377028
OS 51.35883556 -38.90452468
OS 51.3625338 -38.89435452
OS 51.3625338 -38.89342996
OS 51.36345836 -38.8925054
OS 51.36530748 -38.88695804
OS 51.36900572 -38.878637
OS 51.37455308 -38.86754228
OS 51.38194956 -38.85459844
OS 51.39119516 -38.83980548
OS 51.40136532 -38.82501252
OS 51.41430916 -38.809295
OS 51.41430916 -38.80837044
OS 51.41615828 -38.80744588
OS 51.42078108 -38.80189852
OS 51.42910212 -38.79357748
OS 51.4411214 -38.7815582
OS 51.4549898 -38.7676898
OS 51.47255644 -38.75104772
OS 51.49382132 -38.73255652
OS 51.51693532 -38.71314076
OS 51.51785988 -38.7122162
OS 51.52155812 -38.70944252
OS 51.52710548 -38.70481972
OS 51.5335774 -38.69927236
OS 51.54189844 -38.69187588
OS 51.5520686 -38.68355484
OS 51.56223876 -38.67430924
OS 51.57425804 -38.66413908
OS 51.59737204 -38.64194964
OS 51.62048604 -38.6197602
OS 51.63158076 -38.60866548
OS 51.64175092 -38.59757076
OS 51.65099652 -38.5874006
OS 51.658393 -38.57723044
OS 51.658393 -38.57630588
OS 51.66024212 -38.57538132
OS 51.66209124 -38.57260764
OS 51.66394036 -38.5689094
OS 51.67041228 -38.55873924
OS 51.67780876 -38.54671996
OS 51.68428068 -38.531927
OS 51.6907526 -38.51620948
OS 51.69445084 -38.49864284
OS 51.69629996 -38.48200076
OS 51.69629996 -38.4810762
OS 51.69629996 -38.48015164
OS 51.6953754 -38.47460428
OS 51.69445084 -38.46535868
OS 51.69167716 -38.45518852
OS 51.68797892 -38.44224468
OS 51.681507 -38.42930084
OS 51.67318596 -38.416357
OS 51.66209124 -38.40341316
OS 51.66024212 -38.40156404
OS 51.65561932 -38.3978658
OS 51.6491474 -38.393243
OS 51.63897724 -38.38677108
OS 51.6260334 -38.38122372
OS 51.61124044 -38.37567636
OS 51.5936738 -38.37197812
OS 51.57425804 -38.37105356
OS 51.56871068 -38.37105356
OS 51.56501244 -38.37197812
OS 51.55391772 -38.37290268
OS 51.54097388 -38.37567636
OS 51.52710548 -38.3793746
OS 51.51138796 -38.38584652
OS 51.496595 -38.39416756
OS 51.4827266 -38.40526228
OS 51.48087748 -38.4071114
OS 51.47717924 -38.4117342
OS 51.47163188 -38.41913068
OS 51.46608452 -38.4302254
OS 51.4596126 -38.44316924
OS 51.45406524 -38.45981132
OS 51.450367 -38.47830252
OS 51.44851788 -38.4995674
OS 51.36808116 -38.49124636
OS 51.36808116 -38.4903218
OS 51.36900572 -38.48754812
OS 51.36900572 -38.48292532
OS 51.36993028 -38.4764534
OS 51.3717794 -38.46905692
OS 51.37362852 -38.46073588
OS 51.3764022 -38.45056572
OS 51.37917588 -38.44039556
OS 51.38657236 -38.41820612
OS 51.39766708 -38.39601668
OS 51.404139 -38.38492196
OS 51.41246004 -38.37382724
OS 51.42078108 -38.36365708
OS 51.43002668 -38.35441148
OS 51.43095124 -38.35348692
OS 51.43280036 -38.35256236
OS 51.43557404 -38.34978868
OS 51.44019684 -38.347015
OS 51.4457442 -38.34331676
OS 51.45221612 -38.33961852
OS 51.4596126 -38.33499572
OS 51.4688582 -38.33037292
OS 51.47902836 -38.32575012
OS 51.49012308 -38.32112732
OS 51.50214236 -38.31742908
OS 51.5150862 -38.31373084
OS 51.5289546 -38.31095716
OS 51.54374756 -38.30818348
OS 51.55946508 -38.30725892
OS 51.57610716 -38.30633436
OS 51.58535276 -38.30633436
OS 51.59182468 -38.30725892
OE
OB 52.08184148 -38.30725892 I
OS 52.09386076 -38.30910804
OS 52.10865372 -38.31188172
OS 52.1252958 -38.31650452
OS 52.14193788 -38.32205188
OS 52.15857996 -38.32944836
OS 52.15950452 -38.32944836
OS 52.16042908 -38.33037292
OS 52.16597644 -38.3331466
OS 52.17429748 -38.33869396
OS 52.18354308 -38.34516588
OS 52.1946378 -38.35441148
OS 52.20573252 -38.36458164
OS 52.21682724 -38.37660092
OS 52.22607284 -38.39046932
OS 52.2269974 -38.39231844
OS 52.22977108 -38.39694124
OS 52.23346932 -38.40526228
OS 52.23809212 -38.41543244
OS 52.24271492 -38.42745172
OS 52.24641316 -38.44132012
OS 52.24918684 -38.45703764
OS 52.2501114 -38.47275516
OS 52.2501114 -38.47460428
OS 52.2501114 -38.48015164
OS 52.24918684 -38.48754812
OS 52.24733772 -38.49771828
OS 52.24456404 -38.50973756
OS 52.23994124 -38.5226814
OS 52.23439388 -38.53562524
OS 52.2269974 -38.54856908
OS 52.22607284 -38.5504182
OS 52.22329916 -38.55411644
OS 52.2177518 -38.56058836
OS 52.21035532 -38.56798484
OS 52.20110972 -38.57630588
OS 52.190015 -38.58555148
OS 52.17707116 -38.59387252
OS 52.16135364 -38.60219356
OS 52.1622782 -38.60219356
OS 52.16412732 -38.60311812
OS 52.166901 -38.60404268
OS 52.17059924 -38.60496724
OS 52.1807694 -38.60866548
OS 52.19371324 -38.61421284
OS 52.2085062 -38.62160932
OS 52.22329916 -38.63085492
OS 52.23716756 -38.6428742
OS 52.2501114 -38.6567426
OS 52.25103596 -38.65859172
OS 52.2547342 -38.66413908
OS 52.26028156 -38.67338468
OS 52.26582892 -38.68540396
OS 52.27137628 -38.70019692
OS 52.27692364 -38.71776356
OS 52.28062188 -38.73810388
OS 52.28154644 -38.76029332
OS 52.28154644 -38.76121788
OS 52.28154644 -38.76399156
OS 52.28154644 -38.76861436
OS 52.28062188 -38.77416172
OS 52.27969732 -38.7815582
OS 52.2778482 -38.78987924
OS 52.27599908 -38.79912484
OS 52.27414996 -38.809295
OS 52.26675348 -38.83148444
OS 52.26120612 -38.84350372
OS 52.25565876 -38.85459844
OS 52.24826228 -38.86661772
OS 52.23994124 -38.878637
OS 52.23069564 -38.89065628
OS 52.21960092 -38.901751
OS 52.21867636 -38.90267556
OS 52.21682724 -38.90452468
OS 52.213129 -38.90729836
OS 52.2085062 -38.9109966
OS 52.20295884 -38.9156194
OS 52.19556236 -38.9202422
OS 52.18724132 -38.92578956
OS 52.17707116 -38.93041236
OS 52.166901 -38.93595972
OS 52.15488172 -38.94150708
OS 52.14286244 -38.94612988
OS 52.12899404 -38.95075268
OS 52.11420108 -38.95445092
OS 52.09848356 -38.9572246
OS 52.08276604 -38.95907372
OS 52.0651994 -38.95999828
OS 52.05687836 -38.95999828
OS 52.051331 -38.95907372
OS 52.04393452 -38.95814916
OS 52.03561348 -38.9572246
OS 52.02636788 -38.95537548
OS 52.01619772 -38.95352636
OS 51.99400828 -38.947979
OS 51.97089428 -38.9387334
OS 51.958875 -38.93318604
OS 51.94778028 -38.92671412
OS 51.93668556 -38.91839308
OS 51.92559084 -38.91007204
OS 51.92466628 -38.90914748
OS 51.92281716 -38.90729836
OS 51.92004348 -38.90452468
OS 51.9172698 -38.90082644
OS 51.912647 -38.89620364
OS 51.9080242 -38.88973172
OS 51.90247684 -38.8832598
OS 51.89692948 -38.87493876
OS 51.89138212 -38.86569316
OS 51.88583476 -38.85644756
OS 51.8756646 -38.83425812
OS 51.86734356 -38.80837044
OS 51.86456988 -38.79450204
OS 51.86272076 -38.77970908
OS 51.94130836 -38.76953892
OS 51.94130836 -38.77046348
OS 51.94223292 -38.7723126
OS 51.94315748 -38.77601084
OS 51.94408204 -38.78063364
OS 51.9450066 -38.786181
OS 51.94685572 -38.79265292
OS 51.95147852 -38.80652132
OS 51.95795044 -38.8231634
OS 51.96627148 -38.83888092
OS 51.97551708 -38.85367388
OS 51.9866118 -38.86661772
OS 51.98846092 -38.86754228
OS 51.99215916 -38.87124052
OS 51.99955564 -38.87586332
OS 52.00880124 -38.88048612
OS 52.01989596 -38.88603348
OS 52.03376436 -38.89065628
OS 52.04948188 -38.89435452
OS 52.06612396 -38.89527908
OS 52.07167132 -38.89527908
OS 52.07536956 -38.89435452
OS 52.08553972 -38.89342996
OS 52.09848356 -38.89065628
OS 52.11327652 -38.88603348
OS 52.12899404 -38.87956156
OS 52.14471156 -38.87031596
OS 52.15950452 -38.85737212
OS 52.16135364 -38.855523
OS 52.16597644 -38.84997564
OS 52.1715238 -38.8416546
OS 52.17892028 -38.83055988
OS 52.18631676 -38.81669148
OS 52.19186412 -38.80097396
OS 52.19648692 -38.78248276
OS 52.19833604 -38.76214244
OS 52.19833604 -38.76121788
OS 52.19833604 -38.75936876
OS 52.19833604 -38.75659508
OS 52.19741148 -38.75289684
OS 52.19648692 -38.74272668
OS 52.19371324 -38.7307074
OS 52.190015 -38.71591444
OS 52.18354308 -38.70112148
OS 52.17429748 -38.68632852
OS 52.1622782 -38.67246012
OS 52.16042908 -38.670611
OS 52.15580628 -38.66691276
OS 52.1484098 -38.6613654
OS 52.13823964 -38.65489348
OS 52.1252958 -38.64842156
OS 52.10957828 -38.6428742
OS 52.09201164 -38.63917596
OS 52.07259588 -38.63732684
OS 52.06427484 -38.63732684
OS 52.05780292 -38.6382514
OS 52.04948188 -38.63917596
OS 52.04023628 -38.64102508
OS 52.02914156 -38.6428742
OS 52.01712228 -38.64564788
OS 52.02636788 -38.57630588
OS 52.03099068 -38.57630588
OS 52.03468892 -38.57723044
OS 52.0467082 -38.57723044
OS 52.05687836 -38.57538132
OS 52.06889764 -38.5735322
OS 52.08276604 -38.57075852
OS 52.09848356 -38.56613572
OS 52.11327652 -38.5596638
OS 52.12899404 -38.55134276
OS 52.1299186 -38.55134276
OS 52.13084316 -38.5504182
OS 52.13546596 -38.54671996
OS 52.14193788 -38.54024804
OS 52.14933436 -38.531927
OS 52.15673084 -38.51990772
OS 52.16320276 -38.50603932
OS 52.16782556 -38.4903218
OS 52.16967468 -38.4810762
OS 52.16967468 -38.47090604
OS 52.16967468 -38.46998148
OS 52.16967468 -38.46905692
OS 52.16967468 -38.46350956
OS 52.16782556 -38.45611308
OS 52.16597644 -38.44594292
OS 52.1622782 -38.4348482
OS 52.1576554 -38.42282892
OS 52.15025892 -38.41080964
OS 52.14008876 -38.39971492
OS 52.1391642 -38.39879036
OS 52.1345414 -38.39509212
OS 52.12806948 -38.39046932
OS 52.11974844 -38.38492196
OS 52.10865372 -38.38029916
OS 52.09570988 -38.37567636
OS 52.08091692 -38.37197812
OS 52.06427484 -38.37105356
OS 52.05687836 -38.37105356
OS 52.04855732 -38.37290268
OS 52.0374626 -38.3747518
OS 52.02544332 -38.37845004
OS 52.01342404 -38.38307284
OS 52.0004802 -38.39046932
OS 51.98846092 -38.39971492
OS 51.98753636 -38.40063948
OS 51.98383812 -38.40526228
OS 51.97829076 -38.4117342
OS 51.97181884 -38.4209798
OS 51.96534692 -38.43299908
OS 51.958875 -38.44779204
OS 51.95332764 -38.46535868
OS 51.9496294 -38.485699
OS 51.8710418 -38.4718306
OS 51.8710418 -38.47090604
OS 51.87196636 -38.46813236
OS 51.87289092 -38.46443412
OS 51.87381548 -38.45888676
OS 51.8756646 -38.45241484
OS 51.87843828 -38.44501836
OS 51.88398564 -38.42745172
OS 51.89323124 -38.4071114
OS 51.90432596 -38.38677108
OS 51.91819436 -38.36735532
OS 51.935761 -38.34978868
OS 51.93668556 -38.34886412
OS 51.93853468 -38.34793956
OS 51.94130836 -38.34609044
OS 51.9450066 -38.34331676
OS 51.9496294 -38.33961852
OS 51.95610132 -38.33592028
OS 51.96257324 -38.33222204
OS 51.97089428 -38.32759924
OS 51.98938548 -38.32020276
OS 52.01065036 -38.31280628
OS 52.03561348 -38.30818348
OS 52.04855732 -38.30633436
OS 52.07167132 -38.30633436
OS 52.08184148 -38.30725892
OE
OB 51.07499564 -38.37105356 H
OS 51.06944828 -38.37105356
OS 51.06575004 -38.37197812
OS 51.05557988 -38.37382724
OS 51.0435606 -38.37660092
OS 51.0296922 -38.38214828
OS 51.01489924 -38.39046932
OS 51.00750276 -38.39601668
OS 51.00010628 -38.40156404
OS 50.99363436 -38.40896052
OS 50.98716244 -38.41728156
OS 50.98716244 -38.41820612
OS 50.98531332 -38.42005524
OS 50.9834642 -38.42375348
OS 50.98069052 -38.42837628
OS 50.97791684 -38.43577276
OS 50.9742186 -38.4440938
OS 50.97144492 -38.45426396
OS 50.96774668 -38.46628324
OS 50.96404844 -38.48015164
OS 50.9603502 -38.49586916
OS 50.95665196 -38.5134358
OS 50.95387828 -38.53285156
OS 50.9511046 -38.555041
OS 50.94925548 -38.57907956
OS 50.94833092 -38.60496724
OS 50.94740636 -38.6336286
OS 50.94740636 -38.63547772
OS 50.94740636 -38.64010052
OS 50.94740636 -38.64842156
OS 50.94833092 -38.65951628
OS 50.94833092 -38.67153556
OS 50.94925548 -38.68632852
OS 50.95018004 -38.70204604
OS 50.95202916 -38.71868812
OS 50.95665196 -38.75474596
OS 50.95942564 -38.7723126
OS 50.96312388 -38.78895468
OS 50.96682212 -38.8046722
OS 50.97236948 -38.81946516
OS 50.97791684 -38.832409
OS 50.98438876 -38.84350372
OS 50.98438876 -38.84442828
OS 50.98623788 -38.84535284
OS 50.99086068 -38.85182476
OS 50.99918172 -38.8601458
OS 51.00935188 -38.8693914
OS 51.02322028 -38.878637
OS 51.0389378 -38.88695804
OS 51.05650444 -38.89342996
OS 51.06575004 -38.89435452
OS 51.0759202 -38.89527908
OS 51.08146756 -38.89527908
OS 51.0851658 -38.89435452
OS 51.0944114 -38.8925054
OS 51.10735524 -38.88880716
OS 51.12122364 -38.88233524
OS 51.13694116 -38.87308964
OS 51.14433764 -38.86754228
OS 51.15173412 -38.8601458
OS 51.1591306 -38.85274932
OS 51.16652708 -38.84350372
OS 51.16652708 -38.84257916
OS 51.1683762 -38.84073004
OS 51.17022532 -38.83795636
OS 51.17207444 -38.83333356
OS 51.17577268 -38.82686164
OS 51.17854636 -38.8185406
OS 51.1822446 -38.809295
OS 51.18594284 -38.79820028
OS 51.18871652 -38.78433188
OS 51.19241476 -38.76953892
OS 51.196113 -38.75197228
OS 51.19888668 -38.73348108
OS 51.2007358 -38.71129164
OS 51.20258492 -38.68817764
OS 51.20443404 -38.66228996
OS 51.20443404 -38.6336286
OS 51.20443404 -38.63270404
OS 51.20443404 -38.63177948
OS 51.20443404 -38.62715668
OS 51.20443404 -38.61883564
OS 51.20350948 -38.60774092
OS 51.20350948 -38.59572164
OS 51.20258492 -38.58092868
OS 51.20166036 -38.56521116
OS 51.19981124 -38.54764452
OS 51.19518844 -38.51251124
OS 51.19241476 -38.4949446
OS 51.18871652 -38.47830252
OS 51.18501828 -38.462585
OS 51.17947092 -38.44779204
OS 51.17392356 -38.4348482
OS 51.16745164 -38.42375348
OS 51.16745164 -38.42282892
OS 51.16560252 -38.42190436
OS 51.1637534 -38.41913068
OS 51.16097972 -38.41543244
OS 51.15265868 -38.4071114
OS 51.14248852 -38.39694124
OS 51.12862012 -38.38769564
OS 51.1129026 -38.3793746
OS 51.10458156 -38.37567636
OS 51.09533596 -38.37290268
OS 51.0851658 -38.37197812
OS 51.07499564 -38.37105356
OE
OB 54.05947532 -38.37105356 H
OS 54.05392796 -38.37105356
OS 54.05022972 -38.37197812
OS 54.04005956 -38.37382724
OS 54.02804028 -38.37660092
OS 54.01417188 -38.38214828
OS 53.99937892 -38.39046932
OS 53.99198244 -38.39601668
OS 53.98458596 -38.40156404
OS 53.97811404 -38.40896052
OS 53.97164212 -38.41728156
OS 53.97164212 -38.41820612
OS 53.969793 -38.42005524
OS 53.96794388 -38.42375348
OS 53.9651702 -38.42837628
OS 53.96239652 -38.43577276
OS 53.95869828 -38.4440938
OS 53.9559246 -38.45426396
OS 53.95222636 -38.46628324
OS 53.94852812 -38.48015164
OS 53.94482988 -38.49586916
OS 53.94113164 -38.5134358
OS 53.93835796 -38.53285156
OS 53.93558428 -38.555041
OS 53.93373516 -38.57907956
OS 53.9328106 -38.60496724
OS 53.93188604 -38.6336286
OS 53.93188604 -38.63547772
OS 53.93188604 -38.64010052
OS 53.93188604 -38.64842156
OS 53.9328106 -38.65951628
OS 53.9328106 -38.67153556
OS 53.93373516 -38.68632852
OS 53.93465972 -38.70204604
OS 53.93650884 -38.71868812
OS 53.94113164 -38.75474596
OS 53.94390532 -38.7723126
OS 53.94760356 -38.78895468
OS 53.9513018 -38.8046722
OS 53.95684916 -38.81946516
OS 53.96239652 -38.832409
OS 53.96886844 -38.84350372
OS 53.96886844 -38.84442828
OS 53.97071756 -38.84535284
OS 53.97534036 -38.85182476
OS 53.9836614 -38.8601458
OS 53.99383156 -38.8693914
OS 54.00769996 -38.878637
OS 54.02341748 -38.88695804
OS 54.04098412 -38.89342996
OS 54.05022972 -38.89435452
OS 54.06039988 -38.89527908
OS 54.06594724 -38.89527908
OS 54.06964548 -38.89435452
OS 54.07889108 -38.8925054
OS 54.09183492 -38.88880716
OS 54.10570332 -38.88233524
OS 54.12142084 -38.87308964
OS 54.12881732 -38.86754228
OS 54.1362138 -38.8601458
OS 54.14361028 -38.85274932
OS 54.15100676 -38.84350372
OS 54.15100676 -38.84257916
OS 54.15285588 -38.84073004
OS 54.154705 -38.83795636
OS 54.15655412 -38.83333356
OS 54.16025236 -38.82686164
OS 54.16302604 -38.8185406
OS 54.16672428 -38.809295
OS 54.17042252 -38.79820028
OS 54.1731962 -38.78433188
OS 54.17689444 -38.76953892
OS 54.18059268 -38.75197228
OS 54.18336636 -38.73348108
OS 54.18521548 -38.71129164
OS 54.1870646 -38.68817764
OS 54.18891372 -38.66228996
OS 54.18891372 -38.6336286
OS 54.18891372 -38.63270404
OS 54.18891372 -38.63177948
OS 54.18891372 -38.62715668
OS 54.18891372 -38.61883564
OS 54.18798916 -38.60774092
OS 54.18798916 -38.59572164
OS 54.1870646 -38.58092868
OS 54.18614004 -38.56521116
OS 54.18429092 -38.54764452
OS 54.17966812 -38.51251124
OS 54.17689444 -38.4949446
OS 54.1731962 -38.47830252
OS 54.16949796 -38.462585
OS 54.1639506 -38.44779204
OS 54.15840324 -38.4348482
OS 54.15193132 -38.42375348
OS 54.15193132 -38.42282892
OS 54.1500822 -38.42190436
OS 54.14823308 -38.41913068
OS 54.1454594 -38.41543244
OS 54.13713836 -38.4071114
OS 54.1269682 -38.39694124
OS 54.1130998 -38.38769564
OS 54.09738228 -38.3793746
OS 54.08906124 -38.37567636
OS 54.07981564 -38.37290268
OS 54.06964548 -38.37197812
OS 54.05947532 -38.37105356
OE
OB 49.87491676 -38.43669732 H
OS 49.67336268 -38.72331092
OS 49.87491676 -38.72331092
OS 49.87491676 -38.43669732
OE
OB 56.14158444 -38.38492196 H
OS 55.95852156 -38.38492196
OS 55.95852156 -38.61328828
OS 56.13048972 -38.61328828
OS 56.13696164 -38.61236372
OS 56.14343356 -38.61236372
OS 56.15083004 -38.61143916
OS 56.16839668 -38.60959004
OS 56.18781244 -38.6058918
OS 56.2072282 -38.60034444
OS 56.22479484 -38.59294796
OS 56.23311588 -38.58832516
OS 56.2395878 -38.5827778
OS 56.24143692 -38.58092868
OS 56.24513516 -38.57723044
OS 56.25068252 -38.56983396
OS 56.25715444 -38.56058836
OS 56.26362636 -38.54856908
OS 56.26917372 -38.53377612
OS 56.27287196 -38.51713404
OS 56.27472108 -38.49771828
OS 56.27472108 -38.49679372
OS 56.27472108 -38.49586916
OS 56.27472108 -38.49124636
OS 56.27379652 -38.48292532
OS 56.2719474 -38.47367972
OS 56.27009828 -38.46350956
OS 56.26640004 -38.45149028
OS 56.26085268 -38.44039556
OS 56.25438076 -38.42930084
OS 56.2534562 -38.42837628
OS 56.25068252 -38.42467804
OS 56.24605972 -38.42005524
OS 56.24051236 -38.41358332
OS 56.23219132 -38.4071114
OS 56.22294572 -38.40156404
OS 56.21277556 -38.39601668
OS 56.20075628 -38.39139388
OS 56.19983172 -38.39139388
OS 56.19613348 -38.39046932
OS 56.19058612 -38.38954476
OS 56.18318964 -38.38769564
OS 56.17209492 -38.38677108
OS 56.15822652 -38.38584652
OS 56.14158444 -38.38492196
OE
SE
P -2.99999908 16.00000102 27 P 0 0 ;0=21,1=1
P -2.99999908 17.99999956 27 P 0 0 ;0=21,1=1
P -2.99999908 20.00000064 27 P 0 0 ;0=21,1=1
P -2.99999908 21.99999918 27 P 0 0 ;0=21,1=1
P -2.99999908 24.00000026 27 P 0 0 ;0=21,1=1
P -2.99999908 25.9999988 27 P 0 0 ;0=21,1=1
P -2.99999908 27.99999988 27 P 0 0 ;0=21,1=1
P -2.99999908 30.00000096 27 P 0 0 ;0=21,1=1
P -2.99999908 31.9999995 27 P 0 0 ;0=21,1=1
P -2.99999908 34.00000058 27 P 0 0 ;0=21,1=1
P -2.99999908 35.99999912 27 P 0 0 ;0=21,1=1
P -2.99999908 38.0000002 27 P 0 0 ;0=21,1=1
P -2.99999908 39.99999874 27 P 0 0 ;0=21,1=1
P 0.50000154 -3.99999962 27 P 0 0 ;0=21,1=1
P 2.50000008 -3.99999962 27 P 0 0 ;0=21,1=1
P 4.50000116 -3.99999962 27 P 0 0 ;0=21,1=1
P 6.4999997 -3.99999962 27 P 0 0 ;0=21,1=1
P 8.50000078 -3.99999962 27 P 0 0 ;0=21,1=1
P 10.49999932 -3.99999962 27 P 0 0 ;0=21,1=1
P 12.5000004 -3.99999962 27 P 0 0 ;0=21,1=1
P 12.74500118 40.26499948 27 P 0 0 ;0=21,1=1
P 12.74500118 41.21500012 27 P 0 0 ;0=21,1=1
P 12.74500118 44.63999962 27 P 0 0 ;0=21,1=1
P 12.75500116 42.16500076 27 P 0 0 ;0=21,1=1
P 12.98999942 18.0150008 27 P 0 0 ;0=21,1=1
P 14.50000148 -3.99999962 27 P 0 0 ;0=21,1=1
P 15.88470534 21.56499878 27 P 0 0 ;0=21,1=1
P 16.30970576 23.03999964 27 P 0 0 ;0=21,1=1
P 16.50000002 -3.99999962 27 P 0 0 ;0=21,1=1
P 17.57500168 13.89000016 27 P 0 0 ;0=21,1=1
P 17.915001 15.69625258 27 P 0 0 ;0=21,1=1
P 18.8149992 15.10000028 27 P 0 0 ;0=21,1=1
P 18.8149992 15.98270108 27 P 0 0 ;0=21,1=1
P 18.8149992 16.85250122 27 P 0 0 ;0=21,1=1
P 19.01500134 7.39000046 27 P 0 0 ;0=21,1=1
P 19.01500134 8.5900006 27 P 0 0 ;0=21,1=1
P 19.01500134 9.7899982 27 P 0 0 ;0=21,1=1
P 19.01500134 11.09000068 27 P 0 0 ;0=21,1=1
P 19.01500134 12.39000062 27 P 0 0 ;0=21,1=1
P 21.11499968 6.76500044 27 P 0 0 ;0=21,1=1
P 21.11499968 7.78999966 27 P 0 0 ;0=21,1=1
P 21.11499968 8.9899998 27 P 0 0 ;0=21,1=1
P 21.11499968 10.28999974 27 P 0 0 ;0=21,1=1
P 21.11499968 11.38590052 27 P 0 0 ;0=21,1=1
P 22.05919388 12.29000082 27 P 0 0 ;0=21,1=1
P 22.45970616 20.01499934 27 P 0 0 ;0=21,1=1
P 23.29999912 38.90000094 27 P 0 0 ;0=21,1=1
P 23.33999904 44.0138312 27 P 0 0 ;0=21,1=1
P 23.4097068 20.04000056 27 P 0 0 ;0=21,1=1
P 24.35970744 20.04000056 27 P 0 0 ;0=21,1=1
P 24.49999926 -3.50000062 27 P 0 0 ;0=21,1=1
P 25.7999992 38.90000094 27 P 0 0 ;0=21,1=1
P 26.50000034 -3.50000062 27 P 0 0 ;0=21,1=1
P 28.50000142 -3.50000062 27 P 0 0 ;0=21,1=1
P 30.49999996 -3.50000062 27 P 0 0 ;0=21,1=1
P 32.50000104 -3.50000062 27 P 0 0 ;0=21,1=1
P 32.80000044 38.90000094 27 P 0 0 ;0=21,1=1
P 35.30000052 44.0000009 27 P 0 0 ;0=21,1=1
P 38.4999992 -3.50000062 27 P 0 0 ;0=21,1=1
P 39.60000208 38.91499964 27 P 0 0 ;0=21,1=1
P 40.50000028 -3.50000062 27 P 0 0 ;0=21,1=1
P 40.67999992 42.76499956 27 P 0 0 ;0=21,1=1
P 42.2249981 38.91499964 27 P 0 0 ;0=21,1=1
P 44.4999999 0.499999 27 P 0 0 ;0=21,1=1
P 44.4999999 2.50000008 27 P 0 0 ;0=21,1=1
P 44.4999999 4.49999862 27 P 0 0 ;0=21,1=1
P 44.4999999 6.4999997 27 P 0 0 ;0=21,1=1
P 44.4999999 8.49999824 27 P 0 0 ;0=21,1=1
P 44.4999999 10.49999932 27 P 0 0 ;0=21,1=1
P 44.4999999 12.49999786 27 P 0 0 ;0=21,1=1
P 44.4999999 14.49999894 27 P 0 0 ;0=21,1=1
P 44.4999999 16.50000002 27 P 0 0 ;0=21,1=1
P 44.4999999 18.49999856 27 P 0 0 ;0=21,1=1
P 44.4999999 20.49999964 27 P 0 0 ;0=21,1=1
P 44.4999999 22.49999818 27 P 0 0 ;0=21,1=1
P 44.4999999 24.49999926 27 P 0 0 ;0=21,1=1
P 44.4999999 26.4999978 27 P 0 0 ;0=21,1=1
P 44.4999999 28.49999888 27 P 0 0 ;0=21,1=1
P 44.4999999 30.49999996 27 P 0 0 ;0=21,1=1
P 44.4999999 32.4999985 27 P 0 0 ;0=21,1=1
P 44.4999999 34.49999958 27 P 0 0 ;0=21,1=1
P 44.4999999 36.49999812 27 P 0 0 ;0=21,1=1
P 44.4999999 38.4999992 27 P 0 0 ;0=21,1=1
P 44.4999999 40.49999774 27 P 0 0 ;0=21,1=1

### steps/pcb/layers/top_overlay/features
UNITS=MM
#Layer_Color=65535
#
#Feature symbol names
#
$0 r99.9998

#
#Feature attribute names
#
@0 .nomenclature
@1 .string
@2 .string_angle

#
#Feature attribute text strings
#

#
#Layer features
#
L -9.5600012 -24.45999934 40.4400004 -24.45999934 0 P 0
L -9.5600012 -35.9599992 -9.5600012 -24.45999934 0 P 0
L -9.5600012 -35.9599992 28.439999 -35.9599992 0 P 0
L -9.5600012 -39.45999982 -9.5600012 -35.9599992 0 P 0
L -9.5600012 -39.45999982 28.439999 -39.45999982 0 P 0
L -9.5600012 -42.96000044 -9.5600012 -39.45999982 0 P 0
L -9.5600012 -42.96000044 28.439999 -42.96000044 0 P 0
L -10.0600002 -23.96000034 62.93999858 -23.96000034 0 P 0
L -10.0600002 -43.45999944 -10.0600002 -23.96000034 0 P 0
L -10.0600002 -43.45999944 62.93999858 -43.45999944 0 P 0
L 28.439999 -35.96000174 45.44000056 -35.9599992 0 P 0
L 28.439999 -39.45999982 28.439999 -35.9599992 0 P 0
L 28.439999 -39.46000236 45.44000056 -39.45999982 0 P 0
L 28.439999 -42.96000044 28.439999 -39.45999982 0 P 0
L 28.439999 -42.96000298 45.44000056 -42.96000044 0 P 0
L 40.4400004 -24.45999934 62.43999958 -24.45999934 0 P 0
L 40.4400004 -35.9599992 40.4400004 -24.45999934 0 P 0
L 45.44000056 -35.9599992 62.43999958 -35.9599992 0 P 0
L 45.44000056 -39.45999982 62.43999958 -39.45999982 0 P 0
L 45.44000056 -42.96000044 45.44000056 -35.9599992 0 P 0
L 45.44000056 -42.96000044 62.43999958 -42.96000044 0 P 0
L 62.43999958 -35.9599992 62.43999958 -24.45999934 0 P 0
L 62.43999958 -42.96000044 62.43999958 -35.9599992 0 P 0
L 62.93999858 -43.45999944 62.93999858 -23.96000034 0 P 0
S P 0
OB 0.7689596 36.47426284 I
OS 0.690372 36.47426284
OS 0.690372 36.9744498
OS 0.68944744 36.97352524
OS 0.68482464 36.969827
OS 0.67927728 36.96427964
OS 0.67003168 36.95780772
OS 0.65986152 36.94948668
OS 0.64691768 36.94024108
OS 0.63212472 36.93007092
OS 0.61548264 36.91990076
OS 0.61455808 36.91990076
OS 0.61363352 36.9189762
OS 0.60808616 36.91527796
OS 0.59884056 36.91065516
OS 0.58774584 36.9051078
OS 0.574802 36.89863588
OS 0.5609336 36.89216396
OS 0.5470652 36.88569204
OS 0.5331968 36.88014468
OS 0.5331968 36.9559586
OS 0.53412136 36.9559586
OS 0.53597048 36.95780772
OS 0.53966872 36.95873228
OS 0.54429152 36.96150596
OS 0.54983888 36.96427964
OS 0.5563108 36.96797788
OS 0.57202832 36.97722348
OS 0.59051952 36.98739364
OS 0.60901072 37.00033748
OS 0.62842648 37.01513044
OS 0.64784224 37.03084796
OS 0.6487668 37.03177252
OS 0.64969136 37.03269708
OS 0.65246504 37.03547076
OS 0.65616328 37.03824444
OS 0.66448432 37.04749004
OS 0.67557904 37.05858476
OS 0.68667376 37.0715286
OS 0.69869304 37.08632156
OS 0.7088632 37.10111452
OS 0.7181088 37.11683204
OS 0.7689596 37.11683204
OS 0.7689596 36.47426284
OE
OB 0.36400232 36.74423436 I
OS 0.36400232 36.7433098
OS 0.36400232 36.73961156
OS 0.36400232 36.73498876
OS 0.36400232 36.72851684
OS 0.36307776 36.7201958
OS 0.36307776 36.7109502
OS 0.3621532 36.69985548
OS 0.36122864 36.68876076
OS 0.35845496 36.66379764
OS 0.35475672 36.63790996
OS 0.34920936 36.61294684
OS 0.34551112 36.60092756
OS 0.34181288 36.58983284
OS 0.34181288 36.58890828
OS 0.34088832 36.58705916
OS 0.3390392 36.58428548
OS 0.33719008 36.58058724
OS 0.33164272 36.57041708
OS 0.32332168 36.55747324
OS 0.31222696 36.54268028
OS 0.29928312 36.52788732
OS 0.28264104 36.5121698
OS 0.26230072 36.4983014
OS 0.26137616 36.4983014
OS 0.25952704 36.49645228
OS 0.25675336 36.49552772
OS 0.25213056 36.49275404
OS 0.2465832 36.48998036
OS 0.23918672 36.48720668
OS 0.23179024 36.484433
OS 0.22254464 36.48073476
OS 0.21237448 36.47703652
OS 0.20127976 36.47426284
OS 0.18926048 36.47148916
OS 0.17539208 36.46871548
OS 0.16152368 36.46686636
OS 0.14673072 36.46501724
OS 0.11344656 36.46316812
OS 0.10512552 36.46316812
OS 0.0986536 36.46409268
OS 0.09125712 36.46409268
OS 0.08201152 36.46501724
OS 0.07184136 36.4659418
OS 0.0616712 36.46686636
OS 0.0385572 36.4705646
OS 0.01359408 36.47611196
OS -0.01044448 36.48350844
OS -0.03355848 36.4936786
OS -0.03448304 36.4936786
OS -0.03633216 36.49552772
OS -0.03910584 36.49737684
OS -0.04280408 36.49922596
OS -0.05297424 36.50662244
OS -0.06499352 36.5167926
OS -0.07886192 36.52973644
OS -0.09180576 36.5445294
OS -0.1047496 36.5630206
OS -0.11491976 36.58336092
OS -0.11491976 36.58428548
OS -0.11584432 36.5861346
OS -0.11676888 36.58983284
OS -0.118618 36.59445564
OS -0.12046712 36.600003
OS -0.12231624 36.60739948
OS -0.12508992 36.61572052
OS -0.12693904 36.62589068
OS -0.12878816 36.6369854
OS -0.13156184 36.64900468
OS -0.13341096 36.66194852
OS -0.13526008 36.67581692
OS -0.1371092 36.69153444
OS -0.13803376 36.70817652
OS -0.13895832 36.72574316
OS -0.13895832 36.74423436
OS -0.13895832 37.11405836
OS -0.0538988 37.11405836
OS -0.0538988 36.74423436
OS -0.0538988 36.7433098
OS -0.0538988 36.74053612
OS -0.0538988 36.73591332
OS -0.0538988 36.73036596
OS -0.05297424 36.72389404
OS -0.05297424 36.715573
OS -0.05204968 36.69800636
OS -0.05020056 36.67766604
OS -0.04742688 36.65732572
OS -0.04372864 36.63790996
OS -0.04187952 36.62958892
OS -0.03910584 36.62126788
OS -0.03818128 36.61941876
OS -0.03633216 36.61479596
OS -0.03170936 36.60832404
OS -0.026162 36.59907844
OS -0.01969008 36.58983284
OS -0.01044448 36.57966268
OS 0.00065024 36.56949252
OS 0.01359408 36.56117148
OS 0.0154432 36.56024692
OS 0.020066 36.55747324
OS 0.02838704 36.55469956
OS 0.03948176 36.55100132
OS 0.0524256 36.54637852
OS 0.06906768 36.54360484
OS 0.08663432 36.54083116
OS 0.10605008 36.5399066
OS 0.11529568 36.5399066
OS 0.12084304 36.54083116
OS 0.12916408 36.54083116
OS 0.13748512 36.54175572
OS 0.15782544 36.54545396
OS 0.18001488 36.55007676
OS 0.20127976 36.55747324
OS 0.22162008 36.5676434
OS 0.23086568 36.57411532
OS 0.23918672 36.5815118
OS 0.24011128 36.58243636
OS 0.24103584 36.58336092
OS 0.24288496 36.5861346
OS 0.24565864 36.58983284
OS 0.24843232 36.5953802
OS 0.25213056 36.60092756
OS 0.2558288 36.6092486
OS 0.25952704 36.61756964
OS 0.26322528 36.6277398
OS 0.26599896 36.63975908
OS 0.2696972 36.65362748
OS 0.27247088 36.66842044
OS 0.27524456 36.68506252
OS 0.27709368 36.70262916
OS 0.2789428 36.72296948
OS 0.2789428 36.74423436
OS 0.2789428 37.11405836
OS 0.36400232 37.11405836
OS 0.36400232 36.74423436
OE
SE
S P 0
OB -1.6831691 38.2909064 I
OS -1.67577262 38.28998184
OS -1.66652702 38.28905728
OS -1.65635686 38.28720816
OS -1.6461867 38.28535904
OS -1.62214814 38.27888712
OS -1.59810958 38.26964152
OS -1.5860903 38.26409416
OS -1.57407102 38.25762224
OS -1.5629763 38.2493012
OS -1.55280614 38.2400556
OS -1.55188158 38.23913104
OS -1.55003246 38.23820648
OS -1.54818334 38.23450824
OS -1.5444851 38.23081
OS -1.5398623 38.2261872
OS -1.5352395 38.21971528
OS -1.5306167 38.21324336
OS -1.52506934 38.20492232
OS -1.51582374 38.18735568
OS -1.50657814 38.16516624
OS -1.5028799 38.15407152
OS -1.50103078 38.14112768
OS -1.49918166 38.12818384
OS -1.4982571 38.11431544
OS -1.4982571 38.11246632
OS -1.4982571 38.10784352
OS -1.49918166 38.10044704
OS -1.50010622 38.09027688
OS -1.50195534 38.07918216
OS -1.50565358 38.06623832
OS -1.50935182 38.05236992
OS -1.51489918 38.03850152
OS -1.51582374 38.0366524
OS -1.51767286 38.0320296
OS -1.5213711 38.02463312
OS -1.52691846 38.01446296
OS -1.53431494 38.00336824
OS -1.54356054 37.98949984
OS -1.55465526 37.97563144
OS -1.5675991 37.95991392
OS -1.56944822 37.9580648
OS -1.57407102 37.95251744
OS -1.57869382 37.94789464
OS -1.58331662 37.94327184
OS -1.58886398 37.93772448
OS -1.59626046 37.930328
OS -1.60365694 37.92293152
OS -1.61290254 37.91461048
OS -1.62214814 37.90536488
OS -1.63324286 37.89519472
OS -1.64526214 37.88502456
OS -1.65820598 37.87300528
OS -1.67299894 37.860986
OS -1.6877919 37.84804216
OS -1.68871646 37.8471176
OS -1.69056558 37.84526848
OS -1.69426382 37.8424948
OS -1.69888662 37.83879656
OS -1.70443398 37.8332492
OS -1.7109059 37.82770184
OS -1.72569886 37.81568256
OS -1.74141638 37.80181416
OS -1.75620934 37.78794576
OS -1.76915318 37.77592648
OS -1.77470054 37.77130368
OS -1.77932334 37.76668088
OS -1.7802479 37.76575632
OS -1.78302158 37.76298264
OS -1.78671982 37.7592844
OS -1.79134262 37.75373704
OS -1.79596542 37.74726512
OS -1.80151278 37.7407932
OS -1.8126075 37.72507568
OS -1.49733254 37.72507568
OS -1.49733254 37.64926176
OS -1.92170558 37.64926176
OS -1.92170558 37.65018632
OS -1.92170558 37.65388456
OS -1.92170558 37.65943192
OS -1.92078102 37.6668284
OS -1.91985646 37.67514944
OS -1.91800734 37.68439504
OS -1.91615822 37.69364064
OS -1.91245998 37.7038108
OS -1.91245998 37.70473536
OS -1.91153542 37.70565992
OS -1.9096863 37.71120728
OS -1.90598806 37.71952832
OS -1.9004407 37.73062304
OS -1.89304422 37.74356688
OS -1.88379862 37.75835984
OS -1.87362846 37.7731528
OS -1.86068462 37.78887032
OS -1.86068462 37.78979488
OS -1.8588355 37.79071944
OS -1.8542127 37.7962668
OS -1.84589166 37.80458784
OS -1.83387238 37.81660712
OS -1.82000398 37.83047552
OS -1.80243734 37.8471176
OS -1.78117246 37.8656088
OS -1.75805846 37.88502456
OS -1.7571339 37.88594912
OS -1.75343566 37.8887228
OS -1.7478883 37.8933456
OS -1.74141638 37.89889296
OS -1.73309534 37.90628944
OS -1.72292518 37.91461048
OS -1.71275502 37.92385608
OS -1.70073574 37.93402624
OS -1.67762174 37.95621568
OS -1.65450774 37.97840512
OS -1.64341302 37.98949984
OS -1.63324286 38.00059456
OS -1.62399726 38.01076472
OS -1.61660078 38.02093488
OS -1.61660078 38.02185944
OS -1.61475166 38.022784
OS -1.61290254 38.02555768
OS -1.61105342 38.02925592
OS -1.6045815 38.03942608
OS -1.59718502 38.05144536
OS -1.5907131 38.06623832
OS -1.58424118 38.08195584
OS -1.58054294 38.09952248
OS -1.57869382 38.11616456
OS -1.57869382 38.11708912
OS -1.57869382 38.11801368
OS -1.57961838 38.12356104
OS -1.58054294 38.13280664
OS -1.58331662 38.1429768
OS -1.58701486 38.15592064
OS -1.59348678 38.16886448
OS -1.60180782 38.18180832
OS -1.61290254 38.19475216
OS -1.61475166 38.19660128
OS -1.61937446 38.20029952
OS -1.62584638 38.20492232
OS -1.63601654 38.21139424
OS -1.64896038 38.2169416
OS -1.66375334 38.22248896
OS -1.68131998 38.2261872
OS -1.70073574 38.22711176
OS -1.7062831 38.22711176
OS -1.70998134 38.2261872
OS -1.72107606 38.22526264
OS -1.7340199 38.22248896
OS -1.7478883 38.21879072
OS -1.76360582 38.2123188
OS -1.77839878 38.20399776
OS -1.79226718 38.19290304
OS -1.7941163 38.19105392
OS -1.79781454 38.18643112
OS -1.8033619 38.17903464
OS -1.80890926 38.16793992
OS -1.81538118 38.15499608
OS -1.82092854 38.138354
OS -1.82462678 38.1198628
OS -1.8264759 38.09859792
OS -1.90691262 38.10691896
OS -1.90691262 38.10784352
OS -1.90598806 38.1106172
OS -1.90598806 38.11524
OS -1.9050635 38.12171192
OS -1.90321438 38.1291084
OS -1.90136526 38.13742944
OS -1.89859158 38.1475996
OS -1.8958179 38.15776976
OS -1.88842142 38.1799592
OS -1.8773267 38.20214864
OS -1.87085478 38.21324336
OS -1.86253374 38.22433808
OS -1.8542127 38.23450824
OS -1.8449671 38.24375384
OS -1.84404254 38.2446784
OS -1.84219342 38.24560296
OS -1.83941974 38.24837664
OS -1.83479694 38.25115032
OS -1.82924958 38.25484856
OS -1.82277766 38.2585468
OS -1.81538118 38.2631696
OS -1.80613558 38.2677924
OS -1.79596542 38.2724152
OS -1.7848707 38.277038
OS -1.77285142 38.28073624
OS -1.75990758 38.28443448
OS -1.74603918 38.28720816
OS -1.73124622 38.28998184
OS -1.7155287 38.2909064
OS -1.69888662 38.29183096
OS -1.68964102 38.29183096
OS -1.6831691 38.2909064
OE
OB -2.01970894 37.91923328 I
OS -2.01970894 37.91830872
OS -2.01970894 37.91461048
OS -2.01970894 37.90998768
OS -2.01970894 37.90351576
OS -2.0206335 37.89519472
OS -2.0206335 37.88594912
OS -2.02155806 37.8748544
OS -2.02248262 37.86375968
OS -2.0252563 37.83879656
OS -2.02895454 37.81290888
OS -2.0345019 37.78794576
OS -2.03820014 37.77592648
OS -2.04189838 37.76483176
OS -2.04189838 37.7639072
OS -2.04282294 37.76205808
OS -2.04467206 37.7592844
OS -2.04652118 37.75558616
OS -2.05206854 37.745416
OS -2.06038958 37.73247216
OS -2.0714843 37.7176792
OS -2.08442814 37.70288624
OS -2.10107022 37.68716872
OS -2.12141054 37.67330032
OS -2.1223351 37.67330032
OS -2.12418422 37.6714512
OS -2.1269579 37.67052664
OS -2.1315807 37.66775296
OS -2.13712806 37.66497928
OS -2.14452454 37.6622056
OS -2.15192102 37.65943192
OS -2.16116662 37.65573368
OS -2.17133678 37.65203544
OS -2.1824315 37.64926176
OS -2.19445078 37.64648808
OS -2.20831918 37.6437144
OS -2.22218758 37.64186528
OS -2.23698054 37.64001616
OS -2.2702647 37.63816704
OS -2.27858574 37.63816704
OS -2.28505766 37.6390916
OS -2.29245414 37.6390916
OS -2.30169974 37.64001616
OS -2.3118699 37.64094072
OS -2.32204006 37.64186528
OS -2.34515406 37.64556352
OS -2.37011718 37.65111088
OS -2.39415574 37.65850736
OS -2.41726974 37.66867752
OS -2.4181943 37.66867752
OS -2.42004342 37.67052664
OS -2.4228171 37.67237576
OS -2.42651534 37.67422488
OS -2.4366855 37.68162136
OS -2.44870478 37.69179152
OS -2.46257318 37.70473536
OS -2.47551702 37.71952832
OS -2.48846086 37.73801952
OS -2.49863102 37.75835984
OS -2.49863102 37.7592844
OS -2.49955558 37.76113352
OS -2.50048014 37.76483176
OS -2.50232926 37.76945456
OS -2.50417838 37.77500192
OS -2.5060275 37.7823984
OS -2.50880118 37.79071944
OS -2.5106503 37.8008896
OS -2.51249942 37.81198432
OS -2.5152731 37.8240036
OS -2.51712222 37.83694744
OS -2.51897134 37.85081584
OS -2.52082046 37.86653336
OS -2.52174502 37.88317544
OS -2.52266958 37.90074208
OS -2.52266958 37.91923328
OS -2.52266958 38.28905728
OS -2.43761006 38.28905728
OS -2.43761006 37.91923328
OS -2.43761006 37.91830872
OS -2.43761006 37.91553504
OS -2.43761006 37.91091224
OS -2.43761006 37.90536488
OS -2.4366855 37.89889296
OS -2.4366855 37.89057192
OS -2.43576094 37.87300528
OS -2.43391182 37.85266496
OS -2.43113814 37.83232464
OS -2.4274399 37.81290888
OS -2.42559078 37.80458784
OS -2.4228171 37.7962668
OS -2.42189254 37.79441768
OS -2.42004342 37.78979488
OS -2.41542062 37.78332296
OS -2.40987326 37.77407736
OS -2.40340134 37.76483176
OS -2.39415574 37.7546616
OS -2.38306102 37.74449144
OS -2.37011718 37.7361704
OS -2.36826806 37.73524584
OS -2.36364526 37.73247216
OS -2.35532422 37.72969848
OS -2.3442295 37.72600024
OS -2.33128566 37.72137744
OS -2.31464358 37.71860376
OS -2.29707694 37.71583008
OS -2.27766118 37.71490552
OS -2.26841558 37.71490552
OS -2.26286822 37.71583008
OS -2.25454718 37.71583008
OS -2.24622614 37.71675464
OS -2.22588582 37.72045288
OS -2.20369638 37.72507568
OS -2.1824315 37.73247216
OS -2.16209118 37.74264232
OS -2.15284558 37.74911424
OS -2.14452454 37.75651072
OS -2.14359998 37.75743528
OS -2.14267542 37.75835984
OS -2.1408263 37.76113352
OS -2.13805262 37.76483176
OS -2.13527894 37.77037912
OS -2.1315807 37.77592648
OS -2.12788246 37.78424752
OS -2.12418422 37.79256856
OS -2.12048598 37.80273872
OS -2.1177123 37.814758
OS -2.11401406 37.8286264
OS -2.11124038 37.84341936
OS -2.1084667 37.86006144
OS -2.10661758 37.87762808
OS -2.10476846 37.8979684
OS -2.10476846 37.91923328
OS -2.10476846 38.28905728
OS -2.01970894 38.28905728
OS -2.01970894 37.91923328
OE
SE
S P 0
OB -2.9784421 -38.48662356 I
OS -2.97104562 -38.48754812
OS -2.96180002 -38.48939724
OS -2.95162986 -38.49124636
OS -2.93961058 -38.49402004
OS -2.92851586 -38.49679372
OS -2.91557202 -38.50141652
OS -2.90355274 -38.50603932
OS -2.8906089 -38.51251124
OS -2.87766506 -38.51990772
OS -2.86472122 -38.52822876
OS -2.85270194 -38.53839892
OS -2.84160722 -38.54949364
OS -2.84068266 -38.5504182
OS -2.83883354 -38.55226732
OS -2.83605986 -38.55596556
OS -2.83236162 -38.56151292
OS -2.82773882 -38.56798484
OS -2.82311602 -38.57538132
OS -2.81756866 -38.58462692
OS -2.8120213 -38.59572164
OS -2.80647394 -38.60774092
OS -2.80092658 -38.62068476
OS -2.79630378 -38.63547772
OS -2.79168098 -38.65119524
OS -2.78798274 -38.66876188
OS -2.78520906 -38.68725308
OS -2.78335994 -38.70666884
OS -2.78243538 -38.72793372
OS -2.78243538 -38.72885828
OS -2.78243538 -38.73255652
OS -2.78243538 -38.73902844
OS -2.78335994 -38.74827404
OS -3.13006994 -38.74827404
OS -3.13006994 -38.7491986
OS -3.13006994 -38.75197228
OS -3.12914538 -38.75567052
OS -3.12914538 -38.76121788
OS -3.12822082 -38.7676898
OS -3.1263717 -38.77508628
OS -3.12359802 -38.79172836
OS -3.11805066 -38.81021956
OS -3.11065418 -38.83055988
OS -3.10048402 -38.84905108
OS -3.08754018 -38.86569316
OS -3.08661562 -38.86569316
OS -3.08569106 -38.86754228
OS -3.0801437 -38.87216508
OS -3.07182266 -38.878637
OS -3.06072794 -38.88510892
OS -3.04593498 -38.8925054
OS -3.0292929 -38.89897732
OS -3.0108017 -38.90360012
OS -3.00063154 -38.90452468
OS -2.98953682 -38.90544924
OS -2.98214034 -38.90544924
OS -2.9738193 -38.90452468
OS -2.96364914 -38.90267556
OS -2.95255442 -38.89990188
OS -2.93961058 -38.89620364
OS -2.9275913 -38.89065628
OS -2.91557202 -38.8832598
OS -2.91464746 -38.88233524
OS -2.91002466 -38.878637
OS -2.9044773 -38.87308964
OS -2.89800538 -38.86569316
OS -2.8906089 -38.855523
OS -2.88228786 -38.84257916
OS -2.87396682 -38.8277862
OS -2.86657034 -38.81021956
OS -2.78520906 -38.82038972
OS -2.78520906 -38.82131428
OS -2.78613362 -38.8231634
OS -2.78705818 -38.82686164
OS -2.7889073 -38.832409
OS -2.79168098 -38.83795636
OS -2.79445466 -38.84535284
OS -2.80185114 -38.86107036
OS -2.81109674 -38.878637
OS -2.82404058 -38.8971282
OS -2.83883354 -38.91469484
OS -2.85732474 -38.93133692
OS -2.8582493 -38.93133692
OS -2.86009842 -38.93318604
OS -2.8628721 -38.93503516
OS -2.86657034 -38.93780884
OS -2.8721177 -38.94058252
OS -2.87766506 -38.9433562
OS -2.88506154 -38.94705444
OS -2.89338258 -38.95075268
OS -2.90262818 -38.95445092
OS -2.91187378 -38.95814916
OS -2.93498778 -38.96369652
OS -2.96087546 -38.96831932
OS -2.98953682 -38.97016844
OS -2.99970698 -38.97016844
OS -3.0061789 -38.96924388
OS -3.01449994 -38.96831932
OS -3.0246701 -38.9664702
OS -3.03576482 -38.96462108
OS -3.0477841 -38.96277196
OS -3.07367178 -38.95537548
OS -3.08754018 -38.94982812
OS -3.10048402 -38.94428076
OS -3.11435242 -38.93688428
OS -3.12729626 -38.92856324
OS -3.13931554 -38.91931764
OS -3.15133482 -38.90822292
OS -3.15225938 -38.90729836
OS -3.1541085 -38.90544924
OS -3.15688218 -38.901751
OS -3.16058042 -38.89620364
OS -3.16520322 -38.88973172
OS -3.16982602 -38.88233524
OS -3.17537338 -38.87308964
OS -3.18092074 -38.86291948
OS -3.1864681 -38.8509002
OS -3.19201546 -38.83795636
OS -3.19663826 -38.8231634
OS -3.20126106 -38.80744588
OS -3.2049593 -38.7908038
OS -3.20773298 -38.7723126
OS -3.2095821 -38.75289684
OS -3.21050666 -38.73255652
OS -3.21050666 -38.73163196
OS -3.21050666 -38.72700916
OS -3.21050666 -38.7214618
OS -3.2095821 -38.71314076
OS -3.20865754 -38.7029706
OS -3.20773298 -38.69187588
OS -3.20588386 -38.67893204
OS -3.20311018 -38.6659882
OS -3.1957137 -38.63640228
OS -3.1910909 -38.62160932
OS -3.18554354 -38.6058918
OS -3.17814706 -38.59109884
OS -3.16982602 -38.57723044
OS -3.16058042 -38.56336204
OS -3.15041026 -38.5504182
OS -3.1494857 -38.54949364
OS -3.14763658 -38.54764452
OS -3.14393834 -38.54487084
OS -3.13931554 -38.54024804
OS -3.13376818 -38.53562524
OS -3.1263717 -38.53007788
OS -3.11805066 -38.52360596
OS -3.1078805 -38.5180586
OS -3.09771034 -38.51158668
OS -3.08569106 -38.50603932
OS -3.07274722 -38.50049196
OS -3.05887882 -38.49586916
OS -3.04408586 -38.49124636
OS -3.02836834 -38.48847268
OS -3.01172626 -38.48662356
OS -2.99415962 -38.485699
OS -2.98491402 -38.485699
OS -2.9784421 -38.48662356
OE
OB -2.50136914 -38.48662356 I
OS -2.49119898 -38.48847268
OS -2.4791797 -38.49217092
OS -2.46623586 -38.49679372
OS -2.4514429 -38.50326564
OS -2.43572538 -38.51158668
OS -2.46438674 -38.58370236
OS -2.4653113 -38.5827778
OS -2.46900954 -38.58092868
OS -2.4745569 -38.578155
OS -2.48195338 -38.57538132
OS -2.49027442 -38.57260764
OS -2.50044458 -38.56983396
OS -2.51061474 -38.56798484
OS -2.5207849 -38.56706028
OS -2.5254077 -38.56706028
OS -2.5300305 -38.56798484
OS -2.53650242 -38.5689094
OS -2.54297434 -38.57075852
OS -2.55129538 -38.5735322
OS -2.55961642 -38.57723044
OS -2.5670129 -38.5827778
OS -2.56793746 -38.58370236
OS -2.57071114 -38.58555148
OS -2.57348482 -38.58924972
OS -2.57810762 -38.59387252
OS -2.58273042 -38.60034444
OS -2.58735322 -38.60774092
OS -2.59197602 -38.61606196
OS -2.59567426 -38.62623212
OS -2.59659882 -38.62808124
OS -2.59752338 -38.6336286
OS -2.5993725 -38.64194964
OS -2.60214618 -38.65304436
OS -2.60491986 -38.66691276
OS -2.60676898 -38.68263028
OS -2.60769354 -38.69927236
OS -2.6086181 -38.71776356
OS -2.6086181 -38.95999828
OS -2.6872057 -38.95999828
OS -2.6872057 -38.49586916
OS -2.61601458 -38.49586916
OS -2.61601458 -38.56613572
OS -2.61509002 -38.56521116
OS -2.61139178 -38.55873924
OS -2.60676898 -38.5504182
OS -2.5993725 -38.54024804
OS -2.59197602 -38.53007788
OS -2.58365498 -38.51898316
OS -2.57533394 -38.50973756
OS -2.5670129 -38.50234108
OS -2.56608834 -38.50141652
OS -2.56331466 -38.4995674
OS -2.5577673 -38.49679372
OS -2.55221994 -38.49402004
OS -2.54482346 -38.49124636
OS -2.53557786 -38.48847268
OS -2.52633226 -38.48662356
OS -2.5161621 -38.485699
OS -2.50969018 -38.485699
OS -2.50136914 -38.48662356
OE
OB -3.92519154 -38.48662356 I
OS -3.9168705 -38.48754812
OS -3.9076249 -38.48939724
OS -3.89745474 -38.49124636
OS -3.88543546 -38.49309548
OS -3.86047234 -38.50141652
OS -3.8475285 -38.50603932
OS -3.83458466 -38.51251124
OS -3.82164082 -38.51898316
OS -3.80869698 -38.52822876
OS -3.7966777 -38.53747436
OS -3.78465842 -38.54856908
OS -3.78373386 -38.54949364
OS -3.78188474 -38.55134276
OS -3.77911106 -38.555041
OS -3.77541282 -38.5596638
OS -3.77079002 -38.56613572
OS -3.76524266 -38.57445676
OS -3.7596953 -38.58370236
OS -3.75414794 -38.59387252
OS -3.74860058 -38.60496724
OS -3.74305322 -38.61883564
OS -3.73750586 -38.63270404
OS -3.73288306 -38.64842156
OS -3.72918482 -38.66506364
OS -3.72641114 -38.68263028
OS -3.72456202 -38.70112148
OS -3.72363746 -38.7214618
OS -3.72363746 -38.72238636
OS -3.72363746 -38.72516004
OS -3.72363746 -38.72978284
OS -3.72363746 -38.73625476
OS -3.72456202 -38.74365124
OS -3.72548658 -38.75289684
OS -3.72548658 -38.76214244
OS -3.7273357 -38.7723126
OS -3.73010938 -38.7954266
OS -3.73565674 -38.8185406
OS -3.74212866 -38.8416546
OS -3.75137426 -38.86291948
OS -3.75137426 -38.86384404
OS -3.75229882 -38.8647686
OS -3.75414794 -38.86754228
OS -3.75599706 -38.87124052
OS -3.76246898 -38.88048612
OS -3.77079002 -38.89158084
OS -3.78188474 -38.90452468
OS -3.79575314 -38.91746852
OS -3.81147066 -38.93041236
OS -3.82996186 -38.94243164
OS -3.83088642 -38.94243164
OS -3.83181098 -38.9433562
OS -3.83458466 -38.94520532
OS -3.83920746 -38.94705444
OS -3.84383026 -38.94890356
OS -3.84937762 -38.95075268
OS -3.86324602 -38.95630004
OS -3.87896354 -38.96092284
OS -3.8983793 -38.96554564
OS -3.91871962 -38.96924388
OS -3.94090906 -38.97016844
OS -3.95015466 -38.97016844
OS -3.95755114 -38.96924388
OS -3.96587218 -38.96831932
OS -3.97511778 -38.9664702
OS -3.9862125 -38.96462108
OS -3.99730722 -38.96277196
OS -4.02227034 -38.95537548
OS -4.03613874 -38.94982812
OS -4.04908258 -38.94428076
OS -4.06202642 -38.93688428
OS -4.07497026 -38.92856324
OS -4.08698954 -38.91931764
OS -4.09900882 -38.90822292
OS -4.09993338 -38.90729836
OS -4.1017825 -38.90544924
OS -4.10455618 -38.901751
OS -4.10825442 -38.89620364
OS -4.11287722 -38.88973172
OS -4.11750002 -38.88233524
OS -4.12304738 -38.87308964
OS -4.12859474 -38.86199492
OS -4.1341421 -38.84997564
OS -4.13968946 -38.83610724
OS -4.14431226 -38.82131428
OS -4.14893506 -38.80559676
OS -4.1526333 -38.78803012
OS -4.15540698 -38.76953892
OS -4.1572561 -38.7491986
OS -4.15818066 -38.72793372
OS -4.15818066 -38.7260846
OS -4.15818066 -38.72238636
OS -4.1572561 -38.71591444
OS -4.1572561 -38.70666884
OS -4.15633154 -38.69649868
OS -4.15448242 -38.68355484
OS -4.1526333 -38.670611
OS -4.14893506 -38.65581804
OS -4.14523682 -38.64102508
OS -4.14061402 -38.62530756
OS -4.13506666 -38.60866548
OS -4.12767018 -38.59294796
OS -4.1202737 -38.578155
OS -4.11010354 -38.56336204
OS -4.09993338 -38.54949364
OS -4.08698954 -38.53747436
OS -4.08606498 -38.5365498
OS -4.08421586 -38.53562524
OS -4.08051762 -38.53285156
OS -4.07589482 -38.52915332
OS -4.07034746 -38.52545508
OS -4.06295098 -38.52083228
OS -4.0555545 -38.51620948
OS -4.0463089 -38.51158668
OS -4.03613874 -38.50696388
OS -4.02504402 -38.50234108
OS -4.0000809 -38.49402004
OS -3.97141954 -38.48754812
OS -3.95662658 -38.48662356
OS -3.94090906 -38.485699
OS -3.93166346 -38.485699
OS -3.92519154 -38.48662356
OE
OB -3.43055194 -38.95999828 I
OS -3.5054413 -38.95999828
OS -3.68018314 -38.49586916
OS -3.59697274 -38.49586916
OS -3.49712026 -38.77416172
OS -3.49712026 -38.77508628
OS -3.4961957 -38.77601084
OS -3.49527114 -38.77878452
OS -3.49434658 -38.7815582
OS -3.4915729 -38.7908038
OS -3.48787466 -38.80282308
OS -3.48325186 -38.81669148
OS -3.4777045 -38.832409
OS -3.4730817 -38.84997564
OS -3.46753434 -38.86754228
OS -3.46660978 -38.86569316
OS -3.46568522 -38.86107036
OS -3.46291154 -38.85367388
OS -3.46013786 -38.84257916
OS -3.45551506 -38.83055988
OS -3.45089226 -38.81484236
OS -3.44442034 -38.79820028
OS -3.43794842 -38.77970908
OS -3.33532226 -38.49586916
OS -3.25396098 -38.49586916
OS -3.43055194 -38.95999828
OE
OB -1.48897594 -38.96739476 I
OS -1.48897594 -38.96831932
OS -1.4899005 -38.971093
OS -1.49174962 -38.97479124
OS -1.49359874 -38.97941404
OS -1.49637242 -38.98588596
OS -1.4991461 -38.99328244
OS -1.50561802 -39.00899996
OS -1.51208994 -39.0265666
OS -1.51948642 -39.04413324
OS -1.5268829 -39.05985076
OS -1.53058114 -39.06632268
OS -1.53335482 -39.0727946
OS -1.53427938 -39.07464372
OS -1.53705306 -39.07926652
OS -1.54167586 -39.08573844
OS -1.54722322 -39.09405948
OS -1.5546197 -39.10330508
OS -1.56294074 -39.11255068
OS -1.57126178 -39.12179628
OS -1.58143194 -39.12919276
OS -1.5823565 -39.13011732
OS -1.58605474 -39.13196644
OS -1.5916021 -39.13474012
OS -1.59992314 -39.13843836
OS -1.60916874 -39.1421366
OS -1.62026346 -39.14491028
OS -1.63228274 -39.1467594
OS -1.64615114 -39.14768396
OS -1.64984938 -39.14768396
OS -1.65447218 -39.1467594
OS -1.6609441 -39.1467594
OS -1.66834058 -39.14491028
OS -1.67666162 -39.14306116
OS -1.68590722 -39.14121204
OS -1.69607738 -39.1375138
OS -1.70439842 -39.06447356
OS -1.70347386 -39.06447356
OS -1.69977562 -39.06539812
OS -1.69515282 -39.06632268
OS -1.68960546 -39.0681718
OS -1.6748125 -39.07094548
OS -1.66001954 -39.07187004
OS -1.65539674 -39.07187004
OS -1.65077394 -39.07094548
OS -1.64522658 -39.07094548
OS -1.63135818 -39.0681718
OS -1.62488626 -39.06539812
OS -1.61841434 -39.06262444
OS -1.61748978 -39.06262444
OS -1.61564066 -39.06077532
OS -1.61286698 -39.0589262
OS -1.60916874 -39.05615252
OS -1.6008477 -39.04875604
OS -1.59345122 -39.03858588
OS -1.59345122 -39.03766132
OS -1.5916021 -39.0358122
OS -1.58975298 -39.03211396
OS -1.58790386 -39.0265666
OS -1.58420562 -39.01917012
OS -1.58050738 -39.0080754
OS -1.57496002 -38.99513156
OS -1.56941266 -38.97941404
OS -1.56941266 -38.97848948
OS -1.56756354 -38.97479124
OS -1.56571442 -38.96831932
OS -1.56201618 -38.95999828
OS -1.73768258 -38.49586916
OS -1.65447218 -38.49586916
OS -1.55739338 -38.76491612
OS -1.55739338 -38.76584068
OS -1.55646882 -38.76676524
OS -1.55554426 -38.76953892
OS -1.5546197 -38.77416172
OS -1.55277058 -38.77878452
OS -1.55092146 -38.78433188
OS -1.54629866 -38.79727572
OS -1.5407513 -38.81299324
OS -1.53520394 -38.83148444
OS -1.52965658 -38.8509002
OS -1.52410922 -38.87216508
OS -1.52410922 -38.87124052
OS -1.52318466 -38.8693914
OS -1.5222601 -38.86661772
OS -1.52133554 -38.86291948
OS -1.52041098 -38.85829668
OS -1.51856186 -38.85274932
OS -1.51486362 -38.83888092
OS -1.51024082 -38.8231634
OS -1.5037689 -38.8046722
OS -1.49822154 -38.786181
OS -1.49082506 -38.76676524
OS -1.39097258 -38.49586916
OS -1.31238498 -38.49586916
OS -1.48897594 -38.96739476
OE
OB -1.17462554 -38.42745172 I
OS -1.19589042 -38.54671996
OS -1.2448921 -38.54671996
OS -1.26430786 -38.42745172
OS -1.26430786 -38.32020276
OS -1.17462554 -38.32020276
OS -1.17462554 -38.42745172
OE
OB -2.31183434 -38.95999828 I
OS -2.39042194 -38.95999828
OS -2.39042194 -38.32020276
OS -2.31183434 -38.32020276
OS -2.31183434 -38.95999828
OE
OB -1.97344538 -38.48662356 I
OS -1.95957698 -38.48754812
OS -1.94385946 -38.48939724
OS -1.92814194 -38.49217092
OS -1.91242442 -38.49586916
OS -1.89763146 -38.50049196
OS -1.89578234 -38.50141652
OS -1.89115954 -38.50326564
OS -1.88468762 -38.50603932
OS -1.87636658 -38.50973756
OS -1.86712098 -38.51528492
OS -1.85787538 -38.52083228
OS -1.84955434 -38.52822876
OS -1.84215786 -38.53562524
OS -1.8412333 -38.5365498
OS -1.83938418 -38.53932348
OS -1.8366105 -38.54394628
OS -1.83291226 -38.54949364
OS -1.82828946 -38.55781468
OS -1.82459122 -38.56613572
OS -1.82089298 -38.57630588
OS -1.8181193 -38.58832516
OS -1.8181193 -38.58924972
OS -1.81719474 -38.5920234
OS -1.81627018 -38.59757076
OS -1.81534562 -38.60496724
OS -1.81534562 -38.6151374
OS -1.81442106 -38.62715668
OS -1.8134965 -38.6428742
OS -1.8134965 -38.66044084
OS -1.8134965 -38.76584068
OS -1.8134965 -38.76676524
OS -1.8134965 -38.77046348
OS -1.8134965 -38.77601084
OS -1.8134965 -38.78340732
OS -1.8134965 -38.79172836
OS -1.8134965 -38.80189852
OS -1.81257194 -38.82408796
OS -1.81257194 -38.84720196
OS -1.81164738 -38.87031596
OS -1.81072282 -38.88048612
OS -1.81072282 -38.88973172
OS -1.80979826 -38.89805276
OS -1.8088737 -38.90452468
OS -1.8088737 -38.90544924
OS -1.80794914 -38.90914748
OS -1.80702458 -38.91469484
OS -1.8042509 -38.92209132
OS -1.80240178 -38.93041236
OS -1.79870354 -38.93965796
OS -1.79408074 -38.94982812
OS -1.78945794 -38.95999828
OS -1.87174378 -38.95999828
OS -1.87266834 -38.95907372
OS -1.8735929 -38.95537548
OS -1.87544202 -38.95075268
OS -1.8782157 -38.9433562
OS -1.88098938 -38.93503516
OS -1.8828385 -38.924865
OS -1.88468762 -38.91377028
OS -1.88653674 -38.901751
OS -1.8874613 -38.901751
OS -1.88838586 -38.90360012
OS -1.89393322 -38.90822292
OS -1.90225426 -38.91469484
OS -1.91334898 -38.92301588
OS -1.92721738 -38.93133692
OS -1.94108578 -38.94058252
OS -1.95587874 -38.94890356
OS -1.97159626 -38.95537548
OS -1.97344538 -38.95630004
OS -1.97899274 -38.9572246
OS -1.98731378 -38.95999828
OS -1.99748394 -38.96277196
OS -2.01042778 -38.96554564
OS -2.02522074 -38.96739476
OS -2.04186282 -38.96924388
OS -2.0585049 -38.97016844
OS -2.06590138 -38.97016844
OS -2.07144874 -38.96924388
OS -2.07792066 -38.96924388
OS -2.08531714 -38.96831932
OS -2.10195922 -38.96554564
OS -2.12045042 -38.96092284
OS -2.14079074 -38.95445092
OS -2.15928194 -38.94520532
OS -2.17592402 -38.93318604
OS -2.17777314 -38.93133692
OS -2.18239594 -38.92671412
OS -2.18886786 -38.91839308
OS -2.19626434 -38.90729836
OS -2.20366082 -38.89342996
OS -2.21013274 -38.87771244
OS -2.21475554 -38.85829668
OS -2.2156801 -38.84905108
OS -2.21660466 -38.83795636
OS -2.21660466 -38.83610724
OS -2.21660466 -38.832409
OS -2.2156801 -38.82593708
OS -2.21475554 -38.81761604
OS -2.21290642 -38.80744588
OS -2.21013274 -38.79727572
OS -2.2064345 -38.786181
OS -2.2018117 -38.77601084
OS -2.20088714 -38.77508628
OS -2.19903802 -38.77138804
OS -2.19533978 -38.76584068
OS -2.19071698 -38.75936876
OS -2.18516962 -38.75197228
OS -2.17777314 -38.7445758
OS -2.17037666 -38.73717932
OS -2.16113106 -38.7307074
OS -2.1602065 -38.72978284
OS -2.15650826 -38.72793372
OS -2.15188546 -38.72423548
OS -2.14448898 -38.72053724
OS -2.13616794 -38.716839
OS -2.12599778 -38.7122162
OS -2.11582762 -38.70851796
OS -2.10380834 -38.70481972
OS -2.10288378 -38.70481972
OS -2.09918554 -38.70389516
OS -2.09363818 -38.70204604
OS -2.0862417 -38.70112148
OS -2.0769961 -38.69927236
OS -2.06497682 -38.69742324
OS -2.05110842 -38.69464956
OS -2.03446634 -38.69280044
OS -2.03354178 -38.69280044
OS -2.02984354 -38.69187588
OS -2.02522074 -38.69187588
OS -2.01874882 -38.69095132
OS -2.01135234 -38.69002676
OS -2.00210674 -38.68817764
OS -1.99193658 -38.68725308
OS -1.98084186 -38.68540396
OS -1.95865242 -38.68078116
OS -1.93461386 -38.67615836
OS -1.91334898 -38.670611
OS -1.90317882 -38.66783732
OS -1.89393322 -38.66506364
OS -1.89393322 -38.66413908
OS -1.89393322 -38.66228996
OS -1.89300866 -38.6567426
OS -1.89300866 -38.65027068
OS -1.89300866 -38.64657244
OS -1.89300866 -38.64472332
OS -1.89300866 -38.64379876
OS -1.89300866 -38.6428742
OS -1.89300866 -38.63732684
OS -1.89393322 -38.62808124
OS -1.89578234 -38.61791108
OS -1.89855602 -38.60681636
OS -1.90317882 -38.59572164
OS -1.90872618 -38.58555148
OS -1.91612266 -38.57723044
OS -1.91704722 -38.57630588
OS -1.92167002 -38.57260764
OS -1.9290665 -38.5689094
OS -1.9383121 -38.56336204
OS -1.95125594 -38.55873924
OS -1.9660489 -38.55411644
OS -1.9845401 -38.55134276
OS -2.00580498 -38.5504182
OS -2.01505058 -38.5504182
OS -2.02429618 -38.55134276
OS -2.03724002 -38.55319188
OS -2.05018386 -38.555041
OS -2.06405226 -38.55873924
OS -2.0769961 -38.56336204
OS -2.08809082 -38.56983396
OS -2.08901538 -38.57075852
OS -2.09271362 -38.5735322
OS -2.09733642 -38.578155
OS -2.10288378 -38.58555148
OS -2.10843114 -38.59479708
OS -2.11490306 -38.60681636
OS -2.12045042 -38.62160932
OS -2.12599778 -38.6382514
OS -2.20273626 -38.62808124
OS -2.20273626 -38.62715668
OS -2.2018117 -38.62623212
OS -2.2018117 -38.62345844
OS -2.20088714 -38.6197602
OS -2.19811346 -38.61143916
OS -2.19441522 -38.59941988
OS -2.18979242 -38.5874006
OS -2.18424506 -38.57445676
OS -2.17684858 -38.56151292
OS -2.16852754 -38.54949364
OS -2.16760298 -38.54856908
OS -2.16390474 -38.54487084
OS -2.15835738 -38.53932348
OS -2.1509609 -38.531927
OS -2.14079074 -38.52453052
OS -2.12877146 -38.51713404
OS -2.11490306 -38.508813
OS -2.09918554 -38.50234108
OS -2.09826098 -38.50234108
OS -2.09733642 -38.50141652
OS -2.09456274 -38.50049196
OS -2.0908645 -38.4995674
OS -2.0816189 -38.49679372
OS -2.06867506 -38.49402004
OS -2.0538821 -38.49124636
OS -2.0353909 -38.48847268
OS -2.01597514 -38.48662356
OS -1.9937857 -38.485699
OS -1.98361554 -38.485699
OS -1.97344538 -38.48662356
OE
OB -5.41743138 -38.48662356 I
OS -5.40911034 -38.48754812
OS -5.39986474 -38.48939724
OS -5.38969458 -38.49124636
OS -5.3776753 -38.49309548
OS -5.35271218 -38.50141652
OS -5.33976834 -38.50603932
OS -5.3268245 -38.51251124
OS -5.31388066 -38.51898316
OS -5.30093682 -38.52822876
OS -5.28891754 -38.53747436
OS -5.27689826 -38.54856908
OS -5.2759737 -38.54949364
OS -5.27412458 -38.55134276
OS -5.2713509 -38.555041
OS -5.26765266 -38.5596638
OS -5.26302986 -38.56613572
OS -5.2574825 -38.57445676
OS -5.25193514 -38.58370236
OS -5.24638778 -38.59387252
OS -5.24084042 -38.60496724
OS -5.23529306 -38.61883564
OS -5.2297457 -38.63270404
OS -5.2251229 -38.64842156
OS -5.22142466 -38.66506364
OS -5.21865098 -38.68263028
OS -5.21680186 -38.70112148
OS -5.2158773 -38.7214618
OS -5.2158773 -38.72238636
OS -5.2158773 -38.72516004
OS -5.2158773 -38.72978284
OS -5.2158773 -38.73625476
OS -5.21680186 -38.74365124
OS -5.21772642 -38.75289684
OS -5.21772642 -38.76214244
OS -5.21957554 -38.7723126
OS -5.22234922 -38.7954266
OS -5.22789658 -38.8185406
OS -5.2343685 -38.8416546
OS -5.2436141 -38.86291948
OS -5.2436141 -38.86384404
OS -5.24453866 -38.8647686
OS -5.24638778 -38.86754228
OS -5.2482369 -38.87124052
OS -5.25470882 -38.88048612
OS -5.26302986 -38.89158084
OS -5.27412458 -38.90452468
OS -5.28799298 -38.91746852
OS -5.3037105 -38.93041236
OS -5.3222017 -38.94243164
OS -5.32312626 -38.94243164
OS -5.32405082 -38.9433562
OS -5.3268245 -38.94520532
OS -5.3314473 -38.94705444
OS -5.3360701 -38.94890356
OS -5.34161746 -38.95075268
OS -5.35548586 -38.95630004
OS -5.37120338 -38.96092284
OS -5.39061914 -38.96554564
OS -5.41095946 -38.96924388
OS -5.4331489 -38.97016844
OS -5.4423945 -38.97016844
OS -5.44979098 -38.96924388
OS -5.45811202 -38.96831932
OS -5.46735762 -38.9664702
OS -5.47845234 -38.96462108
OS -5.48954706 -38.96277196
OS -5.51451018 -38.95537548
OS -5.52837858 -38.94982812
OS -5.54132242 -38.94428076
OS -5.55426626 -38.93688428
OS -5.5672101 -38.92856324
OS -5.57922938 -38.91931764
OS -5.59124866 -38.90822292
OS -5.59217322 -38.90729836
OS -5.59402234 -38.90544924
OS -5.59679602 -38.901751
OS -5.60049426 -38.89620364
OS -5.60511706 -38.88973172
OS -5.60973986 -38.88233524
OS -5.61528722 -38.87308964
OS -5.62083458 -38.86199492
OS -5.62638194 -38.84997564
OS -5.6319293 -38.83610724
OS -5.6365521 -38.82131428
OS -5.6411749 -38.80559676
OS -5.64487314 -38.78803012
OS -5.64764682 -38.76953892
OS -5.64949594 -38.7491986
OS -5.6504205 -38.72793372
OS -5.6504205 -38.7260846
OS -5.6504205 -38.72238636
OS -5.64949594 -38.71591444
OS -5.64949594 -38.70666884
OS -5.64857138 -38.69649868
OS -5.64672226 -38.68355484
OS -5.64487314 -38.670611
OS -5.6411749 -38.65581804
OS -5.63747666 -38.64102508
OS -5.63285386 -38.62530756
OS -5.6273065 -38.60866548
OS -5.61991002 -38.59294796
OS -5.61251354 -38.578155
OS -5.60234338 -38.56336204
OS -5.59217322 -38.54949364
OS -5.57922938 -38.53747436
OS -5.57830482 -38.5365498
OS -5.5764557 -38.53562524
OS -5.57275746 -38.53285156
OS -5.56813466 -38.52915332
OS -5.5625873 -38.52545508
OS -5.55519082 -38.52083228
OS -5.54779434 -38.51620948
OS -5.53854874 -38.51158668
OS -5.52837858 -38.50696388
OS -5.51728386 -38.50234108
OS -5.49232074 -38.49402004
OS -5.46365938 -38.48754812
OS -5.44886642 -38.48662356
OS -5.4331489 -38.485699
OS -5.4239033 -38.485699
OS -5.41743138 -38.48662356
OE
OB -4.90337602 -38.48662356 I
OS -4.8969041 -38.48754812
OS -4.8830357 -38.48939724
OS -4.86639362 -38.49309548
OS -4.84882698 -38.49864284
OS -4.83126034 -38.50696388
OS -4.8136937 -38.51713404
OS -4.81276914 -38.51713404
OS -4.81184458 -38.51898316
OS -4.80629722 -38.5226814
OS -4.79797618 -38.53007788
OS -4.78780602 -38.53932348
OS -4.7767113 -38.55134276
OS -4.76561658 -38.56613572
OS -4.75452186 -38.58370236
OS -4.74527626 -38.60311812
OS -4.74527626 -38.60404268
OS -4.7443517 -38.6058918
OS -4.74342714 -38.60866548
OS -4.74157802 -38.61236372
OS -4.7397289 -38.61791108
OS -4.73787978 -38.624383
OS -4.73325698 -38.63917596
OS -4.72863418 -38.65766716
OS -4.72493594 -38.67800748
OS -4.72216226 -38.70112148
OS -4.7212377 -38.72516004
OS -4.7212377 -38.7260846
OS -4.7212377 -38.72793372
OS -4.7212377 -38.73163196
OS -4.7212377 -38.73717932
OS -4.72216226 -38.74365124
OS -4.72216226 -38.75104772
OS -4.72401138 -38.7676898
OS -4.72770962 -38.78803012
OS -4.73233242 -38.809295
OS -4.73880434 -38.83148444
OS -4.74712538 -38.85367388
OS -4.74712538 -38.85459844
OS -4.74804994 -38.85644756
OS -4.74989906 -38.85922124
OS -4.75174818 -38.86291948
OS -4.7582201 -38.87308964
OS -4.76654114 -38.88603348
OS -4.7767113 -38.89990188
OS -4.78965514 -38.91377028
OS -4.8044481 -38.92763868
OS -4.82201474 -38.94058252
OS -4.8229393 -38.94058252
OS -4.82386386 -38.94150708
OS -4.82663754 -38.9433562
OS -4.83033578 -38.94520532
OS -4.83958138 -38.94982812
OS -4.85252522 -38.95537548
OS -4.86824274 -38.96092284
OS -4.88488482 -38.96554564
OS -4.90430058 -38.96924388
OS -4.92371634 -38.97016844
OS -4.93018826 -38.97016844
OS -4.93758474 -38.96924388
OS -4.94683034 -38.96831932
OS -4.95792506 -38.9664702
OS -4.96994434 -38.96369652
OS -4.98196362 -38.95999828
OS -4.9939829 -38.95445092
OS -4.99490746 -38.95352636
OS -4.99953026 -38.95167724
OS -5.00507762 -38.947979
OS -5.0124741 -38.94243164
OS -5.01987058 -38.93688428
OS -5.02911618 -38.9294878
OS -5.03743722 -38.92116676
OS -5.0448337 -38.91192116
OS -5.0448337 -39.1375138
OS -5.1234213 -39.1375138
OS -5.1234213 -38.49586916
OS -5.05223018 -38.49586916
OS -5.05223018 -38.55689012
OS -5.05130562 -38.555041
OS -5.04760738 -38.55134276
OS -5.04298458 -38.54487084
OS -5.0355881 -38.53747436
OS -5.02726706 -38.52822876
OS -5.01802146 -38.51990772
OS -5.00692674 -38.51158668
OS -4.99583202 -38.5041902
OS -4.9939829 -38.50326564
OS -4.99028466 -38.50141652
OS -4.98288818 -38.49864284
OS -4.97364258 -38.4949446
OS -4.96254786 -38.49124636
OS -4.94960402 -38.48847268
OS -4.93481106 -38.48662356
OS -4.91816898 -38.485699
OS -4.90799882 -38.485699
OS -4.90337602 -38.48662356
OE
OB -5.77800978 -38.49586916 I
OS -5.69849762 -38.49586916
OS -5.69849762 -38.55689012
OS -5.77800978 -38.55689012
OS -5.77800978 -38.82963532
OS -5.77800978 -38.83148444
OS -5.77800978 -38.83518268
OS -5.77800978 -38.84073004
OS -5.77708522 -38.84720196
OS -5.77616066 -38.86199492
OS -5.7752361 -38.86846684
OS -5.77431154 -38.87308964
OS -5.77338698 -38.87493876
OS -5.7706133 -38.878637
OS -5.76691506 -38.8832598
OS -5.76044314 -38.8878826
OS -5.75859402 -38.88880716
OS -5.75397122 -38.89065628
OS -5.74565018 -38.8925054
OS -5.7336309 -38.89342996
OS -5.7243853 -38.89342996
OS -5.7197625 -38.8925054
OS -5.71329058 -38.8925054
OS -5.7058941 -38.89158084
OS -5.69849762 -38.89065628
OS -5.68832746 -38.95999828
OS -5.69017658 -38.95999828
OS -5.69387482 -38.96092284
OS -5.70034674 -38.9618474
OS -5.70866778 -38.96277196
OS -5.71791338 -38.96462108
OS -5.72808354 -38.96554564
OS -5.74842386 -38.9664702
OS -5.75582034 -38.9664702
OS -5.76321682 -38.96554564
OS -5.77246242 -38.96462108
OS -5.78355714 -38.96369652
OS -5.79465186 -38.96092284
OS -5.80482202 -38.95814916
OS -5.81499218 -38.95352636
OS -5.81591674 -38.9526018
OS -5.81869042 -38.95075268
OS -5.82238866 -38.947979
OS -5.82793602 -38.9433562
OS -5.83255882 -38.9387334
OS -5.83810618 -38.93226148
OS -5.84365354 -38.92578956
OS -5.84735178 -38.91746852
OS -5.84735178 -38.91654396
OS -5.8492009 -38.91284572
OS -5.85012546 -38.9063738
OS -5.85197458 -38.8971282
OS -5.8538237 -38.88510892
OS -5.85474826 -38.87771244
OS -5.85474826 -38.8693914
OS -5.85567282 -38.85922124
OS -5.85659738 -38.84905108
OS -5.85659738 -38.83795636
OS -5.85659738 -38.82501252
OS -5.85659738 -38.55689012
OS -5.91484466 -38.55689012
OS -5.91484466 -38.49586916
OS -5.85659738 -38.49586916
OS -5.85659738 -38.38122372
OS -5.77800978 -38.33407116
OS -5.77800978 -38.49586916
OE
OB -5.97031826 -38.42745172 I
OS -5.99158314 -38.54671996
OS -6.04058482 -38.54671996
OS -6.06000058 -38.42745172
OS -6.06000058 -38.32020276
OS -5.97031826 -38.32020276
OS -5.97031826 -38.42745172
OE
OB -4.17852098 -39.1375138 I
OS -4.69904826 -39.1375138
OS -4.69904826 -39.08111564
OS -4.17852098 -39.08111564
OS -4.17852098 -39.1375138
OE
OB -5.4331489 -38.5504182 H
OS -5.43869626 -38.5504182
OS -5.44331906 -38.55134276
OS -5.45348922 -38.55226732
OS -5.46735762 -38.55596556
OS -5.48307514 -38.56151292
OS -5.49971722 -38.5689094
OS -5.51543474 -38.58000412
OS -5.52375578 -38.5874006
OS -5.53115226 -38.59479708
OS -5.53115226 -38.59572164
OS -5.53300138 -38.5966462
OS -5.5348505 -38.59941988
OS -5.53762418 -38.60311812
OS -5.54039786 -38.60774092
OS -5.54317154 -38.61328828
OS -5.54686978 -38.62068476
OS -5.55056802 -38.62808124
OS -5.55426626 -38.63732684
OS -5.5579645 -38.64657244
OS -5.56073818 -38.65766716
OS -5.56351186 -38.66968644
OS -5.56628554 -38.68263028
OS -5.56813466 -38.69649868
OS -5.56905922 -38.7122162
OS -5.56998378 -38.72793372
OS -5.56998378 -38.72885828
OS -5.56998378 -38.73163196
OS -5.56998378 -38.73625476
OS -5.56905922 -38.74272668
OS -5.56905922 -38.75012316
OS -5.56813466 -38.7584442
OS -5.56536098 -38.77785996
OS -5.56073818 -38.8000494
OS -5.5533417 -38.82223884
OS -5.5440961 -38.84350372
OS -5.53762418 -38.85274932
OS -5.53115226 -38.86199492
OS -5.5302277 -38.86199492
OS -5.52930314 -38.86384404
OS -5.52375578 -38.86846684
OS -5.51543474 -38.87586332
OS -5.50434002 -38.8832598
OS -5.49047162 -38.89158084
OS -5.47382954 -38.89897732
OS -5.45441378 -38.90360012
OS -5.44424362 -38.90452468
OS -5.4331489 -38.90544924
OS -5.42760154 -38.90544924
OS -5.42297874 -38.90452468
OS -5.41280858 -38.90267556
OS -5.39894018 -38.89990188
OS -5.38414722 -38.89435452
OS -5.36750514 -38.88695804
OS -5.35178762 -38.87586332
OS -5.34346658 -38.86846684
OS -5.3360701 -38.86107036
OS -5.33514554 -38.8601458
OS -5.33422098 -38.85922124
OS -5.33237186 -38.85644756
OS -5.32959818 -38.85274932
OS -5.3268245 -38.84812652
OS -5.32312626 -38.84257916
OS -5.31942802 -38.83518268
OS -5.31572978 -38.8277862
OS -5.31203154 -38.8185406
OS -5.30925786 -38.80837044
OS -5.30555962 -38.79727572
OS -5.30278594 -38.78525644
OS -5.30001226 -38.77138804
OS -5.29816314 -38.75751964
OS -5.29631402 -38.74180212
OS -5.29631402 -38.72516004
OS -5.29631402 -38.72423548
OS -5.29631402 -38.7214618
OS -5.29631402 -38.716839
OS -5.29723858 -38.71129164
OS -5.29723858 -38.70389516
OS -5.29816314 -38.69557412
OS -5.30093682 -38.67615836
OS -5.30555962 -38.65581804
OS -5.3129561 -38.6336286
OS -5.32312626 -38.61328828
OS -5.32867362 -38.60311812
OS -5.3360701 -38.59479708
OS -5.3360701 -38.59387252
OS -5.33791922 -38.59294796
OS -5.34346658 -38.5874006
OS -5.35178762 -38.58092868
OS -5.36288234 -38.57260764
OS -5.37675074 -38.5642866
OS -5.39339282 -38.55689012
OS -5.41188402 -38.55226732
OS -5.42205418 -38.55134276
OS -5.4331489 -38.5504182
OE
OB -3.94090906 -38.5504182 H
OS -3.94645642 -38.5504182
OS -3.95107922 -38.55134276
OS -3.96124938 -38.55226732
OS -3.97511778 -38.55596556
OS -3.9908353 -38.56151292
OS -4.00747738 -38.5689094
OS -4.0231949 -38.58000412
OS -4.03151594 -38.5874006
OS -4.03891242 -38.59479708
OS -4.03891242 -38.59572164
OS -4.04076154 -38.5966462
OS -4.04261066 -38.59941988
OS -4.04538434 -38.60311812
OS -4.04815802 -38.60774092
OS -4.0509317 -38.61328828
OS -4.05462994 -38.62068476
OS -4.05832818 -38.62808124
OS -4.06202642 -38.63732684
OS -4.06572466 -38.64657244
OS -4.06849834 -38.65766716
OS -4.07127202 -38.66968644
OS -4.0740457 -38.68263028
OS -4.07589482 -38.69649868
OS -4.07681938 -38.7122162
OS -4.07774394 -38.72793372
OS -4.07774394 -38.72885828
OS -4.07774394 -38.73163196
OS -4.07774394 -38.73625476
OS -4.07681938 -38.74272668
OS -4.07681938 -38.75012316
OS -4.07589482 -38.7584442
OS -4.07312114 -38.77785996
OS -4.06849834 -38.8000494
OS -4.06110186 -38.82223884
OS -4.05185626 -38.84350372
OS -4.04538434 -38.85274932
OS -4.03891242 -38.86199492
OS -4.03798786 -38.86199492
OS -4.0370633 -38.86384404
OS -4.03151594 -38.86846684
OS -4.0231949 -38.87586332
OS -4.01210018 -38.8832598
OS -3.99823178 -38.89158084
OS -3.9815897 -38.89897732
OS -3.96217394 -38.90360012
OS -3.95200378 -38.90452468
OS -3.94090906 -38.90544924
OS -3.9353617 -38.90544924
OS -3.9307389 -38.90452468
OS -3.92056874 -38.90267556
OS -3.90670034 -38.89990188
OS -3.89190738 -38.89435452
OS -3.8752653 -38.88695804
OS -3.85954778 -38.87586332
OS -3.85122674 -38.86846684
OS -3.84383026 -38.86107036
OS -3.8429057 -38.8601458
OS -3.84198114 -38.85922124
OS -3.84013202 -38.85644756
OS -3.83735834 -38.85274932
OS -3.83458466 -38.84812652
OS -3.83088642 -38.84257916
OS -3.82718818 -38.83518268
OS -3.82348994 -38.8277862
OS -3.8197917 -38.8185406
OS -3.81701802 -38.80837044
OS -3.81331978 -38.79727572
OS -3.8105461 -38.78525644
OS -3.80777242 -38.77138804
OS -3.8059233 -38.75751964
OS -3.80407418 -38.74180212
OS -3.80407418 -38.72516004
OS -3.80407418 -38.72423548
OS -3.80407418 -38.7214618
OS -3.80407418 -38.716839
OS -3.80499874 -38.71129164
OS -3.80499874 -38.70389516
OS -3.8059233 -38.69557412
OS -3.80869698 -38.67615836
OS -3.81331978 -38.65581804
OS -3.82071626 -38.6336286
OS -3.83088642 -38.61328828
OS -3.83643378 -38.60311812
OS -3.84383026 -38.59479708
OS -3.84383026 -38.59387252
OS -3.84567938 -38.59294796
OS -3.85122674 -38.5874006
OS -3.85954778 -38.58092868
OS -3.8706425 -38.57260764
OS -3.8845109 -38.5642866
OS -3.90115298 -38.55689012
OS -3.91964418 -38.55226732
OS -3.92981434 -38.55134276
OS -3.94090906 -38.5504182
OE
OB -4.92556546 -38.54764452 H
OS -4.93018826 -38.54764452
OS -4.9338865 -38.54856908
OS -4.9431321 -38.5504182
OS -4.95515138 -38.55319188
OS -4.96901978 -38.55873924
OS -4.98381274 -38.56706028
OS -4.99213378 -38.57260764
OS -4.99953026 -38.57907956
OS -5.00692674 -38.58647604
OS -5.01432322 -38.59479708
OS -5.01432322 -38.59572164
OS -5.01617234 -38.5966462
OS -5.01802146 -38.59941988
OS -5.01987058 -38.60311812
OS -5.02264426 -38.60866548
OS -5.0263425 -38.61421284
OS -5.03004074 -38.62160932
OS -5.03281442 -38.6290058
OS -5.03651266 -38.6382514
OS -5.0402109 -38.64842156
OS -5.04298458 -38.65951628
OS -5.04668282 -38.67153556
OS -5.04853194 -38.68540396
OS -5.05038106 -38.69927236
OS -5.05223018 -38.71406532
OS -5.05223018 -38.7307074
OS -5.05223018 -38.73163196
OS -5.05223018 -38.73440564
OS -5.05223018 -38.73902844
OS -5.05130562 -38.74550036
OS -5.05130562 -38.75289684
OS -5.05038106 -38.76121788
OS -5.04760738 -38.78063364
OS -5.04298458 -38.80282308
OS -5.03743722 -38.82408796
OS -5.02819162 -38.84535284
OS -5.02264426 -38.85459844
OS -5.01617234 -38.86291948
OS -5.01432322 -38.8647686
OS -5.00970042 -38.8693914
OS -5.00230394 -38.87678788
OS -4.99213378 -38.88418436
OS -4.97918994 -38.89158084
OS -4.96439698 -38.89897732
OS -4.9477549 -38.90360012
OS -4.9385093 -38.90452468
OS -4.9292637 -38.90544924
OS -4.92371634 -38.90544924
OS -4.9200181 -38.90452468
OS -4.9107725 -38.90267556
OS -4.89782866 -38.89990188
OS -4.88396026 -38.89435452
OS -4.8691673 -38.88695804
OS -4.85437434 -38.87586332
OS -4.84697786 -38.8693914
OS -4.83958138 -38.86199492
OS -4.83958138 -38.86107036
OS -4.83773226 -38.8601458
OS -4.83588314 -38.85737212
OS -4.83403402 -38.85367388
OS -4.83033578 -38.84905108
OS -4.8275621 -38.84257916
OS -4.82386386 -38.83610724
OS -4.82016562 -38.8277862
OS -4.81739194 -38.81946516
OS -4.8136937 -38.80837044
OS -4.80999546 -38.79727572
OS -4.80722178 -38.78525644
OS -4.80537266 -38.77138804
OS -4.80352354 -38.75659508
OS -4.80167442 -38.74087756
OS -4.80167442 -38.72423548
OS -4.80167442 -38.72331092
OS -4.80167442 -38.72053724
OS -4.80167442 -38.71591444
OS -4.80259898 -38.70944252
OS -4.80259898 -38.70204604
OS -4.80352354 -38.693725
OS -4.80629722 -38.67430924
OS -4.81092002 -38.65304436
OS -4.81739194 -38.63177948
OS -4.82663754 -38.6105146
OS -4.8321849 -38.60034444
OS -4.83865682 -38.5920234
OS -4.83865682 -38.59109884
OS -4.84050594 -38.59017428
OS -4.84512874 -38.58462692
OS -4.85252522 -38.578155
OS -4.86269538 -38.56983396
OS -4.87563922 -38.56151292
OS -4.89043218 -38.55411644
OS -4.90707426 -38.54949364
OS -4.91631986 -38.54856908
OS -4.92556546 -38.54764452
OE
OB -2.99323506 -38.5504182 H
OS -2.99878242 -38.5504182
OS -3.00248066 -38.55134276
OS -3.01265082 -38.55226732
OS -3.0246701 -38.555041
OS -3.03946306 -38.5596638
OS -3.05518058 -38.56613572
OS -3.06997354 -38.57538132
OS -3.0847665 -38.5874006
OS -3.08661562 -38.58924972
OS -3.09031386 -38.59387252
OS -3.09678578 -38.60219356
OS -3.1032577 -38.61328828
OS -3.11065418 -38.62623212
OS -3.1171261 -38.6428742
OS -3.12267346 -38.66228996
OS -3.12544714 -38.68355484
OS -2.86564578 -38.68355484
OS -2.86564578 -38.68263028
OS -2.86564578 -38.68078116
OS -2.86657034 -38.67800748
OS -2.86657034 -38.67430924
OS -2.86841946 -38.66321452
OS -2.87119314 -38.65119524
OS -2.87581594 -38.63640228
OS -2.88043874 -38.62253388
OS -2.88783522 -38.60866548
OS -2.89615626 -38.5966462
OS -2.89615626 -38.59572164
OS -2.89800538 -38.59479708
OS -2.90262818 -38.58924972
OS -2.91094922 -38.58185324
OS -2.92204394 -38.5735322
OS -2.93591234 -38.56521116
OS -2.95255442 -38.55781468
OS -2.97197018 -38.55226732
OS -2.98214034 -38.55134276
OS -2.99323506 -38.5504182
OE
OB -1.89300866 -38.72700916 H
OS -1.89393322 -38.72700916
OS -1.89485778 -38.72793372
OS -1.89763146 -38.72885828
OS -1.9013297 -38.72978284
OS -1.9059525 -38.73163196
OS -1.91149986 -38.73348108
OS -1.91797178 -38.7353302
OS -1.92536826 -38.73717932
OS -1.9336893 -38.739953
OS -1.94385946 -38.74180212
OS -1.95402962 -38.7445758
OS -1.9660489 -38.74734948
OS -1.97899274 -38.75012316
OS -1.99193658 -38.75289684
OS -2.00672954 -38.75474596
OS -2.02244706 -38.75751964
OS -2.02429618 -38.75751964
OS -2.02984354 -38.7584442
OS -2.03908914 -38.76029332
OS -2.0492593 -38.76214244
OS -2.06035402 -38.76399156
OS -2.07144874 -38.76676524
OS -2.0816189 -38.76953892
OS -2.0908645 -38.77323716
OS -2.09178906 -38.77323716
OS -2.09456274 -38.77508628
OS -2.09826098 -38.7769354
OS -2.10195922 -38.77970908
OS -2.11305394 -38.78710556
OS -2.12229954 -38.79820028
OS -2.12229954 -38.79912484
OS -2.12414866 -38.80097396
OS -2.12507322 -38.8046722
OS -2.12692234 -38.809295
OS -2.12877146 -38.81484236
OS -2.13062058 -38.82038972
OS -2.13154514 -38.8277862
OS -2.1324697 -38.83518268
OS -2.1324697 -38.83610724
OS -2.1324697 -38.84073004
OS -2.13154514 -38.8462774
OS -2.12969602 -38.85367388
OS -2.12692234 -38.86199492
OS -2.12229954 -38.87031596
OS -2.11675218 -38.87956156
OS -2.1093557 -38.8878826
OS -2.10843114 -38.88880716
OS -2.1047329 -38.89065628
OS -2.09918554 -38.89435452
OS -2.09178906 -38.89805276
OS -2.0816189 -38.901751
OS -2.06959962 -38.90544924
OS -2.05573122 -38.90729836
OS -2.03908914 -38.90822292
OS -2.03169266 -38.90822292
OS -2.02244706 -38.90729836
OS -2.0122769 -38.90544924
OS -1.99933306 -38.90360012
OS -1.98638922 -38.89990188
OS -1.97252082 -38.89527908
OS -1.95865242 -38.88880716
OS -1.9568033 -38.8878826
OS -1.95310506 -38.88510892
OS -1.94663314 -38.88048612
OS -1.93923666 -38.8740142
OS -1.93091562 -38.86661772
OS -1.92167002 -38.85737212
OS -1.91427354 -38.8462774
OS -1.90687706 -38.83425812
OS -1.9059525 -38.83333356
OS -1.90502794 -38.82963532
OS -1.90317882 -38.8231634
OS -1.90040514 -38.81484236
OS -1.89763146 -38.80374764
OS -1.89578234 -38.7908038
OS -1.89485778 -38.77508628
OS -1.89393322 -38.75659508
OS -1.89300866 -38.72700916
OE
SE
S P 0
OB -4.66714078 -36.5016923 I
OS -4.65465922 -36.5016923
OS -4.62553558 -36.50307914
OS -4.5950251 -36.50723966
OS -4.56174094 -36.51140018
OS -4.53123046 -36.51833438
OS -4.51597522 -36.5224949
OS -4.50349366 -36.52665542
OS -4.50210682 -36.52665542
OS -4.50071998 -36.52804226
OS -4.49239894 -36.53220278
OS -4.47991738 -36.53775014
OS -4.46466214 -36.54745802
OS -4.44802006 -36.55993958
OS -4.42999114 -36.57658166
OS -4.41334906 -36.59599742
OS -4.39670698 -36.61818686
OS -4.39670698 -36.6195737
OS -4.39532014 -36.62096054
OS -4.38977278 -36.62928158
OS -4.38422542 -36.64314998
OS -4.37590438 -36.6611789
OS -4.36897018 -36.6819815
OS -4.36203598 -36.70694462
OS -4.35787546 -36.73329458
OS -4.35648862 -36.76241822
OS -4.35648862 -36.76380506
OS -4.35648862 -36.76657874
OS -4.35648862 -36.7721261
OS -4.35787546 -36.7790603
OS -4.35787546 -36.78876818
OS -4.3592623 -36.79847606
OS -4.36480966 -36.82205234
OS -4.3731307 -36.84978914
OS -4.38422542 -36.87891278
OS -4.4008675 -36.90803642
OS -4.41196222 -36.92190482
OS -4.42305694 -36.93577322
OS -4.42444378 -36.93716006
OS -4.42583062 -36.9385469
OS -4.42999114 -36.94270742
OS -4.4355385 -36.94686794
OS -4.4424727 -36.9524153
OS -4.45079374 -36.95796266
OS -4.46188846 -36.96489686
OS -4.47298318 -36.9732179
OS -4.48685158 -36.9801521
OS -4.50210682 -36.9870863
OS -4.5187489 -36.99540734
OS -4.53677782 -37.00234154
OS -4.55758042 -37.0078889
OS -4.57838302 -37.0148231
OS -4.6019593 -37.01898362
OS -4.62692242 -37.02314414
OS -4.62414874 -37.02453098
OS -4.61860138 -37.02730466
OS -4.61028034 -37.03285202
OS -4.59918562 -37.03839938
OS -4.5742225 -37.05365462
OS -4.56174094 -37.0633625
OS -4.55064622 -37.07168354
OS -4.54787254 -37.07445722
OS -4.54093834 -37.08139142
OS -4.52984362 -37.09248614
OS -4.51597522 -37.10635454
OS -4.50071998 -37.1257703
OS -4.48269106 -37.1465729
OS -4.46466214 -37.17153602
OS -4.44524638 -37.19927282
OS -4.28021242 -37.45999874
OS -4.43831218 -37.45999874
OS -4.56451462 -37.26029378
OS -4.56451462 -37.25890694
OS -4.5672883 -37.25613326
OS -4.57006198 -37.25197274
OS -4.5742225 -37.24642538
OS -4.58393038 -37.23117014
OS -4.59641194 -37.21175438
OS -4.61166718 -37.19095178
OS -4.62692242 -37.16876234
OS -4.64217766 -37.14795974
OS -4.65604606 -37.12854398
OS -4.6574329 -37.12715714
OS -4.66159342 -37.12160978
OS -4.66852762 -37.11328874
OS -4.6782355 -37.10358086
OS -4.6990381 -37.08277826
OS -4.71013282 -37.07307038
OS -4.72122754 -37.06474934
OS -4.72261438 -37.0633625
OS -4.72538806 -37.06197566
OS -4.73093542 -37.05920198
OS -4.73925646 -37.05504146
OS -4.7475775 -37.05088094
OS -4.75728538 -37.04672042
OS -4.77947482 -37.03978622
OS -4.78086166 -37.03978622
OS -4.78363534 -37.03839938
OS -4.7891827 -37.03839938
OS -4.7961169 -37.03701254
OS -4.80582478 -37.0356257
OS -4.8169195 -37.0356257
OS -4.83217474 -37.03423886
OS -4.99582186 -37.03423886
OS -4.99582186 -37.45999874
OS -5.12341114 -37.45999874
OS -5.12341114 -36.50030546
OS -4.6782355 -36.50030546
OS -4.66714078 -36.5016923
OE
OB -1.0100437 -37.45999874 I
OS -1.13208562 -37.45999874
OS -1.13208562 -36.65701838
OS -1.4122273 -37.45999874
OS -1.52594818 -37.45999874
OS -1.80331618 -36.64314998
OS -1.80331618 -37.45999874
OS -1.9253581 -37.45999874
OS -1.9253581 -36.50030546
OS -1.73536102 -36.50030546
OS -1.50791926 -37.1812439
OS -1.50791926 -37.18263074
OS -1.50653242 -37.18540442
OS -1.50514558 -37.18956494
OS -1.5023719 -37.19649914
OS -1.49682454 -37.21314122
OS -1.48989034 -37.23394382
OS -1.48295614 -37.2575201
OS -1.4746351 -37.28109638
OS -1.4677009 -37.30328582
OS -1.46215354 -37.32270158
OS -1.4607667 -37.3199279
OS -1.45937986 -37.3129937
OS -1.45521934 -37.30051214
OS -1.44967198 -37.28387006
OS -1.44273778 -37.26168062
OS -1.4330299 -37.23533066
OS -1.42332202 -37.20482018
OS -1.41084046 -37.16876234
OS -1.18062502 -36.50030546
OS -1.0100437 -36.50030546
OS -1.0100437 -37.45999874
OE
OB -2.02382374 -37.45999874 I
OS -2.1680551 -37.45999874
OS -2.28038914 -37.16876234
OS -2.68257274 -37.16876234
OS -2.78658574 -37.45999874
OS -2.92110922 -37.45999874
OS -2.55498346 -36.50030546
OS -2.41629946 -36.50030546
OS -2.02382374 -37.45999874
OE
OB -3.02928274 -37.45999874 I
OS -3.16103254 -37.45999874
OS -3.66306862 -36.70694462
OS -3.66306862 -37.45999874
OS -3.78511054 -37.45999874
OS -3.78511054 -36.50030546
OS -3.65474758 -36.50030546
OS -3.15132466 -37.25474642
OS -3.15132466 -36.50030546
OS -3.02928274 -36.50030546
OS -3.02928274 -37.45999874
OE
OB -5.3231161 -36.61402634 I
OS -5.89033366 -36.61402634
OS -5.89033366 -36.90664958
OS -5.35917394 -36.90664958
OS -5.35917394 -37.02037046
OS -5.89033366 -37.02037046
OS -5.89033366 -37.34627786
OS -5.30092666 -37.34627786
OS -5.30092666 -37.45999874
OS -6.01792294 -37.45999874
OS -6.01792294 -36.50030546
OS -5.3231161 -36.50030546
OS -5.3231161 -36.61402634
OE
OB -0.10721086 -36.61402634 I
OS -0.67442842 -36.61402634
OS -0.67442842 -36.90664958
OS -0.1432687 -36.90664958
OS -0.1432687 -37.02037046
OS -0.67442842 -37.02037046
OS -0.67442842 -37.34627786
OS -0.08502142 -37.34627786
OS -0.08502142 -37.45999874
OS -0.8020177 -37.45999874
OS -0.8020177 -36.50030546
OS -0.10721086 -36.50030546
OS -0.10721086 -36.61402634
OE
OB -8.43241138 -37.34627786 I
OS -7.95949894 -37.34627786
OS -7.95949894 -37.45999874
OS -8.56000066 -37.45999874
OS -8.56000066 -36.50030546
OS -8.43241138 -36.50030546
OS -8.43241138 -37.34627786
OE
OB -6.51718534 -37.05365462 I
OS -6.51718534 -37.45999874
OS -6.64477462 -37.45999874
OS -6.64477462 -37.05365462
OS -7.0150609 -36.50030546
OS -6.86112166 -36.50030546
OS -6.67251142 -36.79154186
OS -6.67251142 -36.7929287
OS -6.66973774 -36.79570238
OS -6.66696406 -36.7998629
OS -6.66419038 -36.80541026
OS -6.65864302 -36.81234446
OS -6.65309566 -36.8206655
OS -6.6406141 -36.8414681
OS -6.62535886 -36.86643122
OS -6.60871678 -36.89416802
OS -6.59068786 -36.92329166
OS -6.57404578 -36.95380214
OS -6.57404578 -36.9524153
OS -6.57265894 -36.94964162
OS -6.56988526 -36.9454811
OS -6.56572474 -36.93993374
OS -6.56156422 -36.93299954
OS -6.55601686 -36.9246785
OS -6.5435353 -36.9038759
OS -6.52828006 -36.87891278
OS -6.51025114 -36.84978914
OS -6.48944854 -36.81789182
OS -6.4672591 -36.78322082
OS -6.28280938 -36.50030546
OS -6.1344175 -36.50030546
OS -6.51718534 -37.05365462
OE
OB -7.01644774 -37.45999874 I
OS -7.1606791 -37.45999874
OS -7.27301314 -37.16876234
OS -7.67519674 -37.16876234
OS -7.77920974 -37.45999874
OS -7.91373322 -37.45999874
OS -7.54760746 -36.50030546
OS -7.40892346 -36.50030546
OS -7.01644774 -37.45999874
OE
OB -7.48103914 -36.60015794 H
OS -7.48103914 -36.60154478
OS -7.48242598 -36.60431846
OS -7.48242598 -36.60986582
OS -7.48519966 -36.61541318
OS -7.4865865 -36.62512106
OS -7.48936018 -36.63482894
OS -7.49490754 -36.65840522
OS -7.50184174 -36.68614202
OS -7.51154962 -36.7166525
OS -7.5212575 -36.74993666
OS -7.53373906 -36.78460766
OS -7.63775206 -37.06474934
OS -7.3132315 -37.06474934
OS -7.41308398 -36.80124974
OS -7.41308398 -36.7998629
OS -7.41447082 -36.79570238
OS -7.4172445 -36.78876818
OS -7.42001818 -36.78044714
OS -7.4241787 -36.77073926
OS -7.42833922 -36.7582577
OS -7.43249974 -36.7443893
OS -7.4380471 -36.7305209
OS -7.44914182 -36.69862358
OS -7.46023654 -36.66533942
OS -7.47133126 -36.63205526
OS -7.48103914 -36.60015794
OE
OB -4.69349074 -36.60709214 H
OS -4.99582186 -36.60709214
OS -4.99582186 -36.9246785
OS -4.71013282 -36.9246785
OS -4.69349074 -36.92329166
OS -4.67407498 -36.92190482
OS -4.65188554 -36.92051798
OS -4.6296961 -36.9177443
OS -4.60750666 -36.91358378
OS -4.5880909 -36.90803642
OS -4.58531722 -36.90664958
OS -4.57976986 -36.9038759
OS -4.57144882 -36.89971538
OS -4.5603541 -36.89416802
OS -4.54787254 -36.88584698
OS -4.53539098 -36.8761391
OS -4.52290942 -36.86365754
OS -4.51320154 -36.84978914
OS -4.5118147 -36.8484023
OS -4.50904102 -36.84285494
OS -4.5048805 -36.8345339
OS -4.49933314 -36.82343918
OS -4.49517262 -36.81095762
OS -4.4910121 -36.79708922
OS -4.48823842 -36.78044714
OS -4.48685158 -36.76380506
OS -4.48685158 -36.76241822
OS -4.48685158 -36.76103138
OS -4.48823842 -36.75271034
OS -4.48962526 -36.74022878
OS -4.49239894 -36.7235867
OS -4.49933314 -36.70694462
OS -4.50765418 -36.68752886
OS -4.52013574 -36.66949994
OS -4.53677782 -36.65147102
OS -4.5395515 -36.65008418
OS -4.5464857 -36.64453682
OS -4.55758042 -36.63760262
OS -4.57560934 -36.62928158
OS -4.59641194 -36.62096054
OS -4.62414874 -36.61402634
OS -4.65604606 -36.60847898
OS -4.69349074 -36.60709214
OE
OB -2.48841514 -36.60015794 H
OS -2.48841514 -36.60154478
OS -2.48980198 -36.60431846
OS -2.48980198 -36.60986582
OS -2.49257566 -36.61541318
OS -2.4939625 -36.62512106
OS -2.49673618 -36.63482894
OS -2.50228354 -36.65840522
OS -2.50921774 -36.68614202
OS -2.51892562 -36.7166525
OS -2.5286335 -36.74993666
OS -2.54111506 -36.78460766
OS -2.64512806 -37.06474934
OS -2.3206075 -37.06474934
OS -2.42045998 -36.80124974
OS -2.42045998 -36.7998629
OS -2.42184682 -36.79570238
OS -2.4246205 -36.78876818
OS -2.42739418 -36.78044714
OS -2.4315547 -36.77073926
OS -2.43571522 -36.7582577
OS -2.43987574 -36.7443893
OS -2.4454231 -36.7305209
OS -2.45651782 -36.69862358
OS -2.46761254 -36.66533942
OS -2.47870726 -36.63205526
OS -2.48841514 -36.60015794
OE
SE
S P 0
OB 10.53049202 -3.1249366 I
OS 10.54158674 -3.12632344
OS 10.55545514 -3.12909712
OS 10.57071038 -3.1318708
OS 10.5887393 -3.13603132
OS 10.60538138 -3.14019184
OS 10.62479714 -3.14712604
OS 10.64282606 -3.15406024
OS 10.66224182 -3.16376812
OS 10.68165758 -3.17486284
OS 10.70107334 -3.1873444
OS 10.71910226 -3.20259964
OS 10.73574434 -3.21924172
OS 10.73713118 -3.22062856
OS 10.73990486 -3.22340224
OS 10.74406538 -3.2289496
OS 10.74961274 -3.23727064
OS 10.75654694 -3.24697852
OS 10.76348114 -3.25807324
OS 10.77180218 -3.27194164
OS 10.78012322 -3.28858372
OS 10.78844426 -3.30661264
OS 10.7967653 -3.3260284
OS 10.8036995 -3.34821784
OS 10.8106337 -3.37179412
OS 10.81618106 -3.39814408
OS 10.82034158 -3.42588088
OS 10.82311526 -3.45500452
OS 10.8245021 -3.48690184
OS 10.8245021 -3.48828868
OS 10.8245021 -3.49383604
OS 10.8245021 -3.50354392
OS 10.82311526 -3.51741232
OS 10.30305026 -3.51741232
OS 10.30305026 -3.51879916
OS 10.30305026 -3.52295968
OS 10.3044371 -3.52850704
OS 10.3044371 -3.53682808
OS 10.30582394 -3.54653596
OS 10.30859762 -3.55763068
OS 10.31275814 -3.5825938
OS 10.32107918 -3.6103306
OS 10.3321739 -3.64084108
OS 10.34742914 -3.66857788
OS 10.3668449 -3.693541
OS 10.36823174 -3.693541
OS 10.36961858 -3.69631468
OS 10.37793962 -3.70324888
OS 10.39042118 -3.71295676
OS 10.40706326 -3.72266464
OS 10.4292527 -3.73375936
OS 10.45421582 -3.74346724
OS 10.48195262 -3.75040144
OS 10.49720786 -3.75178828
OS 10.51384994 -3.75317512
OS 10.52494466 -3.75317512
OS 10.53742622 -3.75178828
OS 10.55268146 -3.7490146
OS 10.56932354 -3.74485408
OS 10.5887393 -3.73930672
OS 10.60676822 -3.73098568
OS 10.62479714 -3.71989096
OS 10.62618398 -3.71850412
OS 10.63311818 -3.71295676
OS 10.64143922 -3.70463572
OS 10.6511471 -3.693541
OS 10.66224182 -3.67828576
OS 10.67472338 -3.65887
OS 10.68720494 -3.63668056
OS 10.69829966 -3.6103306
OS 10.82034158 -3.62558584
OS 10.82034158 -3.62697268
OS 10.81895474 -3.62974636
OS 10.8175679 -3.63529372
OS 10.81479422 -3.64361476
OS 10.8106337 -3.6519358
OS 10.80647318 -3.66303052
OS 10.79537846 -3.6866068
OS 10.78151006 -3.71295676
OS 10.7620943 -3.74069356
OS 10.73990486 -3.76704352
OS 10.71216806 -3.79200664
OS 10.71078122 -3.79200664
OS 10.70800754 -3.79478032
OS 10.70384702 -3.797554
OS 10.69829966 -3.80171452
OS 10.68997862 -3.80587504
OS 10.68165758 -3.81003556
OS 10.67056286 -3.81558292
OS 10.6580813 -3.82113028
OS 10.6442129 -3.82667764
OS 10.6303445 -3.832225
OS 10.5956735 -3.84054604
OS 10.55684198 -3.84748024
OS 10.51384994 -3.85025392
OS 10.4985947 -3.85025392
OS 10.48888682 -3.84886708
OS 10.47640526 -3.84748024
OS 10.46115002 -3.84470656
OS 10.44450794 -3.84193288
OS 10.42647902 -3.8391592
OS 10.3876475 -3.82806448
OS 10.3668449 -3.81974344
OS 10.34742914 -3.8114224
OS 10.32662654 -3.80032768
OS 10.30721078 -3.78784612
OS 10.28918186 -3.77397772
OS 10.27115294 -3.75733564
OS 10.2697661 -3.7559488
OS 10.26699242 -3.75317512
OS 10.2628319 -3.74762776
OS 10.25728454 -3.73930672
OS 10.25035034 -3.72959884
OS 10.24341614 -3.71850412
OS 10.2350951 -3.70463572
OS 10.22677406 -3.68938048
OS 10.21845302 -3.67135156
OS 10.21013198 -3.6519358
OS 10.20319778 -3.62974636
OS 10.19626358 -3.60617008
OS 10.19071622 -3.58120696
OS 10.1865557 -3.55347016
OS 10.18378202 -3.52434652
OS 10.18239518 -3.49383604
OS 10.18239518 -3.4924492
OS 10.18239518 -3.485515
OS 10.18239518 -3.47719396
OS 10.18378202 -3.4647124
OS 10.18516886 -3.44945716
OS 10.1865557 -3.43281508
OS 10.18932938 -3.41339932
OS 10.1934899 -3.39398356
OS 10.20458462 -3.34960468
OS 10.21151882 -3.32741524
OS 10.21983986 -3.30383896
OS 10.23093458 -3.28164952
OS 10.24341614 -3.26084692
OS 10.25728454 -3.24004432
OS 10.27253978 -3.22062856
OS 10.27392662 -3.21924172
OS 10.2767003 -3.21646804
OS 10.28224766 -3.21230752
OS 10.28918186 -3.20537332
OS 10.2975029 -3.19843912
OS 10.30859762 -3.19011808
OS 10.32107918 -3.1804102
OS 10.33633442 -3.17208916
OS 10.35158966 -3.16238128
OS 10.36961858 -3.15406024
OS 10.38903434 -3.1457392
OS 10.40983694 -3.138805
OS 10.43202638 -3.1318708
OS 10.45560266 -3.12771028
OS 10.48056578 -3.1249366
OS 10.50691574 -3.12354976
OS 10.52078414 -3.12354976
OS 10.53049202 -3.1249366
OE
OB 11.24610146 -3.1249366 I
OS 11.2613567 -3.12771028
OS 11.27938562 -3.13325764
OS 11.29880138 -3.14019184
OS 11.32099082 -3.14989972
OS 11.3445671 -3.16238128
OS 11.30157506 -3.2705548
OS 11.30018822 -3.26916796
OS 11.29464086 -3.26639428
OS 11.28631982 -3.26223376
OS 11.2752251 -3.25807324
OS 11.26274354 -3.25391272
OS 11.2474883 -3.2497522
OS 11.23223306 -3.24697852
OS 11.21697782 -3.24559168
OS 11.21004362 -3.24559168
OS 11.20310942 -3.24697852
OS 11.19340154 -3.24836536
OS 11.18369366 -3.25113904
OS 11.1712121 -3.25529956
OS 11.15873054 -3.26084692
OS 11.14763582 -3.26916796
OS 11.14624898 -3.2705548
OS 11.14208846 -3.27332848
OS 11.13792794 -3.27887584
OS 11.13099374 -3.28581004
OS 11.12405954 -3.29551792
OS 11.11712534 -3.30661264
OS 11.11019114 -3.3190942
OS 11.10464378 -3.33434944
OS 11.10325694 -3.33712312
OS 11.1018701 -3.34544416
OS 11.09909642 -3.35792572
OS 11.0949359 -3.3745678
OS 11.09077538 -3.3953704
OS 11.0880017 -3.41894668
OS 11.08661486 -3.4439098
OS 11.08522802 -3.4716466
OS 11.08522802 -3.83499868
OS 10.96734662 -3.83499868
OS 10.96734662 -3.138805
OS 11.0741333 -3.138805
OS 11.0741333 -3.24420484
OS 11.07552014 -3.242818
OS 11.0810675 -3.23311012
OS 11.0880017 -3.22062856
OS 11.09909642 -3.20537332
OS 11.11019114 -3.19011808
OS 11.1226727 -3.173476
OS 11.13515426 -3.1596076
OS 11.14763582 -3.14851288
OS 11.14902266 -3.14712604
OS 11.15318318 -3.14435236
OS 11.16150422 -3.14019184
OS 11.16982526 -3.13603132
OS 11.18091998 -3.1318708
OS 11.19478838 -3.12771028
OS 11.20865678 -3.1249366
OS 11.22391202 -3.12354976
OS 11.2336199 -3.12354976
OS 11.24610146 -3.1249366
OE
OB 9.98685074 -3.138805 I
OS 10.10611898 -3.138805
OS 10.10611898 -3.23033644
OS 9.98685074 -3.23033644
OS 9.98685074 -3.63945424
OS 9.98685074 -3.64222792
OS 9.98685074 -3.64777528
OS 9.98685074 -3.65609632
OS 9.98823758 -3.6658042
OS 9.98962442 -3.68799364
OS 9.99101126 -3.69770152
OS 9.9923981 -3.70463572
OS 9.99378494 -3.7074094
OS 9.99794546 -3.71295676
OS 10.00349282 -3.71989096
OS 10.0132007 -3.72682516
OS 10.01597438 -3.728212
OS 10.02290858 -3.73098568
OS 10.03539014 -3.73375936
OS 10.05341906 -3.7351462
OS 10.06728746 -3.7351462
OS 10.07422166 -3.73375936
OS 10.08392954 -3.73375936
OS 10.09502426 -3.73237252
OS 10.10611898 -3.73098568
OS 10.12137422 -3.83499868
OS 10.11860054 -3.83499868
OS 10.11305318 -3.83638552
OS 10.1033453 -3.83777236
OS 10.09086374 -3.8391592
OS 10.07699534 -3.84193288
OS 10.0617401 -3.84331972
OS 10.03122962 -3.84470656
OS 10.0201349 -3.84470656
OS 10.00904018 -3.84331972
OS 9.99517178 -3.84193288
OS 9.9785297 -3.84054604
OS 9.96188762 -3.83638552
OS 9.94663238 -3.832225
OS 9.93137714 -3.8252908
OS 9.9299903 -3.82390396
OS 9.92582978 -3.82113028
OS 9.92028242 -3.81696976
OS 9.91196138 -3.81003556
OS 9.90502718 -3.80310136
OS 9.89670614 -3.79339348
OS 9.8883851 -3.7836856
OS 9.88283774 -3.77120404
OS 9.88283774 -3.7698172
OS 9.88006406 -3.76426984
OS 9.87867722 -3.75456196
OS 9.87590354 -3.74069356
OS 9.87312986 -3.72266464
OS 9.87174302 -3.71156992
OS 9.87174302 -3.69908836
OS 9.87035618 -3.68383312
OS 9.86896934 -3.66857788
OS 9.86896934 -3.6519358
OS 9.86896934 -3.63252004
OS 9.86896934 -3.23033644
OS 9.78159842 -3.23033644
OS 9.78159842 -3.138805
OS 9.86896934 -3.138805
OS 9.86896934 -2.96683684
OS 9.98685074 -2.896108
OS 9.98685074 -3.138805
OE
OB 8.6332949 -3.12493914 I
OS 8.64300278 -3.12632598
OS 8.65548434 -3.12909966
OS 8.66935274 -3.13187334
OS 8.68460798 -3.13603386
OS 8.69986322 -3.14158122
OS 8.7165053 -3.14851542
OS 8.73314738 -3.15683646
OS 8.7511763 -3.16654434
OS 8.76781838 -3.17763906
OS 8.78446046 -3.19150746
OS 8.80110254 -3.2067627
OS 8.81635778 -3.22479162
OS 8.81635778 -3.13880754
OS 8.9245313 -3.13880754
OS 8.9245313 -3.7406961
OS 8.9245313 -3.74208294
OS 8.9245313 -3.7476303
OS 8.9245313 -3.75595134
OS 8.9245313 -3.76704606
OS 8.92314446 -3.77952762
OS 8.92314446 -3.79478286
OS 8.92175762 -3.81142494
OS 8.92037078 -3.82945386
OS 8.91621026 -3.86689854
OS 8.9106629 -3.90573006
OS 8.90650238 -3.92375898
OS 8.90234186 -3.94040106
OS 8.8967945 -3.9556563
OS 8.89124714 -3.9695247
OS 8.89124714 -3.97091154
OS 8.8898603 -3.97229838
OS 8.88431294 -3.98061942
OS 8.87737874 -3.99310098
OS 8.86628402 -4.00835622
OS 8.85102878 -4.0249983
OS 8.83299986 -4.04302722
OS 8.81081042 -4.06105614
OS 8.7858473 -4.07631138
OS 8.78446046 -4.07631138
OS 8.78307362 -4.07769822
OS 8.7789131 -4.0804719
OS 8.77336574 -4.08185874
OS 8.76643154 -4.08601926
OS 8.7581105 -4.08879294
OS 8.7373079 -4.09572714
OS 8.71234478 -4.10404818
OS 8.6818343 -4.10959554
OS 8.6471633 -4.1151429
OS 8.60971862 -4.11652974
OS 8.59723706 -4.11652974
OS 8.58891602 -4.1151429
OS 8.5778213 -4.1151429
OS 8.56672658 -4.11375606
OS 8.55285818 -4.11236922
OS 8.53760294 -4.10959554
OS 8.50570562 -4.10266134
OS 8.47242146 -4.09295346
OS 8.4391373 -4.07908506
OS 8.40862682 -4.0596693
OS 8.40723998 -4.05828246
OS 8.40585314 -4.05689562
OS 8.39614526 -4.04857458
OS 8.38505054 -4.03609302
OS 8.37118214 -4.0180641
OS 8.35731374 -3.99448782
OS 8.34483218 -3.96536418
OS 8.34067166 -3.9487221
OS 8.33789798 -3.93069318
OS 8.3351243 -3.91266426
OS 8.3351243 -3.89186166
OS 8.45023202 -3.9071169
OS 8.45023202 -3.90989058
OS 8.45161886 -3.91543794
OS 8.45439254 -3.92514582
OS 8.45716622 -3.93762738
OS 8.46271358 -3.95010894
OS 8.46964778 -3.9625905
OS 8.47796882 -3.97507206
OS 8.48906354 -3.98477994
OS 8.49183722 -3.98616678
OS 8.49738458 -3.9903273
OS 8.50709246 -3.99587466
OS 8.52096086 -4.00142202
OS 8.53760294 -4.00835622
OS 8.55840554 -4.01390358
OS 8.58336866 -4.0180641
OS 8.60971862 -4.01945094
OS 8.62358702 -4.01945094
OS 8.63745542 -4.0180641
OS 8.65687118 -4.01529042
OS 8.67628694 -4.0111299
OS 8.69708954 -4.00558254
OS 8.71789214 -3.9972615
OS 8.73592106 -3.98616678
OS 8.7373079 -3.98477994
OS 8.74285526 -3.98061942
OS 8.7511763 -3.97229838
OS 8.76088418 -3.9625905
OS 8.77059206 -3.9487221
OS 8.78029994 -3.93346686
OS 8.79000782 -3.91543794
OS 8.79694202 -3.89463534
OS 8.79694202 -3.8932485
OS 8.79832886 -3.88770114
OS 8.7997157 -3.87660642
OS 8.80110254 -3.86273802
OS 8.80248938 -3.85303014
OS 8.80248938 -3.84193542
OS 8.80387622 -3.82945386
OS 8.80387622 -3.81558546
OS 8.80387622 -3.80033022
OS 8.80526306 -3.7823013
OS 8.80526306 -3.76427238
OS 8.80526306 -3.74346978
OS 8.80387622 -3.74485662
OS 8.80110254 -3.7476303
OS 8.79694202 -3.75179082
OS 8.79139466 -3.75733818
OS 8.78446046 -3.76427238
OS 8.77475258 -3.77259342
OS 8.76365786 -3.78091446
OS 8.75256314 -3.7892355
OS 8.7234395 -3.80587758
OS 8.69154218 -3.82113282
OS 8.67351326 -3.82668018
OS 8.6540975 -3.8308407
OS 8.6332949 -3.83361438
OS 8.6124923 -3.83500122
OS 8.6055581 -3.83500122
OS 8.5986239 -3.83361438
OS 8.58891602 -3.83361438
OS 8.57643446 -3.83222754
OS 8.56256606 -3.82945386
OS 8.54731082 -3.82668018
OS 8.53066874 -3.82251966
OS 8.51263982 -3.8169723
OS 8.4946109 -3.8100381
OS 8.47658198 -3.80171706
OS 8.45716622 -3.79200918
OS 8.4391373 -3.77952762
OS 8.42110838 -3.76565922
OS 8.4044663 -3.75040398
OS 8.38921106 -3.73237506
OS 8.38782422 -3.73098822
OS 8.38643738 -3.72821454
OS 8.38227686 -3.72128034
OS 8.3767295 -3.71434614
OS 8.37118214 -3.70325142
OS 8.36424794 -3.6921567
OS 8.35731374 -3.6782883
OS 8.35037954 -3.66164622
OS 8.34344534 -3.64500414
OS 8.33651114 -3.62558838
OS 8.32957694 -3.60617262
OS 8.32402958 -3.58398318
OS 8.3143217 -3.53683062
OS 8.31293486 -3.51048066
OS 8.31154802 -3.4841307
OS 8.31154802 -3.48274386
OS 8.31154802 -3.47997018
OS 8.31154802 -3.47442282
OS 8.31154802 -3.46748862
OS 8.31293486 -3.45778074
OS 8.31293486 -3.44807286
OS 8.31570854 -3.42310974
OS 8.31986906 -3.39537294
OS 8.32680326 -3.36486246
OS 8.3351243 -3.33296514
OS 8.34760586 -3.30106782
OS 8.34760586 -3.29968098
OS 8.3489927 -3.2969073
OS 8.35176638 -3.29274678
OS 8.35454006 -3.28719942
OS 8.3628611 -3.27194418
OS 8.37395582 -3.25252842
OS 8.38921106 -3.23172582
OS 8.40723998 -3.21092322
OS 8.42804258 -3.18873378
OS 8.45161886 -3.17070486
OS 8.4530057 -3.17070486
OS 8.45439254 -3.16931802
OS 8.45855306 -3.16654434
OS 8.46410042 -3.16377066
OS 8.47796882 -3.15544962
OS 8.49738458 -3.14712858
OS 8.52096086 -3.13880754
OS 8.54869766 -3.1304865
OS 8.57920814 -3.12493914
OS 8.6124923 -3.1235523
OS 8.62497386 -3.1235523
OS 8.6332949 -3.12493914
OE
OB 9.22131506 -3.21924426 I
OS 9.2227019 -3.21785742
OS 9.22547558 -3.21508374
OS 9.2296361 -3.21092322
OS 9.2365703 -3.20398902
OS 9.2435045 -3.19705482
OS 9.25321238 -3.18873378
OS 9.26569394 -3.18041274
OS 9.2781755 -3.17070486
OS 9.2920439 -3.16238382
OS 9.30729914 -3.15406278
OS 9.34335698 -3.13880754
OS 9.36277274 -3.13187334
OS 9.38357534 -3.12771282
OS 9.40576478 -3.12493914
OS 9.42795422 -3.1235523
OS 9.44043578 -3.1235523
OS 9.45569102 -3.12493914
OS 9.47371994 -3.12771282
OS 9.49452254 -3.13048396
OS 9.51671198 -3.13603132
OS 9.53890142 -3.14435236
OS 9.56109086 -3.15406024
OS 9.56386454 -3.15544708
OS 9.57079874 -3.1596076
OS 9.58050662 -3.1665418
OS 9.59298818 -3.17624968
OS 9.60546974 -3.18873124
OS 9.61933814 -3.20259964
OS 9.6318197 -3.21924172
OS 9.64291442 -3.23865748
OS 9.64430126 -3.24143116
OS 9.64707494 -3.24836536
OS 9.65123546 -3.26084692
OS 9.65539598 -3.27887584
OS 9.6595565 -3.30106528
OS 9.66371702 -3.32741524
OS 9.6664907 -3.35931256
OS 9.66787754 -3.3953704
OS 9.66787754 -3.83499868
OS 9.54999614 -3.83499868
OS 9.54999614 -3.39398356
OS 9.54999614 -3.39259672
OS 9.54999614 -3.38982304
OS 9.54999614 -3.38566252
OS 9.54999614 -3.38011516
OS 9.5486093 -3.36485992
OS 9.54583562 -3.34544416
OS 9.54028826 -3.32464156
OS 9.53335406 -3.30383896
OS 9.52364618 -3.28303636
OS 9.51116462 -3.26639428
OS 9.50977778 -3.26500744
OS 9.50423042 -3.25946008
OS 9.49590938 -3.25252588
OS 9.48342782 -3.24559168
OS 9.46817258 -3.23727318
OS 9.45014366 -3.23172582
OS 9.42795422 -3.22617846
OS 9.4029911 -3.22479162
OS 9.39467006 -3.22479162
OS 9.38496218 -3.22617846
OS 9.37109378 -3.2275653
OS 9.35722538 -3.23172582
OS 9.3405833 -3.23588634
OS 9.32394122 -3.24282054
OS 9.3059123 -3.25252842
OS 9.30452546 -3.25391526
OS 9.2989781 -3.25807578
OS 9.29065706 -3.26362314
OS 9.28094918 -3.27194418
OS 9.26985446 -3.2830389
OS 9.25875974 -3.29552046
OS 9.24905186 -3.3107757
OS 9.24073082 -3.32741778
OS 9.23934398 -3.33019146
OS 9.23795714 -3.33573882
OS 9.23518346 -3.34683354
OS 9.23102294 -3.36070194
OS 9.22686242 -3.37873086
OS 9.22408874 -3.4009203
OS 9.2227019 -3.42588342
OS 9.22131506 -3.45500706
OS 9.22131506 -3.83500122
OS 9.10343366 -3.83500122
OS 9.10343366 -2.87530794
OS 9.22131506 -2.87530794
OS 9.22131506 -3.21924426
OE
OB 11.86879262 -2.86005016 I
OS 11.88127418 -2.861437
OS 11.89652942 -2.86282384
OS 11.91178466 -2.86421068
OS 11.92981358 -2.8683712
OS 11.96725826 -2.87669224
OS 12.00886346 -2.8891738
OS 12.02966606 -2.89749484
OS 12.04908182 -2.90720272
OS 12.06849758 -2.91968428
OS 12.08791334 -2.93216584
OS 12.08930018 -2.93355268
OS 12.09207386 -2.93493952
OS 12.09762122 -2.93910004
OS 12.10455542 -2.94603424
OS 12.11148962 -2.95296844
OS 12.1211975 -2.96267632
OS 12.13090538 -2.97377104
OS 12.1420001 -2.98486576
OS 12.15309482 -2.99873416
OS 12.16418954 -3.01537624
OS 12.1766711 -3.03201832
OS 12.18776582 -3.05004724
OS 12.1974737 -3.07084984
OS 12.20856842 -3.09165244
OS 12.21688946 -3.11384188
OS 12.2252105 -3.138805
OS 12.1003949 -3.16792864
OS 12.1003949 -3.1665418
OS 12.09900806 -3.16376812
OS 12.09623438 -3.15822076
OS 12.0934607 -3.15128656
OS 12.09068702 -3.14296552
OS 12.0865265 -3.1318708
OS 12.07543178 -3.10968136
OS 12.06156338 -3.08471824
OS 12.0449213 -3.05975512
OS 12.0241187 -3.03617884
OS 12.00192926 -3.01537624
OS 11.99915558 -3.01260256
OS 11.99083454 -3.0070552
OS 11.97696614 -3.000121
OS 11.95893722 -2.99041312
OS 11.93536094 -2.98209208
OS 11.90901098 -2.97377104
OS 11.87711366 -2.96822368
OS 11.84244266 -2.96683684
OS 11.83134794 -2.96683684
OS 11.82441374 -2.96822368
OS 11.81470586 -2.96822368
OS 11.80361114 -2.96961052
OS 11.77726118 -2.97377104
OS 11.74813754 -2.9793184
OS 11.71762706 -2.98902628
OS 11.68572974 -3.00289468
OS 11.6566061 -3.0209236
OS 11.65521926 -3.0209236
OS 11.65383242 -3.02369728
OS 11.64412454 -3.03063148
OS 11.63164298 -3.0417262
OS 11.61638774 -3.05836828
OS 11.59835882 -3.07917088
OS 11.58171674 -3.10274716
OS 11.5664615 -3.1318708
OS 11.5525931 -3.16376812
OS 11.5525931 -3.16515496
OS 11.55120626 -3.16792864
OS 11.54981942 -3.17208916
OS 11.54843258 -3.17902336
OS 11.5456589 -3.1873444
OS 11.54288522 -3.19705228
OS 11.5387247 -3.22062856
OS 11.53317734 -3.24836536
OS 11.52762998 -3.27887584
OS 11.5248563 -3.31216
OS 11.52346946 -3.34821784
OS 11.52346946 -3.34960468
OS 11.52346946 -3.3537652
OS 11.52346946 -3.3606994
OS 11.52346946 -3.36902044
OS 11.5248563 -3.37872832
OS 11.5248563 -3.39120988
OS 11.52624314 -3.40507828
OS 11.52762998 -3.42033352
OS 11.5317905 -3.45361768
OS 11.5387247 -3.48967552
OS 11.54704574 -3.52573336
OS 11.55814046 -3.5617912
OS 11.55814046 -3.56317804
OS 11.5595273 -3.56595172
OS 11.56230098 -3.57011224
OS 11.56507466 -3.57704644
OS 11.5733957 -3.59368852
OS 11.58587726 -3.61310428
OS 11.6011325 -3.63529372
OS 11.62054826 -3.65887
OS 11.6427377 -3.6796726
OS 11.66908766 -3.69908836
OS 11.6704745 -3.69908836
OS 11.67324818 -3.7004752
OS 11.6774087 -3.70324888
OS 11.68295606 -3.70602256
OS 11.68989026 -3.70879624
OS 11.6982113 -3.71295676
OS 11.71762706 -3.7212778
OS 11.74259018 -3.72959884
OS 11.77032698 -3.73653304
OS 11.80083746 -3.7420804
OS 11.83273478 -3.74346724
OS 11.84244266 -3.74346724
OS 11.8507637 -3.7420804
OS 11.86047158 -3.7420804
OS 11.87017946 -3.74069356
OS 11.89514258 -3.7351462
OS 11.92426622 -3.728212
OS 11.95338986 -3.71711728
OS 11.98390034 -3.70186204
OS 11.99915558 -3.693541
OS 12.01302398 -3.68244628
OS 12.01441082 -3.68105944
OS 12.01579766 -3.6796726
OS 12.01995818 -3.67551208
OS 12.02550554 -3.67135156
OS 12.0310529 -3.66441736
OS 12.0379871 -3.65609632
OS 12.04630814 -3.64777528
OS 12.05324234 -3.63668056
OS 12.06156338 -3.624199
OS 12.07127126 -3.6103306
OS 12.0795923 -3.5964622
OS 12.08791334 -3.57982012
OS 12.09484754 -3.5617912
OS 12.10178174 -3.54237544
OS 12.10871594 -3.52157284
OS 12.1142633 -3.4993834
OS 12.24185258 -3.53128072
OS 12.24185258 -3.53266756
OS 12.24046574 -3.53821492
OS 12.23769206 -3.54653596
OS 12.23353154 -3.55763068
OS 12.22937102 -3.57011224
OS 12.22382366 -3.58536748
OS 12.21688946 -3.60200956
OS 12.20856842 -3.62003848
OS 12.18915266 -3.65887
OS 12.16418954 -3.69770152
OS 12.1489343 -3.71711728
OS 12.13367906 -3.73653304
OS 12.11703698 -3.75317512
OS 12.09762122 -3.7698172
OS 12.09623438 -3.77120404
OS 12.0934607 -3.77397772
OS 12.0865265 -3.7767514
OS 12.0795923 -3.78229876
OS 12.06849758 -3.78923296
OS 12.05740286 -3.79616716
OS 12.04214762 -3.80310136
OS 12.02689238 -3.81003556
OS 12.00886346 -3.8183566
OS 11.9894477 -3.8252908
OS 11.9686451 -3.832225
OS 11.94645566 -3.8391592
OS 11.92287938 -3.84470656
OS 11.89791626 -3.84748024
OS 11.8715663 -3.85025392
OS 11.8438295 -3.85164076
OS 11.82857426 -3.85164076
OS 11.81747954 -3.85025392
OS 11.80499798 -3.85025392
OS 11.78974274 -3.84886708
OS 11.77310066 -3.8460934
OS 11.7536849 -3.84331972
OS 11.71346654 -3.83638552
OS 11.67186134 -3.8252908
OS 11.63025614 -3.81003556
OS 11.61084038 -3.80032768
OS 11.59142462 -3.78923296
OS 11.59003778 -3.78784612
OS 11.5872641 -3.78645928
OS 11.58171674 -3.78229876
OS 11.57616938 -3.7767514
OS 11.56784834 -3.77120404
OS 11.55814046 -3.762883
OS 11.54704574 -3.75317512
OS 11.53595102 -3.7420804
OS 11.5248563 -3.72959884
OS 11.51237474 -3.71711728
OS 11.48741162 -3.68521996
OS 11.46383534 -3.64777528
OS 11.44303274 -3.60617008
OS 11.44303274 -3.60478324
OS 11.44025906 -3.60062272
OS 11.43887222 -3.59368852
OS 11.4347117 -3.58536748
OS 11.43193802 -3.57427276
OS 11.4277775 -3.56040436
OS 11.42223014 -3.54514912
OS 11.41806962 -3.52850704
OS 11.4139091 -3.51047812
OS 11.40836174 -3.48967552
OS 11.40142754 -3.44668348
OS 11.39588018 -3.39814408
OS 11.3931065 -3.34821784
OS 11.3931065 -3.346831
OS 11.3931065 -3.34128364
OS 11.3931065 -3.3329626
OS 11.39449334 -3.32325472
OS 11.39449334 -3.30938632
OS 11.39588018 -3.29551792
OS 11.39726702 -3.277489
OS 11.4000407 -3.25946008
OS 11.4069749 -3.21924172
OS 11.41668278 -3.17486284
OS 11.43055118 -3.13048396
OS 11.44996694 -3.08749192
OS 11.45135378 -3.08610508
OS 11.45274062 -3.08194456
OS 11.4555143 -3.0763972
OS 11.46106166 -3.069463
OS 11.46660902 -3.05975512
OS 11.47354322 -3.0486604
OS 11.49157214 -3.02369728
OS 11.51514842 -2.99596048
OS 11.54288522 -2.96822368
OS 11.57478254 -2.94048688
OS 11.61222722 -2.9169106
OS 11.61361406 -2.91552376
OS 11.61777458 -2.91413692
OS 11.62332194 -2.91136324
OS 11.63025614 -2.90720272
OS 11.64135086 -2.9030422
OS 11.65244558 -2.89888168
OS 11.66631398 -2.89333432
OS 11.68156922 -2.88778696
OS 11.6982113 -2.8822396
OS 11.71624022 -2.87669224
OS 11.75507174 -2.8683712
OS 11.79945062 -2.861437
OS 11.84521634 -2.85866332
OS 11.85908474 -2.85866332
OS 11.86879262 -2.86005016
OE
OB 15.11538506 -3.83499868 I
OS 14.98224842 -3.83499868
OS 14.6105753 -2.8753054
OS 14.7492593 -2.8753054
OS 14.9988905 -3.57288592
OS 14.9988905 -3.57427276
OS 15.00027734 -3.57704644
OS 15.00166418 -3.58120696
OS 15.00443786 -3.58675432
OS 15.0058247 -3.59507536
OS 15.00859838 -3.6033964
OS 15.01553258 -3.624199
OS 15.02385362 -3.64777528
OS 15.03217466 -3.67412524
OS 15.04881674 -3.72959884
OS 15.04881674 -3.728212
OS 15.05020358 -3.72543832
OS 15.05159042 -3.7212778
OS 15.05297726 -3.71573044
OS 15.05713778 -3.7004752
OS 15.06407198 -3.6796726
OS 15.07100618 -3.65609632
OS 15.07932722 -3.62974636
OS 15.0890351 -3.60200956
OS 15.10012982 -3.57288592
OS 15.36085574 -2.8753054
OS 15.48983186 -2.8753054
OS 15.11538506 -3.83499868
OE
OB 16.00018898 -3.83499868 I
OS 15.88230758 -3.83499868
OS 15.88230758 -3.08471824
OS 15.88092074 -3.08610508
OS 15.87398654 -3.09165244
OS 15.8656655 -3.09997348
OS 15.8517971 -3.10968136
OS 15.83654186 -3.12216292
OS 15.8171261 -3.13603132
OS 15.79493666 -3.15128656
OS 15.76997354 -3.1665418
OS 15.7685867 -3.1665418
OS 15.76719986 -3.16792864
OS 15.75887882 -3.173476
OS 15.74501042 -3.1804102
OS 15.72836834 -3.18873124
OS 15.70895258 -3.19843912
OS 15.68814998 -3.208147
OS 15.66734738 -3.21785488
OS 15.64654478 -3.22617592
OS 15.64654478 -3.11245504
OS 15.64793162 -3.11245504
OS 15.6507053 -3.10968136
OS 15.65625266 -3.10829452
OS 15.66318686 -3.104134
OS 15.6715079 -3.09997348
OS 15.68121578 -3.09442612
OS 15.70479206 -3.08055772
OS 15.73252886 -3.06530248
OS 15.76026566 -3.04588672
OS 15.7893893 -3.02369728
OS 15.81851294 -3.000121
OS 15.81989978 -2.99873416
OS 15.82128662 -2.99734732
OS 15.82544714 -2.9931868
OS 15.8309945 -2.98902628
OS 15.84347606 -2.97515788
OS 15.86011814 -2.9585158
OS 15.87676022 -2.93910004
OS 15.89478914 -2.9169106
OS 15.91004438 -2.89472116
OS 15.92391278 -2.87114488
OS 16.00018898 -2.87114488
OS 16.00018898 -3.83499868
OE
OB 14.13488918 -3.83499868 I
OS 14.02532882 -3.83499868
OS 14.02532882 -3.74762776
OS 14.02394198 -3.7490146
OS 14.02255514 -3.75178828
OS 14.01839462 -3.75733564
OS 14.01284726 -3.76426984
OS 14.00591306 -3.77120404
OS 13.99759202 -3.77952508
OS 13.98788414 -3.78923296
OS 13.97540258 -3.79894084
OS 13.96292102 -3.80864872
OS 13.94905262 -3.8183566
OS 13.93241054 -3.82667764
OS 13.91438162 -3.83361184
OS 13.8963527 -3.84054604
OS 13.8755501 -3.8460934
OS 13.85336066 -3.84886708
OS 13.82978438 -3.85025392
OS 13.82146334 -3.85025392
OS 13.81591598 -3.84886708
OS 13.7992739 -3.84748024
OS 13.77985814 -3.84470656
OS 13.75628186 -3.8391592
OS 13.7299319 -3.83083816
OS 13.70358194 -3.81974344
OS 13.67723198 -3.8044882
OS 13.67584514 -3.8044882
OS 13.6744583 -3.80171452
OS 13.66613726 -3.79616716
OS 13.6536557 -3.78507244
OS 13.63840046 -3.77120404
OS 13.62037154 -3.75317512
OS 13.60234262 -3.73098568
OS 13.5843137 -3.70602256
OS 13.56905846 -3.67689892
OS 13.56905846 -3.67551208
OS 13.56767162 -3.6727384
OS 13.56628478 -3.66857788
OS 13.5635111 -3.66303052
OS 13.56073742 -3.65470948
OS 13.5565769 -3.6450016
OS 13.55380322 -3.63529372
OS 13.55102954 -3.62281216
OS 13.54409534 -3.59507536
OS 13.53716114 -3.56317804
OS 13.53300062 -3.5271202
OS 13.53161378 -3.48828868
OS 13.53161378 -3.48690184
OS 13.53161378 -3.48412816
OS 13.53161378 -3.4785808
OS 13.53161378 -3.47025976
OS 13.53300062 -3.46193872
OS 13.53300062 -3.450844
OS 13.5357743 -3.42588088
OS 13.53993482 -3.39675724
OS 13.54686902 -3.36485992
OS 13.55519006 -3.33157576
OS 13.56628478 -3.29967844
OS 13.56628478 -3.2982916
OS 13.56767162 -3.29551792
OS 13.5704453 -3.2913574
OS 13.57321898 -3.28581004
OS 13.58154002 -3.2705548
OS 13.59263474 -3.25113904
OS 13.60650314 -3.23033644
OS 13.62453206 -3.20953384
OS 13.64533466 -3.1873444
OS 13.67029778 -3.16931548
OS 13.67168462 -3.16931548
OS 13.67307146 -3.16792864
OS 13.67723198 -3.16515496
OS 13.68277934 -3.16238128
OS 13.69664774 -3.15544708
OS 13.7160635 -3.1457392
OS 13.73825294 -3.13741816
OS 13.7646029 -3.13048396
OS 13.79372654 -3.1249366
OS 13.82423702 -3.12354976
OS 13.83533174 -3.12354976
OS 13.84642646 -3.1249366
OS 13.8616817 -3.12632344
OS 13.87971062 -3.13048396
OS 13.89912638 -3.13464448
OS 13.91854214 -3.14157868
OS 13.93657106 -3.15128656
OS 13.93934474 -3.1526734
OS 13.9448921 -3.15544708
OS 13.95321314 -3.16238128
OS 13.96430786 -3.16931548
OS 13.97817626 -3.17902336
OS 13.99065782 -3.19150492
OS 14.00452622 -3.20398648
OS 14.01700778 -3.21924172
OS 14.01700778 -2.8753054
OS 14.13488918 -2.8753054
OS 14.13488918 -3.83499868
OE
OB 12.70783082 -3.1249366 I
OS 12.72863342 -3.12632344
OS 12.7522097 -3.12909712
OS 12.77578598 -3.13325764
OS 12.79936226 -3.138805
OS 12.8215517 -3.1457392
OS 12.82432538 -3.14712604
OS 12.83125958 -3.14989972
OS 12.84096746 -3.15406024
OS 12.85344902 -3.1596076
OS 12.86731742 -3.16792864
OS 12.88118582 -3.17624968
OS 12.89366738 -3.1873444
OS 12.9047621 -3.19843912
OS 12.90614894 -3.19982596
OS 12.90892262 -3.20398648
OS 12.91308314 -3.21092068
OS 12.9186305 -3.21924172
OS 12.9255647 -3.23172328
OS 12.93111206 -3.24420484
OS 12.93665942 -3.25946008
OS 12.94081994 -3.277489
OS 12.94081994 -3.27887584
OS 12.94220678 -3.28303636
OS 12.94359362 -3.2913574
OS 12.94498046 -3.30245212
OS 12.94498046 -3.31770736
OS 12.9463673 -3.33573628
OS 12.94775414 -3.35931256
OS 12.94775414 -3.38566252
OS 12.94775414 -3.54376228
OS 12.94775414 -3.54514912
OS 12.94775414 -3.55069648
OS 12.94775414 -3.55901752
OS 12.94775414 -3.57011224
OS 12.94775414 -3.5825938
OS 12.94775414 -3.59784904
OS 12.94914098 -3.6311332
OS 12.94914098 -3.6658042
OS 12.95052782 -3.7004752
OS 12.95191466 -3.71573044
OS 12.95191466 -3.72959884
OS 12.9533015 -3.7420804
OS 12.95468834 -3.75178828
OS 12.95468834 -3.75317512
OS 12.95607518 -3.75872248
OS 12.95746202 -3.76704352
OS 12.96162254 -3.77813824
OS 12.96439622 -3.7906198
OS 12.96994358 -3.8044882
OS 12.97687778 -3.81974344
OS 12.98381198 -3.83499868
OS 12.86038322 -3.83499868
OS 12.85899638 -3.83361184
OS 12.85760954 -3.82806448
OS 12.85483586 -3.82113028
OS 12.85067534 -3.81003556
OS 12.84651482 -3.797554
OS 12.84374114 -3.78229876
OS 12.84096746 -3.76565668
OS 12.83819378 -3.74762776
OS 12.83680694 -3.74762776
OS 12.8354201 -3.75040144
OS 12.82709906 -3.75733564
OS 12.8146175 -3.76704352
OS 12.79797542 -3.77952508
OS 12.77717282 -3.79200664
OS 12.75637022 -3.80587504
OS 12.73418078 -3.8183566
OS 12.7106045 -3.82806448
OS 12.70783082 -3.82945132
OS 12.69950978 -3.83083816
OS 12.68702822 -3.83499868
OS 12.67177298 -3.8391592
OS 12.65235722 -3.84331972
OS 12.63016778 -3.8460934
OS 12.60520466 -3.84886708
OS 12.58024154 -3.85025392
OS 12.56914682 -3.85025392
OS 12.56082578 -3.84886708
OS 12.5511179 -3.84886708
OS 12.54002318 -3.84748024
OS 12.51506006 -3.84331972
OS 12.48732326 -3.83638552
OS 12.45681278 -3.82667764
OS 12.42907598 -3.81280924
OS 12.40411286 -3.79478032
OS 12.40133918 -3.79200664
OS 12.39440498 -3.78507244
OS 12.3846971 -3.77259088
OS 12.37360238 -3.7559488
OS 12.36250766 -3.7351462
OS 12.35279978 -3.71156992
OS 12.34586558 -3.68244628
OS 12.34447874 -3.66857788
OS 12.3430919 -3.6519358
OS 12.3430919 -3.64916212
OS 12.3430919 -3.64361476
OS 12.34447874 -3.63390688
OS 12.34586558 -3.62142532
OS 12.34863926 -3.60617008
OS 12.35279978 -3.59091484
OS 12.35834714 -3.57427276
OS 12.36528134 -3.55901752
OS 12.36666818 -3.55763068
OS 12.36944186 -3.55208332
OS 12.37498922 -3.54376228
OS 12.38192342 -3.5340544
OS 12.39024446 -3.52295968
OS 12.40133918 -3.51186496
OS 12.4124339 -3.50077024
OS 12.4263023 -3.49106236
OS 12.42768914 -3.48967552
OS 12.4332365 -3.48690184
OS 12.4401707 -3.48135448
OS 12.45126542 -3.47580712
OS 12.46374698 -3.47025976
OS 12.47900222 -3.46332556
OS 12.49425746 -3.4577782
OS 12.51228638 -3.45223084
OS 12.51367322 -3.45223084
OS 12.51922058 -3.450844
OS 12.52754162 -3.44807032
OS 12.53863634 -3.44668348
OS 12.55250474 -3.4439098
OS 12.57053366 -3.44113612
OS 12.59133626 -3.4369756
OS 12.61629938 -3.43420192
OS 12.61768622 -3.43420192
OS 12.62323358 -3.43281508
OS 12.63016778 -3.43281508
OS 12.63987566 -3.43142824
OS 12.65097038 -3.4300414
OS 12.66483878 -3.42726772
OS 12.68009402 -3.42588088
OS 12.6967361 -3.4231072
OS 12.73002026 -3.416173
OS 12.7660781 -3.4092388
OS 12.79797542 -3.40091776
OS 12.81323066 -3.39675724
OS 12.82709906 -3.39259672
OS 12.82709906 -3.39120988
OS 12.82709906 -3.3884362
OS 12.8284859 -3.38011516
OS 12.8284859 -3.37040728
OS 12.8284859 -3.36485992
OS 12.8284859 -3.36208624
OS 12.8284859 -3.3606994
OS 12.8284859 -3.35931256
OS 12.8284859 -3.35099152
OS 12.82709906 -3.33712312
OS 12.82432538 -3.32186788
OS 12.82016486 -3.3052258
OS 12.81323066 -3.28858372
OS 12.80490962 -3.27332848
OS 12.7938149 -3.26084692
OS 12.79242806 -3.25946008
OS 12.78549386 -3.25391272
OS 12.77439914 -3.24836536
OS 12.76053074 -3.24004432
OS 12.74111498 -3.23311012
OS 12.71892554 -3.22617592
OS 12.69118874 -3.2220154
OS 12.65929142 -3.22062856
OS 12.64542302 -3.22062856
OS 12.63155462 -3.2220154
OS 12.61213886 -3.22478908
OS 12.5927231 -3.22756276
OS 12.5719205 -3.23311012
OS 12.55250474 -3.24004432
OS 12.53586266 -3.2497522
OS 12.53447582 -3.25113904
OS 12.52892846 -3.25529956
OS 12.52199426 -3.26223376
OS 12.51367322 -3.27332848
OS 12.50535218 -3.28719688
OS 12.4956443 -3.3052258
OS 12.48732326 -3.32741524
OS 12.47900222 -3.35237836
OS 12.3638945 -3.33712312
OS 12.3638945 -3.33573628
OS 12.36528134 -3.33434944
OS 12.36528134 -3.33018892
OS 12.36666818 -3.32464156
OS 12.3708287 -3.31216
OS 12.37637606 -3.29413108
OS 12.38331026 -3.27610216
OS 12.3916313 -3.2566864
OS 12.40272602 -3.23727064
OS 12.41520758 -3.21924172
OS 12.41659442 -3.21785488
OS 12.42214178 -3.21230752
OS 12.43046282 -3.20398648
OS 12.44155754 -3.19289176
OS 12.45681278 -3.18179704
OS 12.4748417 -3.17070232
OS 12.4956443 -3.15822076
OS 12.51922058 -3.14851288
OS 12.52060742 -3.14851288
OS 12.52199426 -3.14712604
OS 12.52615478 -3.1457392
OS 12.53170214 -3.14435236
OS 12.54557054 -3.14019184
OS 12.5649863 -3.13603132
OS 12.58717574 -3.1318708
OS 12.61491254 -3.12771028
OS 12.64403618 -3.1249366
OS 12.67732034 -3.12354976
OS 12.69257558 -3.12354976
OS 12.70783082 -3.1249366
OE
OB 13.40679818 -3.1249366 I
OS 13.42205342 -3.12771028
OS 13.44008234 -3.13325764
OS 13.4594981 -3.14019184
OS 13.48168754 -3.14989972
OS 13.50526382 -3.16238128
OS 13.46227178 -3.2705548
OS 13.46088494 -3.26916796
OS 13.45533758 -3.26639428
OS 13.44701654 -3.26223376
OS 13.43592182 -3.25807324
OS 13.42344026 -3.25391272
OS 13.40818502 -3.2497522
OS 13.39292978 -3.24697852
OS 13.37767454 -3.24559168
OS 13.37074034 -3.24559168
OS 13.36380614 -3.24697852
OS 13.35409826 -3.24836536
OS 13.34439038 -3.25113904
OS 13.33190882 -3.25529956
OS 13.31942726 -3.26084692
OS 13.30833254 -3.26916796
OS 13.3069457 -3.2705548
OS 13.30278518 -3.27332848
OS 13.29862466 -3.27887584
OS 13.29169046 -3.28581004
OS 13.28475626 -3.29551792
OS 13.27782206 -3.30661264
OS 13.27088786 -3.3190942
OS 13.2653405 -3.33434944
OS 13.26395366 -3.33712312
OS 13.26256682 -3.34544416
OS 13.25979314 -3.35792572
OS 13.25563262 -3.3745678
OS 13.2514721 -3.3953704
OS 13.24869842 -3.41894668
OS 13.24731158 -3.4439098
OS 13.24592474 -3.4716466
OS 13.24592474 -3.83499868
OS 13.12804334 -3.83499868
OS 13.12804334 -3.138805
OS 13.23483002 -3.138805
OS 13.23483002 -3.24420484
OS 13.23621686 -3.242818
OS 13.24176422 -3.23311012
OS 13.24869842 -3.22062856
OS 13.25979314 -3.20537332
OS 13.27088786 -3.19011808
OS 13.28336942 -3.173476
OS 13.29585098 -3.1596076
OS 13.30833254 -3.14851288
OS 13.30971938 -3.14712604
OS 13.3138799 -3.14435236
OS 13.32220094 -3.14019184
OS 13.33052198 -3.13603132
OS 13.3416167 -3.1318708
OS 13.3554851 -3.12771028
OS 13.3693535 -3.1249366
OS 13.38460874 -3.12354976
OS 13.39431662 -3.12354976
OS 13.40679818 -3.1249366
OE
OB 5.33538938 -3.00012354 I
OS 4.9512347 -3.00012354
OS 4.89992162 -3.25946262
OS 4.90130846 -3.25807578
OS 4.90408214 -3.25668894
OS 4.90824266 -3.25391526
OS 4.91517686 -3.24975474
OS 4.9234979 -3.24559422
OS 4.93320578 -3.24004686
OS 4.95539522 -3.22895214
OS 4.98313202 -3.21785742
OS 5.0136425 -3.20814954
OS 5.04692666 -3.20121534
OS 5.06356874 -3.19844166
OS 5.09407922 -3.19844166
OS 5.10240026 -3.1998285
OS 5.11349498 -3.20121534
OS 5.12597654 -3.20260218
OS 5.13984494 -3.20537586
OS 5.15510018 -3.20953638
OS 5.18838434 -3.21924426
OS 5.20641326 -3.22617846
OS 5.22444218 -3.23588634
OS 5.2424711 -3.24559422
OS 5.26050002 -3.25668894
OS 5.2771421 -3.27055734
OS 5.29378418 -3.28581258
OS 5.29517102 -3.28719942
OS 5.2979447 -3.2899731
OS 5.30210522 -3.29413362
OS 5.30765258 -3.30106782
OS 5.31458678 -3.3107757
OS 5.32152098 -3.32048358
OS 5.32984202 -3.33296514
OS 5.33816306 -3.34683354
OS 5.34509726 -3.36208878
OS 5.3534183 -3.37873086
OS 5.3603525 -3.39814662
OS 5.3672867 -3.41756238
OS 5.37283406 -3.43836498
OS 5.37699458 -3.46194126
OS 5.37976826 -3.48551754
OS 5.3811551 -3.51048066
OS 5.3811551 -3.5118675
OS 5.3811551 -3.51602802
OS 5.3811551 -3.52296222
OS 5.37976826 -3.5326701
OS 5.37838142 -3.54376482
OS 5.37699458 -3.55624638
OS 5.3742209 -3.57150162
OS 5.37144722 -3.58675686
OS 5.36312618 -3.6228147
OS 5.34925778 -3.66025938
OS 5.34093674 -3.67967514
OS 5.32984202 -3.69770406
OS 5.3187473 -3.71711982
OS 5.3048789 -3.73514874
OS 5.30349206 -3.73653558
OS 5.30071838 -3.7406961
OS 5.29517102 -3.74624346
OS 5.28823682 -3.75317766
OS 5.27852894 -3.7614987
OS 5.26743422 -3.77259342
OS 5.25356582 -3.7823013
OS 5.23831058 -3.79339602
OS 5.2216685 -3.80449074
OS 5.20225274 -3.81419862
OS 5.18145014 -3.8239065
OS 5.1592607 -3.83361438
OS 5.13568442 -3.84054858
OS 5.10933446 -3.84609594
OS 5.08159766 -3.85025646
OS 5.05247402 -3.8516433
OS 5.03999246 -3.8516433
OS 5.03028458 -3.85025646
OS 5.01918986 -3.84886962
OS 5.0067083 -3.84748278
OS 4.99145306 -3.84609594
OS 4.97619782 -3.84193542
OS 4.94152682 -3.83361438
OS 4.90685582 -3.82113282
OS 4.8888269 -3.81281178
OS 4.87079798 -3.8031039
OS 4.8541559 -3.79200918
OS 4.83751382 -3.77952762
OS 4.83612698 -3.77814078
OS 4.8333533 -3.77675394
OS 4.83057962 -3.77120658
OS 4.82503226 -3.76565922
OS 4.81809806 -3.75872502
OS 4.81116386 -3.75040398
OS 4.80284282 -3.73930926
OS 4.79590862 -3.7268277
OS 4.78758758 -3.71434614
OS 4.77926654 -3.6990909
OS 4.7640113 -3.66580674
OS 4.75152974 -3.62697522
OS 4.74736922 -3.60617262
OS 4.74459554 -3.58398318
OS 4.8680243 -3.5742753
OS 4.8680243 -3.57566214
OS 4.8680243 -3.57843582
OS 4.86941114 -3.58259634
OS 4.87079798 -3.58953054
OS 4.8749585 -3.60478578
OS 4.88050586 -3.62558838
OS 4.8888269 -3.64639098
OS 4.89992162 -3.66996726
OS 4.91379002 -3.69076986
OS 4.9304321 -3.71018562
OS 4.93320578 -3.71157246
OS 4.93875314 -3.71711982
OS 4.94984786 -3.72405402
OS 4.9651031 -3.73237506
OS 4.98174518 -3.7406961
OS 5.00254778 -3.7476303
OS 5.02612406 -3.75317766
OS 5.05247402 -3.7545645
OS 5.06079506 -3.7545645
OS 5.06634242 -3.75317766
OS 5.0829845 -3.75179082
OS 5.10240026 -3.74624346
OS 5.12597654 -3.73930926
OS 5.14955282 -3.72821454
OS 5.17451594 -3.71157246
OS 5.18561066 -3.70186458
OS 5.19670538 -3.69076986
OS 5.19809222 -3.68938302
OS 5.19947906 -3.68799618
OS 5.20225274 -3.68383566
OS 5.20641326 -3.67967514
OS 5.21612114 -3.6644199
OS 5.22721586 -3.64500414
OS 5.23692374 -3.62142786
OS 5.24663162 -3.59230422
OS 5.25356582 -3.55763322
OS 5.2563395 -3.5396043
OS 5.2563395 -3.52018854
OS 5.2563395 -3.5188017
OS 5.2563395 -3.51602802
OS 5.2563395 -3.51048066
OS 5.25495266 -3.50354646
OS 5.25495266 -3.49522542
OS 5.25356582 -3.48551754
OS 5.2494053 -3.4633281
OS 5.2424711 -3.43697814
OS 5.23276322 -3.41062818
OS 5.21889482 -3.38566506
OS 5.19947906 -3.36208878
OS 5.19947906 -3.36070194
OS 5.19670538 -3.3593151
OS 5.18977118 -3.3523809
OS 5.17728962 -3.34267302
OS 5.16064754 -3.3315783
OS 5.1384581 -3.32187042
OS 5.11349498 -3.31216254
OS 5.08437134 -3.30522834
OS 5.06772926 -3.30245466
OS 5.0413793 -3.30245466
OS 5.03028458 -3.3038415
OS 5.01641618 -3.30522834
OS 4.9997741 -3.30938886
OS 4.98313202 -3.31354938
OS 4.9651031 -3.32048358
OS 4.94707418 -3.32880462
OS 4.94568734 -3.33019146
OS 4.94013998 -3.33296514
OS 4.93181894 -3.33989934
OS 4.92072422 -3.34683354
OS 4.9096295 -3.35654142
OS 4.89853478 -3.36902298
OS 4.88605322 -3.38150454
OS 4.87634534 -3.39675978
OS 4.76539814 -3.38150454
OS 4.85831642 -2.8877895
OS 5.33538938 -2.8877895
OS 5.33538938 -3.00012354
OE
OB 6.30617738 -2.87669478 I
OS 6.33391418 -2.87808162
OS 6.36165098 -2.8808553
OS 6.38938778 -2.88501582
OS 6.41296406 -2.88917634
OS 6.4143509 -2.88917634
OS 6.41712458 -2.89056318
OS 6.4212851 -2.89056318
OS 6.42683246 -2.89333686
OS 6.4420877 -2.89749738
OS 6.46150346 -2.90443158
OS 6.4836929 -2.91413946
OS 6.50726918 -2.92662102
OS 6.53084546 -2.94048942
OS 6.5530349 -2.95851834
OS 6.55442174 -2.95990518
OS 6.55580858 -2.96129202
OS 6.5599691 -2.96545254
OS 6.56551646 -2.96961306
OS 6.57938486 -2.98348146
OS 6.59602694 -3.00289722
OS 6.61405586 -3.0264735
OS 6.63347162 -3.0542103
OS 6.65150054 -3.08610762
OS 6.66675578 -3.12216546
OS 6.66675578 -3.1235523
OS 6.66814262 -3.12632598
OS 6.6709163 -3.13187334
OS 6.67230314 -3.14019438
OS 6.67646366 -3.14990226
OS 6.67923734 -3.16099698
OS 6.68201102 -3.17347854
OS 6.68617154 -3.18873378
OS 6.69033206 -3.20398902
OS 6.69310574 -3.22201794
OS 6.70003994 -3.26084946
OS 6.70420046 -3.3038415
OS 6.7055873 -3.35099406
OS 6.7055873 -3.3523809
OS 6.7055873 -3.35515458
OS 6.7055873 -3.36208878
OS 6.7055873 -3.36902298
OS 6.70420046 -3.37873086
OS 6.70420046 -3.38982558
OS 6.70281362 -3.41617554
OS 6.6986531 -3.44668602
OS 6.69449258 -3.47858334
OS 6.68755838 -3.5118675
OS 6.67923734 -3.54515166
OS 6.67923734 -3.5465385
OS 6.6778505 -3.54931218
OS 6.67646366 -3.5534727
OS 6.67507682 -3.55902006
OS 6.66952946 -3.5742753
OS 6.66120842 -3.59369106
OS 6.65288738 -3.6158805
OS 6.64179266 -3.63806994
OS 6.62792426 -3.66164622
OS 6.61405586 -3.68383566
OS 6.61266902 -3.68660934
OS 6.60712166 -3.69354354
OS 6.59880062 -3.70325142
OS 6.5877059 -3.71573298
OS 6.57522434 -3.72960138
OS 6.5599691 -3.74346978
OS 6.54471386 -3.75872502
OS 6.52668494 -3.77120658
OS 6.52391126 -3.77259342
OS 6.5183639 -3.77675394
OS 6.50865602 -3.7823013
OS 6.49478762 -3.7892355
OS 6.47814554 -3.79755654
OS 6.45872978 -3.80449074
OS 6.43654034 -3.81281178
OS 6.41157722 -3.81974598
OS 6.40880354 -3.81974598
OS 6.40464302 -3.82113282
OS 6.4004825 -3.82251966
OS 6.3866141 -3.8239065
OS 6.36719834 -3.82668018
OS 6.3450089 -3.82945386
OS 6.31865894 -3.83222754
OS 6.2895353 -3.83361438
OS 6.25763798 -3.83500122
OS 5.91231482 -3.83500122
OS 5.91231482 -2.87530794
OS 6.28121426 -2.87530794
OS 6.30617738 -2.87669478
OE
OB 4.4935775 -3.49661226 I
OS 4.62394046 -3.49661226
OS 4.62394046 -3.60478578
OS 4.4935775 -3.60478578
OS 4.4935775 -3.83500122
OS 4.3756961 -3.83500122
OS 4.3756961 -3.60478578
OS 3.95825726 -3.60478578
OS 3.95825726 -3.49661226
OS 4.39788554 -2.87530794
OS 4.4935775 -2.87530794
OS 4.4935775 -3.49661226
OE
OB 2.61579614 -2.8600527 I
OS 2.62550402 -2.8600527
OS 2.65185398 -2.86282638
OS 2.68097762 -2.8669869
OS 2.7114881 -2.8739211
OS 2.74477226 -2.88224214
OS 2.77528274 -2.89333686
OS 2.77666958 -2.89333686
OS 2.77944326 -2.8947237
OS 2.78360378 -2.89749738
OS 2.78915114 -2.90027106
OS 2.80301954 -2.90720526
OS 2.82104846 -2.91968682
OS 2.84185106 -2.93355522
OS 2.86265366 -2.95158414
OS 2.88206942 -2.97238674
OS 2.90009834 -2.99596302
OS 2.90009834 -2.99734986
OS 2.90148518 -2.9987367
OS 2.90425886 -3.00289722
OS 2.90703254 -3.00705774
OS 2.91396674 -3.02092614
OS 2.92228778 -3.03895506
OS 2.93199566 -3.0611445
OS 2.93892986 -3.08749446
OS 2.94586406 -3.11523126
OS 2.94863774 -3.14574174
OS 2.82659582 -3.15544962
OS 2.82659582 -3.15406278
OS 2.82659582 -3.1512891
OS 2.82520898 -3.14712858
OS 2.82382214 -3.14019438
OS 2.81966162 -3.12493914
OS 2.81411426 -3.10413654
OS 2.80579322 -3.0819471
OS 2.79331166 -3.05975766
OS 2.77805642 -3.03895506
OS 2.75864066 -3.0195393
OS 2.75586698 -3.01815246
OS 2.74893278 -3.0126051
OS 2.73506438 -3.00428406
OS 2.71703546 -2.99596302
OS 2.69345918 -2.98764198
OS 2.66572238 -2.97932094
OS 2.63105138 -2.97377358
OS 2.59221986 -2.97238674
OS 2.5728041 -2.97238674
OS 2.56448306 -2.97377358
OS 2.55338834 -2.97516042
OS 2.52842522 -2.9779341
OS 2.50068842 -2.98348146
OS 2.47295162 -2.99041566
OS 2.44660166 -3.00151038
OS 2.43550694 -3.00844458
OS 2.42441222 -3.01537878
OS 2.42163854 -3.01676562
OS 2.41609118 -3.02231298
OS 2.40777014 -3.03202086
OS 2.3994491 -3.04311558
OS 2.38974122 -3.05837082
OS 2.38142018 -3.0750129
OS 2.37587282 -3.09442866
OS 2.37309914 -3.1166181
OS 2.37309914 -3.11939178
OS 2.37309914 -3.12493914
OS 2.37448598 -3.13464702
OS 2.37725966 -3.14574174
OS 2.38142018 -3.15961014
OS 2.38835438 -3.17347854
OS 2.39667542 -3.18734694
OS 2.40915698 -3.20121534
OS 2.41054382 -3.20260218
OS 2.41747802 -3.2067627
OS 2.42302538 -3.21092322
OS 2.42857274 -3.2136969
OS 2.43689378 -3.21785742
OS 2.44660166 -3.22340478
OS 2.45908322 -3.2275653
OS 2.47295162 -3.23311266
OS 2.48820686 -3.23866002
OS 2.50623578 -3.24559422
OS 2.52565154 -3.25114158
OS 2.54784098 -3.25807578
OS 2.5728041 -3.26362314
OS 2.6005409 -3.27055734
OS 2.60192774 -3.27055734
OS 2.6074751 -3.27194418
OS 2.61579614 -3.27333102
OS 2.62550402 -3.2761047
OS 2.63798558 -3.27887838
OS 2.65324082 -3.2830389
OS 2.66849606 -3.28719942
OS 2.68513814 -3.29135994
OS 2.72119598 -3.30106782
OS 2.75586698 -3.3107757
OS 2.77250906 -3.31632306
OS 2.7877643 -3.32187042
OS 2.8016327 -3.32603094
OS 2.81272742 -3.3315783
OS 2.81411426 -3.3315783
OS 2.81688794 -3.33296514
OS 2.82104846 -3.33573882
OS 2.82659582 -3.3385125
OS 2.84185106 -3.34683354
OS 2.85987998 -3.35792826
OS 2.88068258 -3.3731835
OS 2.90148518 -3.38982558
OS 2.92090094 -3.40924134
OS 2.93754302 -3.43004394
OS 2.93892986 -3.43281762
OS 2.94447722 -3.43975182
OS 2.95002458 -3.45223338
OS 2.95834562 -3.46887546
OS 2.96527982 -3.48829122
OS 2.97221402 -3.5118675
OS 2.97637454 -3.53821746
OS 2.97776138 -3.56595426
OS 2.97776138 -3.5673411
OS 2.97776138 -3.56872794
OS 2.97776138 -3.57288846
OS 2.97776138 -3.57843582
OS 2.9749877 -3.59369106
OS 2.97221402 -3.61310682
OS 2.96666666 -3.63529626
OS 2.95973246 -3.65887254
OS 2.94863774 -3.68383566
OS 2.9333825 -3.71018562
OS 2.9333825 -3.71157246
OS 2.93199566 -3.7129593
OS 2.92506146 -3.72128034
OS 2.91535358 -3.7337619
OS 2.90148518 -3.7476303
OS 2.88345626 -3.76427238
OS 2.86126682 -3.7823013
OS 2.8363037 -3.79894338
OS 2.80718006 -3.81419862
OS 2.80579322 -3.81419862
OS 2.80301954 -3.81558546
OS 2.79885902 -3.8169723
OS 2.79331166 -3.81974598
OS 2.78499062 -3.82251966
OS 2.77528274 -3.82668018
OS 2.7530933 -3.83222754
OS 2.72674334 -3.83916174
OS 2.69484602 -3.84609594
OS 2.66017502 -3.85025646
OS 2.62273034 -3.8516433
OS 2.6005409 -3.8516433
OS 2.58944618 -3.85025646
OS 2.57696462 -3.85025646
OS 2.56309622 -3.84886962
OS 2.54645414 -3.84748278
OS 2.51178314 -3.84193542
OS 2.4757253 -3.83638806
OS 2.43966746 -3.82668018
OS 2.40499646 -3.81419862
OS 2.40360962 -3.81419862
OS 2.40083594 -3.81281178
OS 2.39667542 -3.8100381
OS 2.39112806 -3.80726442
OS 2.37448598 -3.79894338
OS 2.35507022 -3.78646182
OS 2.33288078 -3.76981974
OS 2.3093045 -3.75040398
OS 2.28711506 -3.7268277
OS 2.26631246 -3.70047774
OS 2.26631246 -3.6990909
OS 2.26353878 -3.69631722
OS 2.26215194 -3.6921567
OS 2.25799142 -3.68660934
OS 2.25521774 -3.67967514
OS 2.25105722 -3.6713541
OS 2.24134934 -3.6505515
OS 2.23164146 -3.62420154
OS 2.22332042 -3.5950779
OS 2.21777306 -3.56179374
OS 2.21499938 -3.52712274
OS 2.33426762 -3.51602802
OS 2.33426762 -3.51741486
OS 2.33426762 -3.5188017
OS 2.33565446 -3.52296222
OS 2.33565446 -3.52850958
OS 2.33842814 -3.54099114
OS 2.34258866 -3.55902006
OS 2.34813602 -3.57704898
OS 2.35368338 -3.59785158
OS 2.36339126 -3.61726734
OS 2.37309914 -3.63529626
OS 2.37448598 -3.6366831
OS 2.3786465 -3.64223046
OS 2.3855807 -3.65193834
OS 2.39667542 -3.66164622
OS 2.41054382 -3.67412778
OS 2.42579906 -3.68660934
OS 2.44660166 -3.6990909
OS 2.4687911 -3.71018562
OS 2.47017794 -3.71018562
OS 2.47156478 -3.71157246
OS 2.4757253 -3.7129593
OS 2.47988582 -3.71434614
OS 2.49375422 -3.71850666
OS 2.51178314 -3.72405402
OS 2.53397258 -3.72960138
OS 2.5589357 -3.7337619
OS 2.5866725 -3.73653558
OS 2.61718298 -3.73792242
OS 2.62966454 -3.73792242
OS 2.64353294 -3.73653558
OS 2.66017502 -3.73514874
OS 2.67959078 -3.73237506
OS 2.70178022 -3.72960138
OS 2.72396966 -3.72405402
OS 2.74477226 -3.71711982
OS 2.74754594 -3.71573298
OS 2.75448014 -3.7129593
OS 2.76418802 -3.70741194
OS 2.77666958 -3.70186458
OS 2.78915114 -3.6921567
OS 2.80301954 -3.68244882
OS 2.81688794 -3.6713541
OS 2.82798266 -3.6574857
OS 2.8293695 -3.65609886
OS 2.83214318 -3.6505515
OS 2.8363037 -3.6436173
OS 2.84185106 -3.63252258
OS 2.84739842 -3.62142786
OS 2.85155894 -3.60755946
OS 2.85433262 -3.59230422
OS 2.85571946 -3.57566214
OS 2.85571946 -3.5742753
OS 2.85571946 -3.5673411
OS 2.85433262 -3.55902006
OS 2.85294578 -3.54792534
OS 2.84878526 -3.53683062
OS 2.84462474 -3.52296222
OS 2.83769054 -3.50909382
OS 2.82798266 -3.49661226
OS 2.82659582 -3.49522542
OS 2.8224353 -3.4910649
OS 2.81688794 -3.48551754
OS 2.80718006 -3.4771965
OS 2.79608534 -3.46887546
OS 2.7808301 -3.45916758
OS 2.76280118 -3.4494597
OS 2.74199858 -3.44113866
OS 2.74061174 -3.43975182
OS 2.73367754 -3.43836498
OS 2.72258282 -3.43420446
OS 2.71564862 -3.43281762
OS 2.70594074 -3.43004394
OS 2.69623286 -3.42588342
OS 2.6837513 -3.42310974
OS 2.6698829 -3.41894922
OS 2.65324082 -3.4147887
OS 2.63659874 -3.41062818
OS 2.61718298 -3.40508082
OS 2.59499354 -3.39953346
OS 2.57141726 -3.3939861
OS 2.57003042 -3.3939861
OS 2.5658699 -3.39259926
OS 2.5589357 -3.39121242
OS 2.55061466 -3.38843874
OS 2.53951994 -3.38566506
OS 2.52703838 -3.38289138
OS 2.49930158 -3.37457034
OS 2.4687911 -3.36486246
OS 2.43689378 -3.35515458
OS 2.40915698 -3.3454467
OS 2.39667542 -3.33989934
OS 2.3855807 -3.33435198
OS 2.38419386 -3.33435198
OS 2.38280702 -3.33296514
OS 2.37448598 -3.32741778
OS 2.36200442 -3.32048358
OS 2.34813602 -3.30938886
OS 2.33149394 -3.2969073
OS 2.31485186 -3.28165206
OS 2.29820978 -3.26362314
OS 2.28434138 -3.24420738
OS 2.28295454 -3.2414337
OS 2.27879402 -3.2344995
OS 2.27324666 -3.22340478
OS 2.2676993 -3.20953638
OS 2.26215194 -3.19150746
OS 2.25660458 -3.17070486
OS 2.25244406 -3.14851542
OS 2.25105722 -3.12493914
OS 2.25105722 -3.1235523
OS 2.25105722 -3.12216546
OS 2.25105722 -3.11800494
OS 2.25105722 -3.11245758
OS 2.2538309 -3.09858918
OS 2.25660458 -3.08056026
OS 2.2607651 -3.05975766
OS 2.2676993 -3.03618138
OS 2.27740718 -3.0126051
OS 2.29127558 -2.98902882
OS 2.29127558 -2.98764198
OS 2.29266242 -2.98625514
OS 2.29959662 -2.9779341
OS 2.3093045 -2.96683938
OS 2.32178606 -2.95297098
OS 2.33842814 -2.93771574
OS 2.35923074 -2.92107366
OS 2.38419386 -2.90581842
OS 2.41193066 -2.89195002
OS 2.4133175 -2.89195002
OS 2.41609118 -2.89056318
OS 2.4202517 -2.88917634
OS 2.42579906 -2.88640266
OS 2.43273326 -2.88362898
OS 2.44244114 -2.8808553
OS 2.46324374 -2.87530794
OS 2.4895937 -2.86976058
OS 2.52010418 -2.86421322
OS 2.5520015 -2.8600527
OS 2.58805934 -2.85866586
OS 2.60608826 -2.85866586
OS 2.61579614 -2.8600527
OE
OB 3.94438886 -3.83500122 I
OS 3.8001575 -3.83500122
OS 3.68782346 -3.54376482
OS 3.28563986 -3.54376482
OS 3.18162686 -3.83500122
OS 3.04710338 -3.83500122
OS 3.41322914 -2.87530794
OS 3.55191314 -2.87530794
OS 3.94438886 -3.83500122
OE
OB 7.18959446 -3.12493914 I
OS 7.21039706 -3.12632598
OS 7.23397334 -3.12909966
OS 7.25754962 -3.13326018
OS 7.2811259 -3.13880754
OS 7.30331534 -3.14574174
OS 7.30608902 -3.14712858
OS 7.31302322 -3.14990226
OS 7.3227311 -3.15406278
OS 7.33521266 -3.15961014
OS 7.34908106 -3.16793118
OS 7.36294946 -3.17625222
OS 7.37543102 -3.18734694
OS 7.38652574 -3.19844166
OS 7.38791258 -3.1998285
OS 7.39068626 -3.20398902
OS 7.39484678 -3.21092322
OS 7.40039414 -3.21924426
OS 7.40732834 -3.23172582
OS 7.4128757 -3.24420738
OS 7.41842306 -3.25946262
OS 7.42258358 -3.27749154
OS 7.42258358 -3.27887838
OS 7.42397042 -3.2830389
OS 7.42535726 -3.29135994
OS 7.4267441 -3.30245466
OS 7.4267441 -3.3177099
OS 7.42813094 -3.33573882
OS 7.42951778 -3.3593151
OS 7.42951778 -3.38566506
OS 7.42951778 -3.54376482
OS 7.42951778 -3.54515166
OS 7.42951778 -3.55069902
OS 7.42951778 -3.55902006
OS 7.42951778 -3.57011478
OS 7.42951778 -3.58259634
OS 7.42951778 -3.59785158
OS 7.43090462 -3.63113574
OS 7.43090462 -3.66580674
OS 7.43229146 -3.70047774
OS 7.4336783 -3.71573298
OS 7.4336783 -3.72960138
OS 7.43506514 -3.74208294
OS 7.43645198 -3.75179082
OS 7.43645198 -3.75317766
OS 7.43783882 -3.75872502
OS 7.43922566 -3.76704606
OS 7.44338618 -3.77814078
OS 7.44615986 -3.79062234
OS 7.45170722 -3.80449074
OS 7.45864142 -3.81974598
OS 7.46557562 -3.83500122
OS 7.34214686 -3.83500122
OS 7.34076002 -3.83361438
OS 7.33937318 -3.82806702
OS 7.3365995 -3.82113282
OS 7.33243898 -3.8100381
OS 7.32827846 -3.79755654
OS 7.32550478 -3.7823013
OS 7.3227311 -3.76565922
OS 7.31995742 -3.7476303
OS 7.31857058 -3.7476303
OS 7.31718374 -3.75040398
OS 7.3088627 -3.75733818
OS 7.29638114 -3.76704606
OS 7.27973906 -3.77952762
OS 7.25893646 -3.79200918
OS 7.23813386 -3.80587758
OS 7.21594442 -3.81835914
OS 7.19236814 -3.82806702
OS 7.18959446 -3.82945386
OS 7.18127342 -3.8308407
OS 7.16879186 -3.83500122
OS 7.15353662 -3.83916174
OS 7.13412086 -3.84332226
OS 7.11193142 -3.84609594
OS 7.0869683 -3.84886962
OS 7.06200518 -3.85025646
OS 7.05091046 -3.85025646
OS 7.04258942 -3.84886962
OS 7.03288154 -3.84886962
OS 7.02178682 -3.84748278
OS 6.9968237 -3.84332226
OS 6.9690869 -3.83638806
OS 6.93857642 -3.82668018
OS 6.91083962 -3.81281178
OS 6.8858765 -3.79478286
OS 6.88310282 -3.79200918
OS 6.87616862 -3.78507498
OS 6.86646074 -3.77259342
OS 6.85536602 -3.75595134
OS 6.8442713 -3.73514874
OS 6.83456342 -3.71157246
OS 6.82762922 -3.68244882
OS 6.82624238 -3.66858042
OS 6.82485554 -3.65193834
OS 6.82485554 -3.64916466
OS 6.82485554 -3.6436173
OS 6.82624238 -3.63390942
OS 6.82762922 -3.62142786
OS 6.8304029 -3.60617262
OS 6.83456342 -3.59091738
OS 6.84011078 -3.5742753
OS 6.84704498 -3.55902006
OS 6.84843182 -3.55763322
OS 6.8512055 -3.55208586
OS 6.85675286 -3.54376482
OS 6.86368706 -3.53405694
OS 6.8720081 -3.52296222
OS 6.88310282 -3.5118675
OS 6.89419754 -3.50077278
OS 6.90806594 -3.4910649
OS 6.90945278 -3.48967806
OS 6.91500014 -3.48690438
OS 6.92193434 -3.48135702
OS 6.93302906 -3.47580966
OS 6.94551062 -3.4702623
OS 6.96076586 -3.4633281
OS 6.9760211 -3.45778074
OS 6.99405002 -3.45223338
OS 6.99543686 -3.45223338
OS 7.00098422 -3.45084654
OS 7.00930526 -3.44807286
OS 7.02039998 -3.44668602
OS 7.03426838 -3.44391234
OS 7.0522973 -3.44113866
OS 7.0730999 -3.43697814
OS 7.09806302 -3.43420446
OS 7.09944986 -3.43420446
OS 7.10499722 -3.43281762
OS 7.11193142 -3.43281762
OS 7.1216393 -3.43143078
OS 7.13273402 -3.43004394
OS 7.14660242 -3.42727026
OS 7.16185766 -3.42588342
OS 7.17849974 -3.42310974
OS 7.2117839 -3.41617554
OS 7.24784174 -3.40924134
OS 7.27973906 -3.4009203
OS 7.2949943 -3.39675978
OS 7.3088627 -3.39259926
OS 7.3088627 -3.39121242
OS 7.3088627 -3.38843874
OS 7.31024954 -3.3801177
OS 7.31024954 -3.37040982
OS 7.31024954 -3.36486246
OS 7.31024954 -3.36208878
OS 7.31024954 -3.36070194
OS 7.31024954 -3.3593151
OS 7.31024954 -3.35099406
OS 7.3088627 -3.33712566
OS 7.30608902 -3.32187042
OS 7.3019285 -3.30522834
OS 7.2949943 -3.28858626
OS 7.28667326 -3.27333102
OS 7.27557854 -3.26084946
OS 7.2741917 -3.25946262
OS 7.2672575 -3.25391526
OS 7.25616278 -3.2483679
OS 7.24229438 -3.24004686
OS 7.22287862 -3.23311266
OS 7.20068918 -3.22617846
OS 7.17295238 -3.22201794
OS 7.14105506 -3.2206311
OS 7.12718666 -3.2206311
OS 7.11331826 -3.22201794
OS 7.0939025 -3.22479162
OS 7.07448674 -3.2275653
OS 7.05368414 -3.23311266
OS 7.03426838 -3.24004686
OS 7.0176263 -3.24975474
OS 7.01623946 -3.25114158
OS 7.0106921 -3.2553021
OS 7.0037579 -3.2622363
OS 6.99543686 -3.27333102
OS 6.98711582 -3.28719942
OS 6.97740794 -3.30522834
OS 6.9690869 -3.32741778
OS 6.96076586 -3.3523809
OS 6.84565814 -3.33712566
OS 6.84565814 -3.33573882
OS 6.84704498 -3.33435198
OS 6.84704498 -3.33019146
OS 6.84843182 -3.3246441
OS 6.85259234 -3.31216254
OS 6.8581397 -3.29413362
OS 6.8650739 -3.2761047
OS 6.87339494 -3.25668894
OS 6.88448966 -3.23727318
OS 6.89697122 -3.21924426
OS 6.89835806 -3.21785742
OS 6.90390542 -3.21231006
OS 6.91222646 -3.20398902
OS 6.92332118 -3.1928943
OS 6.93857642 -3.18179958
OS 6.95660534 -3.17070486
OS 6.97740794 -3.1582233
OS 7.00098422 -3.14851542
OS 7.00237106 -3.14851542
OS 7.0037579 -3.14712858
OS 7.00791842 -3.14574174
OS 7.01346578 -3.1443549
OS 7.02733418 -3.14019438
OS 7.04674994 -3.13603386
OS 7.06893938 -3.13187334
OS 7.09667618 -3.12771282
OS 7.12579982 -3.12493914
OS 7.15908398 -3.1235523
OS 7.17433922 -3.1235523
OS 7.18959446 -3.12493914
OE
OB 8.17286402 -3.83500122 I
OS 8.06746418 -3.83500122
OS 8.06746418 -3.7337619
OS 8.06607734 -3.73514874
OS 8.06330366 -3.73930926
OS 8.05914314 -3.74485662
OS 8.05220894 -3.75179082
OS 8.0438879 -3.76011186
OS 8.03418002 -3.77120658
OS 8.0230853 -3.78091446
OS 8.0092169 -3.79200918
OS 7.99396166 -3.8031039
OS 7.97731958 -3.81281178
OS 7.95929066 -3.82251966
OS 7.9398749 -3.83222754
OS 7.91768546 -3.83916174
OS 7.89549602 -3.8447091
OS 7.8705329 -3.84886962
OS 7.84556978 -3.85025646
OS 7.8358619 -3.85025646
OS 7.82338034 -3.84886962
OS 7.8081251 -3.84748278
OS 7.79009618 -3.8447091
OS 7.77068042 -3.84054858
OS 7.75126466 -3.83500122
OS 7.73046206 -3.82668018
OS 7.72768838 -3.82529334
OS 7.72214102 -3.82251966
OS 7.71243314 -3.8169723
OS 7.70133842 -3.8100381
OS 7.68747002 -3.80171706
OS 7.67498846 -3.79200918
OS 7.6625069 -3.78091446
OS 7.65141218 -3.7684329
OS 7.65002534 -3.76704606
OS 7.64725166 -3.7614987
OS 7.64309114 -3.7545645
OS 7.63754378 -3.74346978
OS 7.63060958 -3.73098822
OS 7.62506222 -3.71573298
OS 7.61951486 -3.6990909
OS 7.61535434 -3.68106198
OS 7.61535434 -3.67967514
OS 7.6139675 -3.67412778
OS 7.61258066 -3.66580674
OS 7.61258066 -3.65471202
OS 7.61119382 -3.63806994
OS 7.60980698 -3.62004102
OS 7.60842014 -3.59646474
OS 7.60842014 -3.57011478
OS 7.60842014 -3.13880754
OS 7.72630154 -3.13880754
OS 7.72630154 -3.5257359
OS 7.72630154 -3.52712274
OS 7.72630154 -3.52989642
OS 7.72630154 -3.53405694
OS 7.72630154 -3.54099114
OS 7.72630154 -3.55624638
OS 7.72768838 -3.57566214
OS 7.72768838 -3.59646474
OS 7.72907522 -3.61726734
OS 7.73046206 -3.63529626
OS 7.73323574 -3.6505515
OS 7.73323574 -3.65193834
OS 7.73600942 -3.6574857
OS 7.7387831 -3.66580674
OS 7.74294362 -3.67690146
OS 7.74987782 -3.68799618
OS 7.75819886 -3.70047774
OS 7.76790674 -3.71157246
OS 7.7803883 -3.72266718
OS 7.78177514 -3.72405402
OS 7.7873225 -3.7268277
OS 7.7942567 -3.73098822
OS 7.80535142 -3.73514874
OS 7.81783298 -3.7406961
OS 7.83308822 -3.74485662
OS 7.8497303 -3.7476303
OS 7.86914606 -3.74901714
OS 7.87885394 -3.74901714
OS 7.88856182 -3.7476303
OS 7.90104338 -3.74624346
OS 7.91629862 -3.74208294
OS 7.9329407 -3.73792242
OS 7.95096962 -3.73098822
OS 7.96899854 -3.72266718
OS 7.97177222 -3.72128034
OS 7.97731958 -3.71711982
OS 7.98564062 -3.71157246
OS 7.9953485 -3.70325142
OS 8.00644322 -3.6921567
OS 8.01753794 -3.67967514
OS 8.02724582 -3.66580674
OS 8.03556686 -3.64916466
OS 8.0369537 -3.64639098
OS 8.03834054 -3.64084362
OS 8.04111422 -3.6297489
OS 8.04527474 -3.61449366
OS 8.04943526 -3.5950779
OS 8.05220894 -3.57150162
OS 8.05359578 -3.54376482
OS 8.05498262 -3.5118675
OS 8.05498262 -3.13880754
OS 8.17286402 -3.13880754
OS 8.17286402 -3.83500122
OE
OB 13.83671858 -3.22062856 H
OS 13.82978438 -3.22062856
OS 13.82423702 -3.2220154
OS 13.80898178 -3.22340224
OS 13.79095286 -3.2289496
OS 13.77015026 -3.2358838
OS 13.74796082 -3.24836536
OS 13.72577138 -3.2636206
OS 13.71467666 -3.27471532
OS 13.70496878 -3.28581004
OS 13.70496878 -3.28719688
OS 13.7021951 -3.28858372
OS 13.70080826 -3.29274424
OS 13.69664774 -3.2982916
OS 13.69248722 -3.3052258
OS 13.6883267 -3.31354684
OS 13.68416618 -3.32325472
OS 13.67861882 -3.33434944
OS 13.67307146 -3.34821784
OS 13.66891094 -3.36347308
OS 13.66475042 -3.38011516
OS 13.6605899 -3.39814408
OS 13.65781622 -3.41755984
OS 13.65504254 -3.43974928
OS 13.65226886 -3.46332556
OS 13.65226886 -3.48828868
OS 13.65226886 -3.48967552
OS 13.65226886 -3.49383604
OS 13.65226886 -3.50077024
OS 13.6536557 -3.51047812
OS 13.6536557 -3.52157284
OS 13.65504254 -3.5340544
OS 13.65920306 -3.56317804
OS 13.66613726 -3.59507536
OS 13.67584514 -3.62835952
OS 13.68971354 -3.66025684
OS 13.69803458 -3.67412524
OS 13.70774246 -3.68799364
OS 13.7091293 -3.68799364
OS 13.71051614 -3.69076732
OS 13.71745034 -3.69770152
OS 13.7299319 -3.70879624
OS 13.74518714 -3.71989096
OS 13.7646029 -3.73237252
OS 13.78817918 -3.74346724
OS 13.8131423 -3.75040144
OS 13.8270107 -3.75178828
OS 13.8408791 -3.75317512
OS 13.8478133 -3.75317512
OS 13.85336066 -3.75178828
OS 13.8686159 -3.75040144
OS 13.88664482 -3.74485408
OS 13.90744742 -3.73791988
OS 13.92963686 -3.72682516
OS 13.9518263 -3.71156992
OS 13.96292102 -3.70186204
OS 13.9726289 -3.69076732
OS 13.9726289 -3.68938048
OS 13.97540258 -3.68799364
OS 13.97817626 -3.68383312
OS 13.98094994 -3.67828576
OS 13.98511046 -3.67135156
OS 13.99065782 -3.66441736
OS 13.99481834 -3.65332264
OS 14.0003657 -3.64222792
OS 14.00591306 -3.62974636
OS 14.01007358 -3.61587796
OS 14.01562094 -3.59923588
OS 14.01978146 -3.5825938
OS 14.02255514 -3.56317804
OS 14.02532882 -3.54376228
OS 14.0281025 -3.52157284
OS 14.0281025 -3.49799656
OS 14.0281025 -3.49660972
OS 14.0281025 -3.49106236
OS 14.0281025 -3.48412816
OS 14.02671566 -3.47442028
OS 14.02671566 -3.46332556
OS 14.02532882 -3.44945716
OS 14.02394198 -3.43420192
OS 14.0211683 -3.41755984
OS 14.0142341 -3.38427568
OS 14.00452622 -3.34960468
OS 13.99065782 -3.31632052
OS 13.98233678 -3.30245212
OS 13.9726289 -3.28858372
OS 13.9726289 -3.28719688
OS 13.96985522 -3.28581004
OS 13.96292102 -3.277489
OS 13.95043946 -3.26639428
OS 13.93518422 -3.25391272
OS 13.91576846 -3.24143116
OS 13.89219218 -3.23172328
OS 13.86584222 -3.22340224
OS 13.85197382 -3.2220154
OS 13.83671858 -3.22062856
OE
OB 10.50830258 -3.22062856 H
OS 10.49998154 -3.22062856
OS 10.49443418 -3.2220154
OS 10.47917894 -3.22340224
OS 10.46115002 -3.22756276
OS 10.43896058 -3.23449696
OS 10.4153843 -3.24420484
OS 10.39319486 -3.25807324
OS 10.37100542 -3.27610216
OS 10.36823174 -3.27887584
OS 10.36268438 -3.28581004
OS 10.3529765 -3.2982916
OS 10.34326862 -3.31493368
OS 10.3321739 -3.33434944
OS 10.32246602 -3.35931256
OS 10.31414498 -3.3884362
OS 10.30998446 -3.42033352
OS 10.6996865 -3.42033352
OS 10.6996865 -3.41894668
OS 10.6996865 -3.416173
OS 10.69829966 -3.41201248
OS 10.69829966 -3.40646512
OS 10.69552598 -3.38982304
OS 10.69136546 -3.37179412
OS 10.68443126 -3.34960468
OS 10.67749706 -3.32880208
OS 10.66640234 -3.30799948
OS 10.65392078 -3.28997056
OS 10.65392078 -3.28858372
OS 10.6511471 -3.28719688
OS 10.6442129 -3.27887584
OS 10.63173134 -3.26778112
OS 10.61508926 -3.25529956
OS 10.59428666 -3.242818
OS 10.56932354 -3.23172328
OS 10.5401999 -3.22340224
OS 10.52494466 -3.2220154
OS 10.50830258 -3.22062856
OE
OB 8.63606858 -3.2206311 H
OS 8.61387914 -3.2206311
OS 8.60833178 -3.22201794
OS 8.59307654 -3.22340478
OS 8.57504762 -3.22895214
OS 8.55285818 -3.23588634
OS 8.53066874 -3.2483679
OS 8.5084793 -3.26362314
OS 8.49738458 -3.27471786
OS 8.48628986 -3.28581258
OS 8.48628986 -3.28719942
OS 8.48351618 -3.28858626
OS 8.4807425 -3.29274678
OS 8.47796882 -3.29829414
OS 8.4738083 -3.3038415
OS 8.46964778 -3.31216254
OS 8.46410042 -3.32187042
OS 8.4599399 -3.33296514
OS 8.45439254 -3.3454467
OS 8.44884518 -3.36070194
OS 8.44468466 -3.37595718
OS 8.44052414 -3.39259926
OS 8.43775046 -3.41201502
OS 8.43497678 -3.43143078
OS 8.4322031 -3.45223338
OS 8.4322031 -3.47580966
OS 8.4322031 -3.4771965
OS 8.4322031 -3.48135702
OS 8.4322031 -3.48829122
OS 8.43358994 -3.4979991
OS 8.43358994 -3.50909382
OS 8.43497678 -3.52296222
OS 8.4391373 -3.55208586
OS 8.4460715 -3.58537002
OS 8.45439254 -3.61726734
OS 8.46826094 -3.64916466
OS 8.47658198 -3.66303306
OS 8.48628986 -3.67551462
OS 8.48906354 -3.6782883
OS 8.49599774 -3.6852225
OS 8.50709246 -3.69493038
OS 8.52373454 -3.7060251
OS 8.5431503 -3.71850666
OS 8.56672658 -3.72821454
OS 8.59307654 -3.73514874
OS 8.60694494 -3.73653558
OS 8.62220018 -3.73792242
OS 8.63052122 -3.73792242
OS 8.63606858 -3.73653558
OS 8.65132382 -3.73514874
OS 8.67073958 -3.72960138
OS 8.69154218 -3.72266718
OS 8.71511846 -3.71157246
OS 8.7373079 -3.69631722
OS 8.74840262 -3.68660934
OS 8.75949734 -3.67551462
OS 8.75949734 -3.67412778
OS 8.76227102 -3.67274094
OS 8.7650447 -3.66858042
OS 8.76781838 -3.66303306
OS 8.7719789 -3.6574857
OS 8.77752626 -3.64916466
OS 8.78168678 -3.63945678
OS 8.78723414 -3.62697522
OS 8.7927815 -3.61449366
OS 8.79694202 -3.60062526
OS 8.80248938 -3.58398318
OS 8.8066499 -3.56595426
OS 8.80942358 -3.54792534
OS 8.81219726 -3.52712274
OS 8.81497094 -3.50354646
OS 8.81497094 -3.47997018
OS 8.81497094 -3.47858334
OS 8.81497094 -3.47442282
OS 8.81497094 -3.46748862
OS 8.8135841 -3.45916758
OS 8.8135841 -3.44807286
OS 8.81219726 -3.4355913
OS 8.80803674 -3.4078545
OS 8.80110254 -3.37595718
OS 8.79139466 -3.34405986
OS 8.77752626 -3.31216254
OS 8.76781838 -3.29829414
OS 8.7581105 -3.28581258
OS 8.7581105 -3.28442574
OS 8.75533682 -3.2830389
OS 8.74840262 -3.2761047
OS 8.73592106 -3.26500998
OS 8.71927898 -3.25252842
OS 8.69986322 -3.2414337
OS 8.67628694 -3.23033898
OS 8.64993698 -3.22340478
OS 8.63606858 -3.2206311
OE
OB 3.47979746 -2.97516042 H
OS 3.47979746 -2.97654726
OS 3.47841062 -2.97932094
OS 3.47841062 -2.9848683
OS 3.47563694 -2.99041566
OS 3.4742501 -3.00012354
OS 3.47147642 -3.00983142
OS 3.46592906 -3.0334077
OS 3.45899486 -3.0611445
OS 3.44928698 -3.09165498
OS 3.4395791 -3.12493914
OS 3.42709754 -3.15961014
OS 3.32308454 -3.43975182
OS 3.6476051 -3.43975182
OS 3.54775262 -3.17625222
OS 3.54775262 -3.17486538
OS 3.54636578 -3.17070486
OS 3.5435921 -3.16377066
OS 3.54081842 -3.15544962
OS 3.5366579 -3.14574174
OS 3.53249738 -3.13326018
OS 3.52833686 -3.11939178
OS 3.5227895 -3.10552338
OS 3.51169478 -3.07362606
OS 3.50060006 -3.0403419
OS 3.48950534 -3.00705774
OS 3.47979746 -2.97516042
OE
OB 12.8284859 -3.485515 H
OS 12.82709906 -3.485515
OS 12.82571222 -3.48690184
OS 12.8215517 -3.48828868
OS 12.81600434 -3.48967552
OS 12.80907014 -3.4924492
OS 12.8007491 -3.49522288
OS 12.79104122 -3.49799656
OS 12.7799465 -3.50077024
OS 12.76746494 -3.50493076
OS 12.7522097 -3.50770444
OS 12.73695446 -3.51186496
OS 12.71892554 -3.51602548
OS 12.69950978 -3.520186
OS 12.68009402 -3.52434652
OS 12.65790458 -3.5271202
OS 12.6343283 -3.53128072
OS 12.63155462 -3.53128072
OS 12.62323358 -3.53266756
OS 12.60936518 -3.53544124
OS 12.59410994 -3.53821492
OS 12.57746786 -3.5409886
OS 12.56082578 -3.54514912
OS 12.54557054 -3.54930964
OS 12.53170214 -3.554857
OS 12.5303153 -3.554857
OS 12.52615478 -3.55763068
OS 12.52060742 -3.56040436
OS 12.51506006 -3.56456488
OS 12.49841798 -3.5756596
OS 12.48454958 -3.59230168
OS 12.48454958 -3.59368852
OS 12.4817759 -3.5964622
OS 12.48038906 -3.60200956
OS 12.47761538 -3.60894376
OS 12.4748417 -3.6172648
OS 12.47206802 -3.62558584
OS 12.47068118 -3.63668056
OS 12.46929434 -3.64777528
OS 12.46929434 -3.64916212
OS 12.46929434 -3.65609632
OS 12.47068118 -3.66441736
OS 12.47345486 -3.67551208
OS 12.47761538 -3.68799364
OS 12.48454958 -3.7004752
OS 12.49287062 -3.7143436
OS 12.50396534 -3.72682516
OS 12.50535218 -3.728212
OS 12.51089954 -3.73098568
OS 12.51922058 -3.73653304
OS 12.5303153 -3.7420804
OS 12.54557054 -3.74762776
OS 12.56359946 -3.75317512
OS 12.58440206 -3.7559488
OS 12.60936518 -3.75733564
OS 12.6204599 -3.75733564
OS 12.6343283 -3.7559488
OS 12.64958354 -3.75317512
OS 12.6689993 -3.75040144
OS 12.68841506 -3.74485408
OS 12.70921766 -3.73791988
OS 12.73002026 -3.728212
OS 12.73279394 -3.72682516
OS 12.7383413 -3.72266464
OS 12.74804918 -3.71573044
OS 12.7591439 -3.70602256
OS 12.77162546 -3.69492784
OS 12.78549386 -3.68105944
OS 12.79658858 -3.66441736
OS 12.8076833 -3.64638844
OS 12.80907014 -3.6450016
OS 12.81045698 -3.63945424
OS 12.81323066 -3.62974636
OS 12.81739118 -3.6172648
OS 12.8215517 -3.60062272
OS 12.82432538 -3.58120696
OS 12.82571222 -3.55763068
OS 12.82709906 -3.52989388
OS 12.8284859 -3.485515
OE
OB 7.31024954 -3.48551754 H
OS 7.3088627 -3.48551754
OS 7.30747586 -3.48690438
OS 7.30331534 -3.48829122
OS 7.29776798 -3.48967806
OS 7.29083378 -3.49245174
OS 7.28251274 -3.49522542
OS 7.27280486 -3.4979991
OS 7.26171014 -3.50077278
OS 7.24922858 -3.5049333
OS 7.23397334 -3.50770698
OS 7.2187181 -3.5118675
OS 7.20068918 -3.51602802
OS 7.18127342 -3.52018854
OS 7.16185766 -3.52434906
OS 7.13966822 -3.52712274
OS 7.11609194 -3.53128326
OS 7.11331826 -3.53128326
OS 7.10499722 -3.5326701
OS 7.09112882 -3.53544378
OS 7.07587358 -3.53821746
OS 7.0592315 -3.54099114
OS 7.04258942 -3.54515166
OS 7.02733418 -3.54931218
OS 7.01346578 -3.55485954
OS 7.01207894 -3.55485954
OS 7.00791842 -3.55763322
OS 7.00237106 -3.5604069
OS 6.9968237 -3.56456742
OS 6.98018162 -3.57566214
OS 6.96631322 -3.59230422
OS 6.96631322 -3.59369106
OS 6.96353954 -3.59646474
OS 6.9621527 -3.6020121
OS 6.95937902 -3.6089463
OS 6.95660534 -3.61726734
OS 6.95383166 -3.62558838
OS 6.95244482 -3.6366831
OS 6.95105798 -3.64777782
OS 6.95105798 -3.64916466
OS 6.95105798 -3.65609886
OS 6.95244482 -3.6644199
OS 6.9552185 -3.67551462
OS 6.95937902 -3.68799618
OS 6.96631322 -3.70047774
OS 6.97463426 -3.71434614
OS 6.98572898 -3.7268277
OS 6.98711582 -3.72821454
OS 6.99266318 -3.73098822
OS 7.00098422 -3.73653558
OS 7.01207894 -3.74208294
OS 7.02733418 -3.7476303
OS 7.0453631 -3.75317766
OS 7.0661657 -3.75595134
OS 7.09112882 -3.75733818
OS 7.10222354 -3.75733818
OS 7.11609194 -3.75595134
OS 7.13134718 -3.75317766
OS 7.15076294 -3.75040398
OS 7.1701787 -3.74485662
OS 7.1909813 -3.73792242
OS 7.2117839 -3.72821454
OS 7.21455758 -3.7268277
OS 7.22010494 -3.72266718
OS 7.22981282 -3.71573298
OS 7.24090754 -3.7060251
OS 7.2533891 -3.69493038
OS 7.2672575 -3.68106198
OS 7.27835222 -3.6644199
OS 7.28944694 -3.64639098
OS 7.29083378 -3.64500414
OS 7.29222062 -3.63945678
OS 7.2949943 -3.6297489
OS 7.29915482 -3.61726734
OS 7.30331534 -3.60062526
OS 7.30608902 -3.5812095
OS 7.30747586 -3.55763322
OS 7.3088627 -3.52989642
OS 7.31024954 -3.48551754
OE
OB 4.3756961 -3.06669186 H
OS 4.07336498 -3.49661226
OS 4.3756961 -3.49661226
OS 4.3756961 -3.06669186
OE
OB 6.2617985 -2.98902882 H
OS 6.0399041 -2.98902882
OS 6.0399041 -3.72128034
OS 6.26734586 -3.72128034
OS 6.27705374 -3.7198935
OS 6.29785634 -3.71850666
OS 6.32143262 -3.71711982
OS 6.34639574 -3.71434614
OS 6.37135886 -3.71018562
OS 6.39216146 -3.70463826
OS 6.39493514 -3.70325142
OS 6.40186934 -3.70186458
OS 6.41157722 -3.69770406
OS 6.42405878 -3.6921567
OS 6.43792718 -3.68383566
OS 6.45179558 -3.67551462
OS 6.46566398 -3.66580674
OS 6.47953238 -3.65471202
OS 6.48091922 -3.65193834
OS 6.48646658 -3.64639098
OS 6.49478762 -3.6366831
OS 6.5044955 -3.6228147
OS 6.51559022 -3.60478578
OS 6.52807178 -3.58398318
OS 6.5391665 -3.5604069
OS 6.54887438 -3.53405694
OS 6.54887438 -3.5326701
OS 6.55026122 -3.52989642
OS 6.55164806 -3.5257359
OS 6.5530349 -3.52018854
OS 6.55442174 -3.51325434
OS 6.55719542 -3.50354646
OS 6.5599691 -3.49383858
OS 6.56274278 -3.48274386
OS 6.5669033 -3.45500706
OS 6.57106382 -3.42310974
OS 6.5738375 -3.3870519
OS 6.57522434 -3.34822038
OS 6.57522434 -3.34683354
OS 6.57522434 -3.34128618
OS 6.57522434 -3.33435198
OS 6.5738375 -3.32325726
OS 6.5738375 -3.3107757
OS 6.57245066 -3.2969073
OS 6.57106382 -3.28026522
OS 6.56967698 -3.26362314
OS 6.56274278 -3.22617846
OS 6.55442174 -3.18734694
OS 6.54194018 -3.1512891
OS 6.53361914 -3.13326018
OS 6.5252981 -3.11800494
OS 6.5252981 -3.1166181
OS 6.52252442 -3.11384442
OS 6.51975074 -3.1096839
OS 6.51697706 -3.10413654
OS 6.50588234 -3.09026814
OS 6.49201394 -3.07362606
OS 6.47398502 -3.05559714
OS 6.45318242 -3.03756822
OS 6.42960614 -3.02231298
OS 6.40464302 -3.00983142
OS 6.40186934 -3.00844458
OS 6.39493514 -3.00705774
OS 6.38245358 -3.00289722
OS 6.36442466 -2.9987367
OS 6.34223522 -2.99596302
OS 6.31449842 -2.9918025
OS 6.29785634 -2.99041566
OS 6.27982742 -2.99041566
OS 6.2617985 -2.98902882
OE
SE
S P 0
OB 12.70078232 0.7551039 I
OS 12.70078232 0.75371706
OS 12.70078232 0.74955654
OS 12.70078232 0.74400918
OS 12.70078232 0.73568814
OS 12.69939548 0.72459342
OS 12.69939548 0.7134987
OS 12.6966218 0.68714874
OS 12.69384812 0.65663826
OS 12.68830076 0.62474094
OS 12.67997972 0.5956173
OS 12.67027184 0.5678805
OS 12.67027184 0.56649366
OS 12.668885 0.56510682
OS 12.66472448 0.55678578
OS 12.65779028 0.54569106
OS 12.6480824 0.53043582
OS 12.634214 0.51518058
OS 12.61895876 0.4985385
OS 12.599543 0.48189642
OS 12.57735356 0.46802802
OS 12.57457988 0.46664118
OS 12.56625884 0.46248066
OS 12.55377728 0.4569333
OS 12.53574836 0.45138594
OS 12.51355892 0.44445174
OS 12.4885958 0.43890438
OS 12.460859 0.43474386
OS 12.43034852 0.43335702
OS 12.41786696 0.43335702
OS 12.40954592 0.43474386
OS 12.3984512 0.4361307
OS 12.38735648 0.43751754
OS 12.35823284 0.4430649
OS 12.32772236 0.45138594
OS 12.29582504 0.4638675
OS 12.27918296 0.47218854
OS 12.26392772 0.48189642
OS 12.25005932 0.49299114
OS 12.23619092 0.5054727
OS 12.23480408 0.50685954
OS 12.23341724 0.50824638
OS 12.23064356 0.51379374
OS 12.22648304 0.5193411
OS 12.22093568 0.5262753
OS 12.21538832 0.53598318
OS 12.20984096 0.5470779
OS 12.20290676 0.55955946
OS 12.1973594 0.57342786
OS 12.19181204 0.59006994
OS 12.18626468 0.60671202
OS 12.18071732 0.62612778
OS 12.17794364 0.64693038
OS 12.17378312 0.67050666
OS 12.17239628 0.69408294
OS 12.17239628 0.7204329
OS 12.287504 0.73707498
OS 12.287504 0.73568814
OS 12.287504 0.73291446
OS 12.287504 0.7273671
OS 12.28889084 0.71904606
OS 12.29027768 0.71072502
OS 12.29027768 0.70101714
OS 12.2944382 0.67744086
OS 12.29859872 0.65247774
OS 12.30691976 0.62751462
OS 12.3152408 0.60532518
OS 12.32078816 0.5956173
OS 12.32772236 0.58729626
OS 12.3291092 0.58590942
OS 12.33465656 0.5817489
OS 12.3429776 0.5748147
OS 12.35407232 0.5678805
OS 12.36932756 0.55955946
OS 12.38596964 0.5540121
OS 12.40677224 0.54846474
OS 12.42896168 0.5470779
OS 12.43728272 0.5470779
OS 12.44560376 0.54846474
OS 12.45808532 0.54985158
OS 12.47056688 0.55262526
OS 12.48443528 0.55539894
OS 12.49830368 0.5609463
OS 12.51217208 0.5678805
OS 12.51355892 0.56926734
OS 12.51771944 0.57204102
OS 12.5232668 0.57758838
OS 12.53158784 0.58313574
OS 12.53852204 0.59284362
OS 12.54684308 0.6025515
OS 12.55377728 0.61364622
OS 12.55932464 0.62751462
OS 12.55932464 0.62890146
OS 12.56209832 0.63444882
OS 12.56348516 0.6441567
OS 12.56625884 0.65663826
OS 12.56903252 0.67328034
OS 12.57041936 0.69408294
OS 12.57319304 0.71904606
OS 12.57319304 0.7481697
OS 12.57319304 1.40969238
OS 12.70078232 1.40969238
OS 12.70078232 0.7551039
OE
OB 11.61349976 1.14619278 I
OS 11.732768 1.14619278
OS 11.732768 1.05466134
OS 11.61349976 1.05466134
OS 11.61349976 0.64554354
OS 11.61349976 0.64276986
OS 11.61349976 0.6372225
OS 11.61349976 0.62890146
OS 11.6148866 0.61919358
OS 11.61627344 0.59700414
OS 11.61766028 0.58729626
OS 11.61904712 0.58036206
OS 11.62043396 0.57758838
OS 11.62459448 0.57204102
OS 11.63014184 0.56510682
OS 11.63984972 0.55817262
OS 11.6426234 0.55678578
OS 11.6495576 0.5540121
OS 11.66203916 0.55123842
OS 11.68006808 0.54985158
OS 11.69393648 0.54985158
OS 11.70087068 0.55123842
OS 11.71057856 0.55123842
OS 11.72167328 0.55262526
OS 11.732768 0.5540121
OS 11.74802324 0.4499991
OS 11.74524956 0.4499991
OS 11.7397022 0.44861226
OS 11.72999432 0.44722542
OS 11.71751276 0.44583858
OS 11.70364436 0.4430649
OS 11.68838912 0.44167806
OS 11.65787864 0.44029122
OS 11.64678392 0.44029122
OS 11.6356892 0.44167806
OS 11.6218208 0.4430649
OS 11.60517872 0.44445174
OS 11.58853664 0.44861226
OS 11.5732814 0.45277278
OS 11.55802616 0.45970698
OS 11.55663932 0.46109382
OS 11.5524788 0.4638675
OS 11.54693144 0.46802802
OS 11.5386104 0.47496222
OS 11.5316762 0.48189642
OS 11.52335516 0.4916043
OS 11.51503412 0.50131218
OS 11.50948676 0.51379374
OS 11.50948676 0.51518058
OS 11.50671308 0.52072794
OS 11.50532624 0.53043582
OS 11.50255256 0.54430422
OS 11.49977888 0.56233314
OS 11.49839204 0.57342786
OS 11.49839204 0.58590942
OS 11.4970052 0.60116466
OS 11.49561836 0.6164199
OS 11.49561836 0.63306198
OS 11.49561836 0.65247774
OS 11.49561836 1.05466134
OS 11.40824744 1.05466134
OS 11.40824744 1.14619278
OS 11.49561836 1.14619278
OS 11.49561836 1.31816094
OS 11.61349976 1.38888978
OS 11.61349976 1.14619278
OE
OB 10.95475076 1.42494762 I
OS 10.96445864 1.42494762
OS 10.9908086 1.42217394
OS 11.01993224 1.41801342
OS 11.05044272 1.41107922
OS 11.08372688 1.40275818
OS 11.11423736 1.39166346
OS 11.1156242 1.39166346
OS 11.11839788 1.39027662
OS 11.1225584 1.38750294
OS 11.12810576 1.38472926
OS 11.14197416 1.37779506
OS 11.16000308 1.3653135
OS 11.18080568 1.3514451
OS 11.20160828 1.33341618
OS 11.22102404 1.31261358
OS 11.23905296 1.2890373
OS 11.23905296 1.28765046
OS 11.2404398 1.28626362
OS 11.24321348 1.2821031
OS 11.24598716 1.27794258
OS 11.25292136 1.26407418
OS 11.2612424 1.24604526
OS 11.27095028 1.22385582
OS 11.27788448 1.19750586
OS 11.28481868 1.16976906
OS 11.28759236 1.13925858
OS 11.16555044 1.1295507
OS 11.16555044 1.13093754
OS 11.16555044 1.13371122
OS 11.1641636 1.13787174
OS 11.16277676 1.14480594
OS 11.15861624 1.16006118
OS 11.15306888 1.18086378
OS 11.14474784 1.20305322
OS 11.13226628 1.22524266
OS 11.11701104 1.24604526
OS 11.09759528 1.26546102
OS 11.0948216 1.26684786
OS 11.0878874 1.27239522
OS 11.074019 1.28071626
OS 11.05599008 1.2890373
OS 11.0324138 1.29735834
OS 11.004677 1.30567938
OS 10.970006 1.31122674
OS 10.93117448 1.31261358
OS 10.91175872 1.31261358
OS 10.90343768 1.31122674
OS 10.89234296 1.3098399
OS 10.86737984 1.30706622
OS 10.83964304 1.30151886
OS 10.81190624 1.29458466
OS 10.78555628 1.28348994
OS 10.77446156 1.27655574
OS 10.76336684 1.26962154
OS 10.76059316 1.2682347
OS 10.7550458 1.26268734
OS 10.74672476 1.25297946
OS 10.73840372 1.24188474
OS 10.72869584 1.2266295
OS 10.7203748 1.20998742
OS 10.71482744 1.19057166
OS 10.71205376 1.16838222
OS 10.71205376 1.16560854
OS 10.71205376 1.16006118
OS 10.7134406 1.1503533
OS 10.71621428 1.13925858
OS 10.7203748 1.12539018
OS 10.727309 1.11152178
OS 10.73563004 1.09765338
OS 10.7481116 1.08378498
OS 10.74949844 1.08239814
OS 10.75643264 1.07823762
OS 10.76198 1.0740771
OS 10.76752736 1.07130342
OS 10.7758484 1.0671429
OS 10.78555628 1.06159554
OS 10.79803784 1.05743502
OS 10.81190624 1.05188766
OS 10.82716148 1.0463403
OS 10.8451904 1.0394061
OS 10.86460616 1.03385874
OS 10.8867956 1.02692454
OS 10.91175872 1.02137718
OS 10.93949552 1.01444298
OS 10.94088236 1.01444298
OS 10.94642972 1.01305614
OS 10.95475076 1.0116693
OS 10.96445864 1.00889562
OS 10.9769402 1.00612194
OS 10.99219544 1.00196142
OS 11.00745068 0.9978009
OS 11.02409276 0.99364038
OS 11.0601506 0.9839325
OS 11.0948216 0.97422462
OS 11.11146368 0.96867726
OS 11.12671892 0.9631299
OS 11.14058732 0.95896938
OS 11.15168204 0.95342202
OS 11.15306888 0.95342202
OS 11.15584256 0.95203518
OS 11.16000308 0.9492615
OS 11.16555044 0.94648782
OS 11.18080568 0.93816678
OS 11.1988346 0.92707206
OS 11.2196372 0.91181682
OS 11.2404398 0.89517474
OS 11.25985556 0.87575898
OS 11.27649764 0.85495638
OS 11.27788448 0.8521827
OS 11.28343184 0.8452485
OS 11.2889792 0.83276694
OS 11.29730024 0.81612486
OS 11.30423444 0.7967091
OS 11.31116864 0.77313282
OS 11.31532916 0.74678286
OS 11.316716 0.71904606
OS 11.316716 0.71765922
OS 11.316716 0.71627238
OS 11.316716 0.71211186
OS 11.316716 0.7065645
OS 11.31394232 0.69130926
OS 11.31116864 0.6718935
OS 11.30562128 0.64970406
OS 11.29868708 0.62612778
OS 11.28759236 0.60116466
OS 11.27233712 0.5748147
OS 11.27233712 0.57342786
OS 11.27095028 0.57204102
OS 11.26401608 0.56371998
OS 11.2543082 0.55123842
OS 11.2404398 0.53737002
OS 11.22241088 0.52072794
OS 11.20022144 0.50269902
OS 11.17525832 0.48605694
OS 11.14613468 0.4708017
OS 11.14474784 0.4708017
OS 11.14197416 0.46941486
OS 11.13781364 0.46802802
OS 11.13226628 0.46525434
OS 11.12394524 0.46248066
OS 11.11423736 0.45832014
OS 11.09204792 0.45277278
OS 11.06569796 0.44583858
OS 11.03380064 0.43890438
OS 10.99912964 0.43474386
OS 10.96168496 0.43335702
OS 10.93949552 0.43335702
OS 10.9284008 0.43474386
OS 10.91591924 0.43474386
OS 10.90205084 0.4361307
OS 10.88540876 0.43751754
OS 10.85073776 0.4430649
OS 10.81467992 0.44861226
OS 10.77862208 0.45832014
OS 10.74395108 0.4708017
OS 10.74256424 0.4708017
OS 10.73979056 0.47218854
OS 10.73563004 0.47496222
OS 10.73008268 0.4777359
OS 10.7134406 0.48605694
OS 10.69402484 0.4985385
OS 10.6718354 0.51518058
OS 10.64825912 0.53459634
OS 10.62606968 0.55817262
OS 10.60526708 0.58452258
OS 10.60526708 0.58590942
OS 10.6024934 0.5886831
OS 10.60110656 0.59284362
OS 10.59694604 0.59839098
OS 10.59417236 0.60532518
OS 10.59001184 0.61364622
OS 10.58030396 0.63444882
OS 10.57059608 0.66079878
OS 10.56227504 0.68992242
OS 10.55672768 0.72320658
OS 10.553954 0.75787758
OS 10.67322224 0.7689723
OS 10.67322224 0.76758546
OS 10.67322224 0.76619862
OS 10.67460908 0.7620381
OS 10.67460908 0.75649074
OS 10.67738276 0.74400918
OS 10.68154328 0.72598026
OS 10.68709064 0.70795134
OS 10.692638 0.68714874
OS 10.70234588 0.66773298
OS 10.71205376 0.64970406
OS 10.7134406 0.64831722
OS 10.71760112 0.64276986
OS 10.72453532 0.63306198
OS 10.73563004 0.6233541
OS 10.74949844 0.61087254
OS 10.76475368 0.59839098
OS 10.78555628 0.58590942
OS 10.80774572 0.5748147
OS 10.80913256 0.5748147
OS 10.8105194 0.57342786
OS 10.81467992 0.57204102
OS 10.81884044 0.57065418
OS 10.83270884 0.56649366
OS 10.85073776 0.5609463
OS 10.8729272 0.55539894
OS 10.89789032 0.55123842
OS 10.92562712 0.54846474
OS 10.9561376 0.5470779
OS 10.96861916 0.5470779
OS 10.98248756 0.54846474
OS 10.99912964 0.54985158
OS 11.0185454 0.55262526
OS 11.04073484 0.55539894
OS 11.06292428 0.5609463
OS 11.08372688 0.5678805
OS 11.08650056 0.56926734
OS 11.09343476 0.57204102
OS 11.10314264 0.57758838
OS 11.1156242 0.58313574
OS 11.12810576 0.59284362
OS 11.14197416 0.6025515
OS 11.15584256 0.61364622
OS 11.16693728 0.62751462
OS 11.16832412 0.62890146
OS 11.1710978 0.63444882
OS 11.17525832 0.64138302
OS 11.18080568 0.65247774
OS 11.18635304 0.66357246
OS 11.19051356 0.67744086
OS 11.19328724 0.6926961
OS 11.19467408 0.70933818
OS 11.19467408 0.71072502
OS 11.19467408 0.71765922
OS 11.19328724 0.72598026
OS 11.1919004 0.73707498
OS 11.18773988 0.7481697
OS 11.18357936 0.7620381
OS 11.17664516 0.7759065
OS 11.16693728 0.78838806
OS 11.16555044 0.7897749
OS 11.16138992 0.79393542
OS 11.15584256 0.79948278
OS 11.14613468 0.80780382
OS 11.13503996 0.81612486
OS 11.11978472 0.82583274
OS 11.1017558 0.83554062
OS 11.0809532 0.84386166
OS 11.07956636 0.8452485
OS 11.07263216 0.84663534
OS 11.06153744 0.85079586
OS 11.05460324 0.8521827
OS 11.04489536 0.85495638
OS 11.03518748 0.8591169
OS 11.02270592 0.86189058
OS 11.00883752 0.8660511
OS 10.99219544 0.87021162
OS 10.97555336 0.87437214
OS 10.9561376 0.8799195
OS 10.93394816 0.88546686
OS 10.91037188 0.89101422
OS 10.90898504 0.89101422
OS 10.90482452 0.89240106
OS 10.89789032 0.8937879
OS 10.88956928 0.89656158
OS 10.87847456 0.89933526
OS 10.865993 0.90210894
OS 10.8382562 0.91042998
OS 10.80774572 0.92013786
OS 10.7758484 0.92984574
OS 10.7481116 0.93955362
OS 10.73563004 0.94510098
OS 10.72453532 0.95064834
OS 10.72314848 0.95064834
OS 10.72176164 0.95203518
OS 10.7134406 0.95758254
OS 10.70095904 0.96451674
OS 10.68709064 0.97561146
OS 10.67044856 0.98809302
OS 10.65380648 1.00334826
OS 10.6371644 1.02137718
OS 10.623296 1.04079294
OS 10.62190916 1.04356662
OS 10.61774864 1.05050082
OS 10.61220128 1.06159554
OS 10.60665392 1.07546394
OS 10.60110656 1.09349286
OS 10.5955592 1.11429546
OS 10.59139868 1.1364849
OS 10.59001184 1.16006118
OS 10.59001184 1.16144802
OS 10.59001184 1.16283486
OS 10.59001184 1.16699538
OS 10.59001184 1.17254274
OS 10.59278552 1.18641114
OS 10.5955592 1.20444006
OS 10.59971972 1.22524266
OS 10.60665392 1.24881894
OS 10.6163618 1.27239522
OS 10.6302302 1.2959715
OS 10.6302302 1.29735834
OS 10.63161704 1.29874518
OS 10.63855124 1.30706622
OS 10.64825912 1.31816094
OS 10.66074068 1.33202934
OS 10.67738276 1.34728458
OS 10.69818536 1.36392666
OS 10.72314848 1.3791819
OS 10.75088528 1.3930503
OS 10.75227212 1.3930503
OS 10.7550458 1.39443714
OS 10.75920632 1.39582398
OS 10.76475368 1.39859766
OS 10.77168788 1.40137134
OS 10.78139576 1.40414502
OS 10.80219836 1.40969238
OS 10.82854832 1.41523974
OS 10.8590588 1.4207871
OS 10.89095612 1.42494762
OS 10.92701396 1.42633446
OS 10.94504288 1.42633446
OS 10.95475076 1.42494762
OE
OB 13.21807364 1.16006118 I
OS 13.23887624 1.15867434
OS 13.26245252 1.15590066
OS 13.2860288 1.15174014
OS 13.30960508 1.14619278
OS 13.33179452 1.13925858
OS 13.3345682 1.13787174
OS 13.3415024 1.13509806
OS 13.35121028 1.13093754
OS 13.36369184 1.12539018
OS 13.37756024 1.11706914
OS 13.39142864 1.1087481
OS 13.4039102 1.09765338
OS 13.41500492 1.08655866
OS 13.41639176 1.08517182
OS 13.41916544 1.0810113
OS 13.42332596 1.0740771
OS 13.42887332 1.06575606
OS 13.43580752 1.0532745
OS 13.44135488 1.04079294
OS 13.44690224 1.0255377
OS 13.45106276 1.00750878
OS 13.45106276 1.00612194
OS 13.4524496 1.00196142
OS 13.45383644 0.99364038
OS 13.45522328 0.98254566
OS 13.45522328 0.96729042
OS 13.45661012 0.9492615
OS 13.45799696 0.92568522
OS 13.45799696 0.89933526
OS 13.45799696 0.7412355
OS 13.45799696 0.73984866
OS 13.45799696 0.7343013
OS 13.45799696 0.72598026
OS 13.45799696 0.71488554
OS 13.45799696 0.70240398
OS 13.45799696 0.68714874
OS 13.4593838 0.65386458
OS 13.4593838 0.61919358
OS 13.46077064 0.58452258
OS 13.46215748 0.56926734
OS 13.46215748 0.55539894
OS 13.46354432 0.54291738
OS 13.46493116 0.5332095
OS 13.46493116 0.53182266
OS 13.466318 0.5262753
OS 13.46770484 0.51795426
OS 13.47186536 0.50685954
OS 13.47463904 0.49437798
OS 13.4801864 0.48050958
OS 13.4871206 0.46525434
OS 13.4940548 0.4499991
OS 13.37062604 0.4499991
OS 13.3692392 0.45138594
OS 13.36785236 0.4569333
OS 13.36507868 0.4638675
OS 13.36091816 0.47496222
OS 13.35675764 0.48744378
OS 13.35398396 0.50269902
OS 13.35121028 0.5193411
OS 13.3484366 0.53737002
OS 13.34704976 0.53737002
OS 13.34566292 0.53459634
OS 13.33734188 0.52766214
OS 13.32486032 0.51795426
OS 13.30821824 0.5054727
OS 13.28741564 0.49299114
OS 13.26661304 0.47912274
OS 13.2444236 0.46664118
OS 13.22084732 0.4569333
OS 13.21807364 0.45554646
OS 13.2097526 0.45415962
OS 13.19727104 0.4499991
OS 13.1820158 0.44583858
OS 13.16260004 0.44167806
OS 13.1404106 0.43890438
OS 13.11544748 0.4361307
OS 13.09048436 0.43474386
OS 13.07938964 0.43474386
OS 13.0710686 0.4361307
OS 13.06136072 0.4361307
OS 13.050266 0.43751754
OS 13.02530288 0.44167806
OS 12.99756608 0.44861226
OS 12.9670556 0.45832014
OS 12.9393188 0.47218854
OS 12.91435568 0.49021746
OS 12.911582 0.49299114
OS 12.9046478 0.49992534
OS 12.89493992 0.5124069
OS 12.8838452 0.52904898
OS 12.87275048 0.54985158
OS 12.8630426 0.57342786
OS 12.8561084 0.6025515
OS 12.85472156 0.6164199
OS 12.85333472 0.63306198
OS 12.85333472 0.63583566
OS 12.85333472 0.64138302
OS 12.85472156 0.6510909
OS 12.8561084 0.66357246
OS 12.85888208 0.6788277
OS 12.8630426 0.69408294
OS 12.86858996 0.71072502
OS 12.87552416 0.72598026
OS 12.876911 0.7273671
OS 12.87968468 0.73291446
OS 12.88523204 0.7412355
OS 12.89216624 0.75094338
OS 12.90048728 0.7620381
OS 12.911582 0.77313282
OS 12.92267672 0.78422754
OS 12.93654512 0.79393542
OS 12.93793196 0.79532226
OS 12.94347932 0.79809594
OS 12.95041352 0.8036433
OS 12.96150824 0.80919066
OS 12.9739898 0.81473802
OS 12.98924504 0.82167222
OS 13.00450028 0.82721958
OS 13.0225292 0.83276694
OS 13.02391604 0.83276694
OS 13.0294634 0.83415378
OS 13.03778444 0.83692746
OS 13.04887916 0.8383143
OS 13.06274756 0.84108798
OS 13.08077648 0.84386166
OS 13.10157908 0.84802218
OS 13.1265422 0.85079586
OS 13.12792904 0.85079586
OS 13.1334764 0.8521827
OS 13.1404106 0.8521827
OS 13.15011848 0.85356954
OS 13.1612132 0.85495638
OS 13.1750816 0.85773006
OS 13.19033684 0.8591169
OS 13.20697892 0.86189058
OS 13.24026308 0.86882478
OS 13.27632092 0.87575898
OS 13.30821824 0.88408002
OS 13.32347348 0.88824054
OS 13.33734188 0.89240106
OS 13.33734188 0.8937879
OS 13.33734188 0.89656158
OS 13.33872872 0.90488262
OS 13.33872872 0.9145905
OS 13.33872872 0.92013786
OS 13.33872872 0.92291154
OS 13.33872872 0.92429838
OS 13.33872872 0.92568522
OS 13.33872872 0.93400626
OS 13.33734188 0.94787466
OS 13.3345682 0.9631299
OS 13.33040768 0.97977198
OS 13.32347348 0.99641406
OS 13.31515244 1.0116693
OS 13.30405772 1.02415086
OS 13.30267088 1.0255377
OS 13.29573668 1.03108506
OS 13.28464196 1.03663242
OS 13.27077356 1.04495346
OS 13.2513578 1.05188766
OS 13.22916836 1.05882186
OS 13.20143156 1.06298238
OS 13.16953424 1.06436922
OS 13.15566584 1.06436922
OS 13.14179744 1.06298238
OS 13.12238168 1.0602087
OS 13.10296592 1.05743502
OS 13.08216332 1.05188766
OS 13.06274756 1.04495346
OS 13.04610548 1.03524558
OS 13.04471864 1.03385874
OS 13.03917128 1.02969822
OS 13.03223708 1.02276402
OS 13.02391604 1.0116693
OS 13.015595 0.9978009
OS 13.00588712 0.97977198
OS 12.99756608 0.95758254
OS 12.98924504 0.93261942
OS 12.87413732 0.94787466
OS 12.87413732 0.9492615
OS 12.87552416 0.95064834
OS 12.87552416 0.95480886
OS 12.876911 0.96035622
OS 12.88107152 0.97283778
OS 12.88661888 0.9908667
OS 12.89355308 1.00889562
OS 12.90187412 1.02831138
OS 12.91296884 1.04772714
OS 12.9254504 1.06575606
OS 12.92683724 1.0671429
OS 12.9323846 1.07269026
OS 12.94070564 1.0810113
OS 12.95180036 1.09210602
OS 12.9670556 1.10320074
OS 12.98508452 1.11429546
OS 13.00588712 1.12677702
OS 13.0294634 1.1364849
OS 13.03085024 1.1364849
OS 13.03223708 1.13787174
OS 13.0363976 1.13925858
OS 13.04194496 1.14064542
OS 13.05581336 1.14480594
OS 13.07522912 1.14896646
OS 13.09741856 1.15312698
OS 13.12515536 1.1572875
OS 13.154279 1.16006118
OS 13.18756316 1.16144802
OS 13.2028184 1.16144802
OS 13.21807364 1.16006118
OE
OB 15.76015136 1.16006372 I
OS 15.78095396 1.15867688
OS 15.8031434 1.1559032
OS 15.82671968 1.15035584
OS 15.8516828 1.14480848
OS 15.87525908 1.13648744
OS 15.87664592 1.13648744
OS 15.87803276 1.1351006
OS 15.88496696 1.13232692
OS 15.89606168 1.12677956
OS 15.90993008 1.11984536
OS 15.92518532 1.11013748
OS 15.94044056 1.09904276
OS 15.95430896 1.0865612
OS 15.96679052 1.0726928
OS 15.96817736 1.07130596
OS 15.97095104 1.0657586
OS 15.9764984 1.05605072
OS 15.9834326 1.044956
OS 15.9903668 1.02831392
OS 15.997301 1.010285
OS 16.00284836 0.9894824
OS 16.00839572 0.96590612
OS 15.893288 0.95065088
OS 15.893288 0.95342456
OS 15.89190116 0.95897192
OS 15.88912748 0.9686798
OS 15.88496696 0.98116136
OS 15.87803276 0.99364292
OS 15.86971172 1.00751132
OS 15.86000384 1.02137972
OS 15.84613544 1.03386128
OS 15.8447486 1.03524812
OS 15.83920124 1.0380218
OS 15.8308802 1.04356916
OS 15.81839864 1.04911652
OS 15.80453024 1.05466388
OS 15.78650132 1.06021124
OS 15.76431188 1.06298492
OS 15.7407356 1.06437176
OS 15.7268672 1.06437176
OS 15.7129988 1.06298492
OS 15.69496988 1.06159808
OS 15.67694096 1.05743756
OS 15.6575252 1.05327704
OS 15.63949628 1.04634284
OS 15.62424104 1.03663496
OS 15.6228542 1.03524812
OS 15.61869368 1.03247444
OS 15.61314632 1.02692708
OS 15.60759896 1.01860604
OS 15.60066476 1.010285
OS 15.5951174 0.99919028
OS 15.59095688 0.98670872
OS 15.58957004 0.97422716
OS 15.58957004 0.97284032
OS 15.58957004 0.97006664
OS 15.59095688 0.96590612
OS 15.59095688 0.96035876
OS 15.5951174 0.94649036
OS 15.60343844 0.93262196
OS 15.60482528 0.93123512
OS 15.60621212 0.92984828
OS 15.6089858 0.92568776
OS 15.61453316 0.92152724
OS 15.62008052 0.91736672
OS 15.62840156 0.91181936
OS 15.63810944 0.90765884
OS 15.64920416 0.90211148
OS 15.650591 0.90211148
OS 15.65336468 0.90072464
OS 15.65891204 0.8993378
OS 15.66861992 0.89517728
OS 15.68248832 0.89101676
OS 15.70051724 0.88685624
OS 15.71161196 0.88269572
OS 15.72409352 0.87992204
OS 15.73796192 0.87576152
OS 15.75321716 0.871601
OS 15.754604 0.871601
OS 15.75876452 0.87021416
OS 15.76569872 0.86882732
OS 15.77401976 0.86605364
OS 15.78372764 0.86327996
OS 15.7962092 0.86050628
OS 15.82255916 0.85218524
OS 15.8516828 0.8438642
OS 15.88080644 0.83415632
OS 15.9071564 0.82444844
OS 15.91825112 0.82028792
OS 15.927959 0.8161274
OS 15.93073268 0.81474056
OS 15.93628004 0.81196688
OS 15.94460108 0.80780636
OS 15.95708264 0.80087216
OS 15.9695642 0.79255112
OS 15.98204576 0.7814564
OS 15.99452732 0.76897484
OS 16.00562204 0.75510644
OS 16.00700888 0.7537196
OS 16.00978256 0.74817224
OS 16.01532992 0.7398512
OS 16.02087728 0.72736964
OS 16.0250378 0.7121144
OS 16.03058516 0.69547232
OS 16.03335884 0.67605656
OS 16.03474568 0.65386712
OS 16.03474568 0.65109344
OS 16.03474568 0.64415924
OS 16.03335884 0.63306452
OS 16.03058516 0.61780928
OS 16.02642464 0.6011672
OS 16.01949044 0.58313828
OS 16.0111694 0.56233568
OS 16.00007468 0.54291992
OS 15.99868784 0.54014624
OS 15.99314048 0.53459888
OS 15.98620628 0.524891
OS 15.97511156 0.51379628
OS 15.95985632 0.50131472
OS 15.94321424 0.48744632
OS 15.92379848 0.47496476
OS 15.9002222 0.4624832
OS 15.89883536 0.4624832
OS 15.89744852 0.46109636
OS 15.88912748 0.45832268
OS 15.87525908 0.45416216
OS 15.85723016 0.4486148
OS 15.83504072 0.44306744
OS 15.8100776 0.43890692
OS 15.78372764 0.43613324
OS 15.75321716 0.4347464
OS 15.7407356 0.4347464
OS 15.73102772 0.43613324
OS 15.719933 0.43613324
OS 15.7060646 0.43752008
OS 15.6921962 0.43890692
OS 15.67694096 0.4416806
OS 15.6436568 0.4486148
OS 15.6089858 0.45832268
OS 15.57570164 0.47219108
OS 15.5604464 0.48051212
OS 15.546578 0.49022
OS 15.54519116 0.49160684
OS 15.54380432 0.49299368
OS 15.53548328 0.50131472
OS 15.52300172 0.51379628
OS 15.50913332 0.53321204
OS 15.49387808 0.55678832
OS 15.47862284 0.58452512
OS 15.46614128 0.61919612
OS 15.4564334 0.65802764
OS 15.57292796 0.67605656
OS 15.57292796 0.67466972
OS 15.57292796 0.67328288
OS 15.57570164 0.66496184
OS 15.57847532 0.65109344
OS 15.58402268 0.6358382
OS 15.59095688 0.61919612
OS 15.59927792 0.6011672
OS 15.61175948 0.58313828
OS 15.62701472 0.56788304
OS 15.6297884 0.5664962
OS 15.63533576 0.56233568
OS 15.64643048 0.55678832
OS 15.66029888 0.54985412
OS 15.6783278 0.54291992
OS 15.6991304 0.53737256
OS 15.72409352 0.53321204
OS 15.75321716 0.5318252
OS 15.76708556 0.5318252
OS 15.78095396 0.53321204
OS 15.79898288 0.53598572
OS 15.81839864 0.54014624
OS 15.83920124 0.5456936
OS 15.85723016 0.5526278
OS 15.87387224 0.56372252
OS 15.87525908 0.56510936
OS 15.88080644 0.56926988
OS 15.8863538 0.57620408
OS 15.89467484 0.58591196
OS 15.90160904 0.59700668
OS 15.90854324 0.61087508
OS 15.91270376 0.62474348
OS 15.9140906 0.64138556
OS 15.9140906 0.6427724
OS 15.9140906 0.64831976
OS 15.91270376 0.65525396
OS 15.90993008 0.66496184
OS 15.90576956 0.67466972
OS 15.89883536 0.6843776
OS 15.89051432 0.69547232
OS 15.87803276 0.70379336
OS 15.87664592 0.7051802
OS 15.8724854 0.70656704
OS 15.8655512 0.71072756
OS 15.85445648 0.71488808
OS 15.8378144 0.72043544
OS 15.82810652 0.72459596
OS 15.8170118 0.72736964
OS 15.80453024 0.73153016
OS 15.79066184 0.73569068
OS 15.7754066 0.7398512
OS 15.75737768 0.74401172
OS 15.75599084 0.74401172
OS 15.75183032 0.74539856
OS 15.74489612 0.7467854
OS 15.73657508 0.74955908
OS 15.72548036 0.75233276
OS 15.7129988 0.75649328
OS 15.68664884 0.76342748
OS 15.65613836 0.77313536
OS 15.62701472 0.7814564
OS 15.59927792 0.79116428
OS 15.58679636 0.79671164
OS 15.57708848 0.80087216
OS 15.5743148 0.802259
OS 15.56876744 0.80503268
OS 15.5604464 0.81058004
OS 15.54935168 0.81751424
OS 15.53687012 0.82722212
OS 15.52438856 0.83831684
OS 15.511907 0.8507984
OS 15.50081228 0.86605364
OS 15.49942544 0.86744048
OS 15.49665176 0.87298784
OS 15.49249124 0.88269572
OS 15.48833072 0.89379044
OS 15.4841702 0.90765884
OS 15.48000968 0.92430092
OS 15.477236 0.940943
OS 15.47584916 0.96035876
OS 15.47584916 0.96313244
OS 15.47584916 0.9686798
OS 15.477236 0.97700084
OS 15.47862284 0.9894824
OS 15.48139652 1.00196396
OS 15.4841702 1.0172192
OS 15.48971756 1.0310876
OS 15.49665176 1.04634284
OS 15.4980386 1.04772968
OS 15.50081228 1.05327704
OS 15.5049728 1.06021124
OS 15.511907 1.06991912
OS 15.52022804 1.079627
OS 15.52993592 1.09210856
OS 15.54103064 1.10320328
OS 15.55489904 1.11291116
OS 15.55628588 1.114298
OS 15.5604464 1.11568484
OS 15.56599376 1.11984536
OS 15.5743148 1.12400588
OS 15.58540952 1.12955324
OS 15.59789108 1.1351006
OS 15.61314632 1.14064796
OS 15.6297884 1.14619532
OS 15.63256208 1.14758216
OS 15.63810944 1.148969
OS 15.64781732 1.15174268
OS 15.66029888 1.15451636
OS 15.67555412 1.15729004
OS 15.6921962 1.15867688
OS 15.71161196 1.16145056
OS 15.74489612 1.16145056
OS 15.76015136 1.16006372
OE
OB 15.06534452 1.16006372 I
OS 15.07643924 1.15867688
OS 15.09030764 1.1559032
OS 15.10556288 1.15312952
OS 15.1235918 1.148969
OS 15.14023388 1.14480848
OS 15.15964964 1.13787428
OS 15.17767856 1.13094008
OS 15.19709432 1.1212322
OS 15.21651008 1.11013748
OS 15.23592584 1.09765592
OS 15.25395476 1.08240068
OS 15.27059684 1.0657586
OS 15.27198368 1.06437176
OS 15.27475736 1.06159808
OS 15.27891788 1.05605072
OS 15.28446524 1.04772968
OS 15.29139944 1.0380218
OS 15.29833364 1.02692708
OS 15.30665468 1.01305868
OS 15.31497572 0.9964166
OS 15.32329676 0.97838768
OS 15.3316178 0.95897192
OS 15.338552 0.93678248
OS 15.3454862 0.9132062
OS 15.35103356 0.88685624
OS 15.35519408 0.85911944
OS 15.35796776 0.8299958
OS 15.3593546 0.79809848
OS 15.3593546 0.79671164
OS 15.3593546 0.79116428
OS 15.3593546 0.7814564
OS 15.35796776 0.767588
OS 14.83790276 0.767588
OS 14.83790276 0.76620116
OS 14.83790276 0.76204064
OS 14.8392896 0.75649328
OS 14.8392896 0.74817224
OS 14.84067644 0.73846436
OS 14.84345012 0.72736964
OS 14.84761064 0.70240652
OS 14.85593168 0.67466972
OS 14.8670264 0.64415924
OS 14.88228164 0.61642244
OS 14.9016974 0.59145932
OS 14.90308424 0.59145932
OS 14.90447108 0.58868564
OS 14.91279212 0.58175144
OS 14.92527368 0.57204356
OS 14.94191576 0.56233568
OS 14.9641052 0.55124096
OS 14.98906832 0.54153308
OS 15.01680512 0.53459888
OS 15.03206036 0.53321204
OS 15.04870244 0.5318252
OS 15.05979716 0.5318252
OS 15.07227872 0.53321204
OS 15.08753396 0.53598572
OS 15.10417604 0.54014624
OS 15.1235918 0.5456936
OS 15.14162072 0.55401464
OS 15.15964964 0.56510936
OS 15.16103648 0.5664962
OS 15.16797068 0.57204356
OS 15.17629172 0.5803646
OS 15.1859996 0.59145932
OS 15.19709432 0.60671456
OS 15.20957588 0.62613032
OS 15.22205744 0.64831976
OS 15.23315216 0.67466972
OS 15.35519408 0.65941448
OS 15.35519408 0.65802764
OS 15.35380724 0.65525396
OS 15.3524204 0.6497066
OS 15.34964672 0.64138556
OS 15.3454862 0.63306452
OS 15.34132568 0.6219698
OS 15.33023096 0.59839352
OS 15.31636256 0.57204356
OS 15.2969468 0.54430676
OS 15.27475736 0.5179568
OS 15.24702056 0.49299368
OS 15.24563372 0.49299368
OS 15.24286004 0.49022
OS 15.23869952 0.48744632
OS 15.23315216 0.4832858
OS 15.22483112 0.47912528
OS 15.21651008 0.47496476
OS 15.20541536 0.4694174
OS 15.1929338 0.46387004
OS 15.1790654 0.45832268
OS 15.165197 0.45277532
OS 15.130526 0.44445428
OS 15.09169448 0.43752008
OS 15.04870244 0.4347464
OS 15.0334472 0.4347464
OS 15.02373932 0.43613324
OS 15.01125776 0.43752008
OS 14.99600252 0.44029376
OS 14.97936044 0.44306744
OS 14.96133152 0.44584112
OS 14.9225 0.45693584
OS 14.9016974 0.46525688
OS 14.88228164 0.47357792
OS 14.86147904 0.48467264
OS 14.84206328 0.4971542
OS 14.82403436 0.5110226
OS 14.80600544 0.52766468
OS 14.8046186 0.52905152
OS 14.80184492 0.5318252
OS 14.7976844 0.53737256
OS 14.79213704 0.5456936
OS 14.78520284 0.55540148
OS 14.77826864 0.5664962
OS 14.7699476 0.5803646
OS 14.76162656 0.59561984
OS 14.75330552 0.61364876
OS 14.74498448 0.63306452
OS 14.73805028 0.65525396
OS 14.73111608 0.67883024
OS 14.72556872 0.70379336
OS 14.7214082 0.73153016
OS 14.71863452 0.7606538
OS 14.71724768 0.79116428
OS 14.71724768 0.79255112
OS 14.71724768 0.79948532
OS 14.71724768 0.80780636
OS 14.71863452 0.82028792
OS 14.72002136 0.83554316
OS 14.7214082 0.85218524
OS 14.72418188 0.871601
OS 14.7283424 0.89101676
OS 14.73943712 0.93539564
OS 14.74637132 0.95758508
OS 14.75469236 0.98116136
OS 14.76578708 1.0033508
OS 14.77826864 1.0241534
OS 14.79213704 1.044956
OS 14.80739228 1.06437176
OS 14.80877912 1.0657586
OS 14.8115528 1.06853228
OS 14.81710016 1.0726928
OS 14.82403436 1.079627
OS 14.8323554 1.0865612
OS 14.84345012 1.09488224
OS 14.85593168 1.10459012
OS 14.87118692 1.11291116
OS 14.88644216 1.12261904
OS 14.90447108 1.13094008
OS 14.92388684 1.13926112
OS 14.94468944 1.14619532
OS 14.96687888 1.15312952
OS 14.99045516 1.15729004
OS 15.01541828 1.16006372
OS 15.04176824 1.16145056
OS 15.05563664 1.16145056
OS 15.06534452 1.16006372
OE
OB 14.38440608 1.16006372 I
OS 14.39411396 1.16006372
OS 14.40382184 1.15867688
OS 14.42739812 1.15451636
OS 14.45236124 1.14758216
OS 14.4787112 1.13648744
OS 14.50506116 1.12261904
OS 14.5272506 1.10320328
OS 14.53002428 1.1004296
OS 14.53557164 1.09210856
OS 14.54527952 1.079627
OS 14.54944004 1.06991912
OS 14.5549874 1.06021124
OS 14.56053476 1.04772968
OS 14.56469528 1.03524812
OS 14.57024264 1.02137972
OS 14.57440316 1.00473764
OS 14.57717684 0.98809556
OS 14.57995052 0.9686798
OS 14.5827242 0.94926404
OS 14.5827242 0.9270746
OS 14.5827242 0.45000164
OS 14.4648428 0.45000164
OS 14.4648428 0.88685624
OS 14.4648428 0.88824308
OS 14.4648428 0.88962992
OS 14.4648428 0.89795096
OS 14.4648428 0.91043252
OS 14.46345596 0.92568776
OS 14.46206912 0.94232984
OS 14.46068228 0.95897192
OS 14.4579086 0.975614
OS 14.45374808 0.98809556
OS 14.45374808 0.9894824
OS 14.4509744 0.99364292
OS 14.44820072 0.99919028
OS 14.4440402 1.00612448
OS 14.43849284 1.01444552
OS 14.43155864 1.02276656
OS 14.4232376 1.0310876
OS 14.41214288 1.03940864
OS 14.41075604 1.04079548
OS 14.40659552 1.04218232
OS 14.40104816 1.044956
OS 14.39134028 1.04911652
OS 14.3816324 1.05327704
OS 14.36915084 1.05605072
OS 14.35666928 1.05743756
OS 14.34141404 1.0588244
OS 14.33447984 1.0588244
OS 14.32893248 1.05743756
OS 14.31506408 1.05605072
OS 14.298422 1.05327704
OS 14.27900624 1.04634284
OS 14.25820364 1.0380218
OS 14.23740104 1.02554024
OS 14.21798528 1.00889816
OS 14.21659844 1.00612448
OS 14.21105108 0.99919028
OS 14.20273004 0.98809556
OS 14.194409 0.97145348
OS 14.18470112 0.94926404
OS 14.17776692 0.92291408
OS 14.17221956 0.89101676
OS 14.16944588 0.85357208
OS 14.16944588 0.45000164
OS 14.05156448 0.45000164
OS 14.05156448 0.90072464
OS 14.05156448 0.90211148
OS 14.05156448 0.90488516
OS 14.05156448 0.90765884
OS 14.05156448 0.9132062
OS 14.05017764 0.92846144
OS 14.04740396 0.94510352
OS 14.04463028 0.96451928
OS 14.03908292 0.98393504
OS 14.03214872 1.00196396
OS 14.02244084 1.01860604
OS 14.021054 1.01999288
OS 14.01689348 1.02554024
OS 14.00995928 1.0310876
OS 14.0002514 1.03940864
OS 13.98776984 1.04634284
OS 13.97112776 1.05327704
OS 13.951712 1.05743756
OS 13.92813572 1.0588244
OS 13.91981468 1.0588244
OS 13.9101068 1.05743502
OS 13.89901208 1.05604818
OS 13.88514368 1.05188766
OS 13.8685016 1.04772714
OS 13.85324636 1.04079294
OS 13.83660428 1.0324719
OS 13.83521744 1.03108506
OS 13.82967008 1.02692454
OS 13.82273588 1.02137718
OS 13.813028 1.01305614
OS 13.80332012 1.00196142
OS 13.79361224 0.98809302
OS 13.78390436 0.97283778
OS 13.77558332 0.95480886
OS 13.77419648 0.95203518
OS 13.77280964 0.94510098
OS 13.77003596 0.93400626
OS 13.76587544 0.91875102
OS 13.76171492 0.89794842
OS 13.75894124 0.8729853
OS 13.7575544 0.84386166
OS 13.75616756 0.8105775
OS 13.75616756 0.4499991
OS 13.63828616 0.4499991
OS 13.63828616 1.14619278
OS 13.743686 1.14619278
OS 13.743686 1.0463403
OS 13.74507284 1.04911398
OS 13.74923336 1.05466134
OS 13.7575544 1.06436922
OS 13.76726228 1.07546394
OS 13.77974384 1.08933234
OS 13.79499908 1.10320074
OS 13.81164116 1.11706914
OS 13.83105692 1.1295507
OS 13.8338306 1.13093754
OS 13.8407648 1.13509806
OS 13.85185952 1.13925858
OS 13.86711476 1.14619278
OS 13.88514368 1.15174014
OS 13.90594628 1.15590066
OS 13.92952256 1.16006372
OS 13.95448568 1.16145056
OS 13.96696724 1.16145056
OS 13.98222248 1.16006372
OS 13.99886456 1.15729004
OS 14.01966716 1.15312952
OS 14.04046976 1.14758216
OS 14.06127236 1.13926112
OS 14.08068812 1.1281664
OS 14.0834618 1.12677956
OS 14.08900916 1.12261904
OS 14.0973302 1.11568484
OS 14.10842492 1.10459012
OS 14.11951964 1.09210856
OS 14.1320012 1.07685332
OS 14.14309592 1.0588244
OS 14.15141696 1.0380218
OS 14.1528038 1.03940864
OS 14.15557748 1.04356916
OS 14.159738 1.04911652
OS 14.1666722 1.05743756
OS 14.17499324 1.06714544
OS 14.18470112 1.07685332
OS 14.19579584 1.08794804
OS 14.20966424 1.1004296
OS 14.22491948 1.11152432
OS 14.24017472 1.12261904
OS 14.25820364 1.13232692
OS 14.2776194 1.1420348
OS 14.298422 1.15035584
OS 14.32061144 1.1559032
OS 14.34280088 1.16006372
OS 14.367764 1.16145056
OS 14.37747188 1.16145056
OS 14.38440608 1.16006372
OE
OB 9.81060776 1.16006118 I
OS 9.825863 1.15867434
OS 9.84389192 1.15590066
OS 9.86330768 1.15174014
OS 9.88411028 1.14619278
OS 9.90352604 1.13787174
OS 9.90629972 1.1364849
OS 9.91184708 1.13371122
OS 9.92155496 1.1295507
OS 9.93264968 1.1226165
OS 9.94651808 1.11429546
OS 9.95899964 1.10320074
OS 9.9714812 1.09210602
OS 9.98257592 1.07823762
OS 9.98396276 1.07685078
OS 9.98673644 1.07130342
OS 9.99089696 1.06436922
OS 9.99783116 1.05466134
OS 10.00337852 1.04079294
OS 10.00892588 1.02692454
OS 10.01586008 1.01028246
OS 10.0200206 0.99225354
OS 10.0200206 0.9908667
OS 10.02140744 0.98531934
OS 10.02279428 0.9769983
OS 10.02418112 0.96590358
OS 10.02418112 0.9492615
OS 10.02556796 0.92984574
OS 10.0269548 0.90626946
OS 10.0269548 0.87714582
OS 10.0269548 0.4499991
OS 9.9090734 0.4499991
OS 9.9090734 0.87159846
OS 9.9090734 0.8729853
OS 9.9090734 0.87437214
OS 9.9090734 0.88408002
OS 9.9090734 0.89656158
OS 9.90768656 0.91181682
OS 9.90629972 0.92984574
OS 9.90352604 0.94787466
OS 9.89936552 0.96451674
OS 9.895205 0.97977198
OS 9.895205 0.98115882
OS 9.89243132 0.98531934
OS 9.8882708 0.99225354
OS 9.88411028 1.00057458
OS 9.87717608 1.00889562
OS 9.86885504 1.0186035
OS 9.85776032 1.02831138
OS 9.84527876 1.03663242
OS 9.84389192 1.03801926
OS 9.8397314 1.04079294
OS 9.83141036 1.04356662
OS 9.82170248 1.04772714
OS 9.81060776 1.05188766
OS 9.79673936 1.05604818
OS 9.78009728 1.05743502
OS 9.7634552 1.05882186
OS 9.756521 1.05882186
OS 9.75097364 1.05743502
OS 9.73710524 1.05604818
OS 9.71907632 1.0532745
OS 9.69966056 1.0463403
OS 9.67747112 1.03801926
OS 9.65528168 1.02692454
OS 9.63447908 1.01028246
OS 9.6317054 1.00750878
OS 9.62615804 1.00057458
OS 9.62199752 0.99502722
OS 9.617837 0.98809302
OS 9.61228964 0.97977198
OS 9.60812912 0.9700641
OS 9.60258176 0.95896938
OS 9.5970344 0.94510098
OS 9.59287388 0.92984574
OS 9.58871336 0.91320366
OS 9.58593968 0.89517474
OS 9.583166 0.87575898
OS 9.58039232 0.8521827
OS 9.58039232 0.82860642
OS 9.58039232 0.4499991
OS 9.46251092 0.4499991
OS 9.46251092 1.14619278
OS 9.56791076 1.14619278
OS 9.56791076 1.0463403
OS 9.5692976 1.04772714
OS 9.57207128 1.05188766
OS 9.5762318 1.05743502
OS 9.58177916 1.06436922
OS 9.5901002 1.07269026
OS 9.59980808 1.08239814
OS 9.6109028 1.09349286
OS 9.6247712 1.10458758
OS 9.6386396 1.11429546
OS 9.65528168 1.12539018
OS 9.6733106 1.13509806
OS 9.69272636 1.1434191
OS 9.7149158 1.1503533
OS 9.73710524 1.15590066
OS 9.76206836 1.16006118
OS 9.78841832 1.16144802
OS 9.79951304 1.16144802
OS 9.81060776 1.16006118
OE
OB 8.23515752 0.4499991 I
OS 8.11727612 0.4499991
OS 8.11727612 1.40969238
OS 8.23515752 1.40969238
OS 8.23515752 0.4499991
OE
OB 8.5361018 1.2751689 I
OS 8.4182204 1.2751689
OS 8.4182204 1.40969238
OS 8.5361018 1.40969238
OS 8.5361018 1.2751689
OE
OB 7.18115912 0.7551039 I
OS 7.18115912 0.75371706
OS 7.18115912 0.74955654
OS 7.18115912 0.74400918
OS 7.18115912 0.73568814
OS 7.17977228 0.72459342
OS 7.17977228 0.7134987
OS 7.1769986 0.68714874
OS 7.17422492 0.65663826
OS 7.16867756 0.62474094
OS 7.16035652 0.5956173
OS 7.15064864 0.5678805
OS 7.15064864 0.56649366
OS 7.1492618 0.56510682
OS 7.14510128 0.55678578
OS 7.13816708 0.54569106
OS 7.1284592 0.53043582
OS 7.1145908 0.51518058
OS 7.09933556 0.4985385
OS 7.0799198 0.48189642
OS 7.05773036 0.46802802
OS 7.05495668 0.46664118
OS 7.04663564 0.46248066
OS 7.03415408 0.4569333
OS 7.01612516 0.45138594
OS 6.99393572 0.44445174
OS 6.9689726 0.43890438
OS 6.9412358 0.43474386
OS 6.91072532 0.43335702
OS 6.89824376 0.43335702
OS 6.88992272 0.43474386
OS 6.878828 0.4361307
OS 6.86773328 0.43751754
OS 6.83860964 0.4430649
OS 6.80809916 0.45138594
OS 6.77620184 0.4638675
OS 6.75955976 0.47218854
OS 6.74430452 0.48189642
OS 6.73043612 0.49299114
OS 6.71656772 0.5054727
OS 6.71518088 0.50685954
OS 6.71379404 0.50824638
OS 6.71102036 0.51379374
OS 6.70685984 0.5193411
OS 6.70131248 0.5262753
OS 6.69576512 0.53598318
OS 6.69021776 0.5470779
OS 6.68328356 0.55955946
OS 6.6777362 0.57342786
OS 6.67218884 0.59006994
OS 6.66664148 0.60671202
OS 6.66109412 0.62612778
OS 6.65832044 0.64693038
OS 6.65415992 0.67050666
OS 6.65277308 0.69408294
OS 6.65277308 0.7204329
OS 6.7678808 0.73707498
OS 6.7678808 0.73568814
OS 6.7678808 0.73291446
OS 6.7678808 0.7273671
OS 6.76926764 0.71904606
OS 6.77065448 0.71072502
OS 6.77065448 0.70101714
OS 6.774815 0.67744086
OS 6.77897552 0.65247774
OS 6.78729656 0.62751462
OS 6.7956176 0.60532518
OS 6.80116496 0.5956173
OS 6.80809916 0.58729626
OS 6.809486 0.58590942
OS 6.81503336 0.5817489
OS 6.8233544 0.5748147
OS 6.83444912 0.5678805
OS 6.84970436 0.55955946
OS 6.86634644 0.5540121
OS 6.88714904 0.54846474
OS 6.90933848 0.5470779
OS 6.91765952 0.5470779
OS 6.92598056 0.54846474
OS 6.93846212 0.54985158
OS 6.95094368 0.55262526
OS 6.96481208 0.55539894
OS 6.97868048 0.5609463
OS 6.99254888 0.5678805
OS 6.99393572 0.56926734
OS 6.99809624 0.57204102
OS 7.0036436 0.57758838
OS 7.01196464 0.58313574
OS 7.01889884 0.59284362
OS 7.02721988 0.6025515
OS 7.03415408 0.61364622
OS 7.03970144 0.62751462
OS 7.03970144 0.62890146
OS 7.04247512 0.63444882
OS 7.04386196 0.6441567
OS 7.04663564 0.65663826
OS 7.04940932 0.67328034
OS 7.05079616 0.69408294
OS 7.05356984 0.71904606
OS 7.05356984 0.7481697
OS 7.05356984 1.40969238
OS 7.18115912 1.40969238
OS 7.18115912 0.7551039
OE
OB 7.93560008 0.4499991 I
OS 7.83020024 0.4499991
OS 7.83020024 0.55123842
OS 7.8288134 0.54985158
OS 7.82603972 0.54569106
OS 7.8218792 0.5401437
OS 7.814945 0.5332095
OS 7.80662396 0.52488846
OS 7.79691608 0.51379374
OS 7.78582136 0.50408586
OS 7.77195296 0.49299114
OS 7.75669772 0.48189642
OS 7.74005564 0.47218854
OS 7.72202672 0.46248066
OS 7.70261096 0.45277278
OS 7.68042152 0.44583858
OS 7.65823208 0.44029122
OS 7.63326896 0.4361307
OS 7.60830584 0.43474386
OS 7.59859796 0.43474386
OS 7.5861164 0.4361307
OS 7.57086116 0.43751754
OS 7.55283224 0.44029122
OS 7.53341648 0.44445174
OS 7.51400072 0.4499991
OS 7.49319812 0.45832014
OS 7.49042444 0.45970698
OS 7.48487708 0.46248066
OS 7.4751692 0.46802802
OS 7.46407448 0.47496222
OS 7.45020608 0.48328326
OS 7.43772452 0.49299114
OS 7.42524296 0.50408586
OS 7.41414824 0.51656742
OS 7.4127614 0.51795426
OS 7.40998772 0.52350162
OS 7.4058272 0.53043582
OS 7.40027984 0.54153054
OS 7.39334564 0.5540121
OS 7.38779828 0.56926734
OS 7.38225092 0.58590942
OS 7.3780904 0.60393834
OS 7.3780904 0.60532518
OS 7.37670356 0.61087254
OS 7.37531672 0.61919358
OS 7.37531672 0.6302883
OS 7.37392988 0.64693038
OS 7.37254304 0.6649593
OS 7.3711562 0.68853558
OS 7.3711562 0.71488554
OS 7.3711562 1.14619278
OS 7.4890376 1.14619278
OS 7.4890376 0.75926442
OS 7.4890376 0.75787758
OS 7.4890376 0.7551039
OS 7.4890376 0.75094338
OS 7.4890376 0.74400918
OS 7.4890376 0.72875394
OS 7.49042444 0.70933818
OS 7.49042444 0.68853558
OS 7.49181128 0.66773298
OS 7.49319812 0.64970406
OS 7.4959718 0.63444882
OS 7.4959718 0.63306198
OS 7.49874548 0.62751462
OS 7.50151916 0.61919358
OS 7.50567968 0.60809886
OS 7.51261388 0.59700414
OS 7.52093492 0.58452258
OS 7.5306428 0.57342786
OS 7.54312436 0.56233314
OS 7.5445112 0.5609463
OS 7.55005856 0.55817262
OS 7.55699276 0.5540121
OS 7.56808748 0.54985158
OS 7.58056904 0.54430422
OS 7.59582428 0.5401437
OS 7.61246636 0.53737002
OS 7.63188212 0.53598318
OS 7.64159 0.53598318
OS 7.65129788 0.53737002
OS 7.66377944 0.53875686
OS 7.67903468 0.54291738
OS 7.69567676 0.5470779
OS 7.71370568 0.5540121
OS 7.7317346 0.56233314
OS 7.73450828 0.56371998
OS 7.74005564 0.5678805
OS 7.74837668 0.57342786
OS 7.75808456 0.5817489
OS 7.76917928 0.59284362
OS 7.780274 0.60532518
OS 7.78998188 0.61919358
OS 7.79830292 0.63583566
OS 7.79968976 0.63860934
OS 7.8010766 0.6441567
OS 7.80385028 0.65525142
OS 7.8080108 0.67050666
OS 7.81217132 0.68992242
OS 7.814945 0.7134987
OS 7.81633184 0.7412355
OS 7.81771868 0.77313282
OS 7.81771868 1.14619278
OS 7.93560008 1.14619278
OS 7.93560008 0.4499991
OE
OB 8.5361018 0.4499991 I
OS 8.4182204 0.4499991
OS 8.4182204 1.14619278
OS 8.5361018 1.14619278
OS 8.5361018 0.4499991
OE
OB 9.04091156 1.16006118 I
OS 9.06171416 1.15867434
OS 9.08529044 1.15590066
OS 9.10886672 1.15174014
OS 9.132443 1.14619278
OS 9.15463244 1.13925858
OS 9.15740612 1.13787174
OS 9.16434032 1.13509806
OS 9.1740482 1.13093754
OS 9.18652976 1.12539018
OS 9.20039816 1.11706914
OS 9.21426656 1.1087481
OS 9.22674812 1.09765338
OS 9.23784284 1.08655866
OS 9.23922968 1.08517182
OS 9.24200336 1.0810113
OS 9.24616388 1.0740771
OS 9.25171124 1.06575606
OS 9.25864544 1.0532745
OS 9.2641928 1.04079294
OS 9.26974016 1.0255377
OS 9.27390068 1.00750878
OS 9.27390068 1.00612194
OS 9.27528752 1.00196142
OS 9.27667436 0.99364038
OS 9.2780612 0.98254566
OS 9.2780612 0.96729042
OS 9.27944804 0.9492615
OS 9.28083488 0.92568522
OS 9.28083488 0.89933526
OS 9.28083488 0.7412355
OS 9.28083488 0.73984866
OS 9.28083488 0.7343013
OS 9.28083488 0.72598026
OS 9.28083488 0.71488554
OS 9.28083488 0.70240398
OS 9.28083488 0.68714874
OS 9.28222172 0.65386458
OS 9.28222172 0.61919358
OS 9.28360856 0.58452258
OS 9.2849954 0.56926734
OS 9.2849954 0.55539894
OS 9.28638224 0.54291738
OS 9.28776908 0.5332095
OS 9.28776908 0.53182266
OS 9.28915592 0.5262753
OS 9.29054276 0.51795426
OS 9.29470328 0.50685954
OS 9.29747696 0.49437798
OS 9.30302432 0.48050958
OS 9.30995852 0.46525434
OS 9.31689272 0.4499991
OS 9.19346396 0.4499991
OS 9.19207712 0.45138594
OS 9.19069028 0.4569333
OS 9.1879166 0.4638675
OS 9.18375608 0.47496222
OS 9.17959556 0.48744378
OS 9.17682188 0.50269902
OS 9.1740482 0.5193411
OS 9.17127452 0.53737002
OS 9.16988768 0.53737002
OS 9.16850084 0.53459634
OS 9.1601798 0.52766214
OS 9.14769824 0.51795426
OS 9.13105616 0.5054727
OS 9.11025356 0.49299114
OS 9.08945096 0.47912274
OS 9.06726152 0.46664118
OS 9.04368524 0.4569333
OS 9.04091156 0.45554646
OS 9.03259052 0.45415962
OS 9.02010896 0.4499991
OS 9.00485372 0.44583858
OS 8.98543796 0.44167806
OS 8.96324852 0.43890438
OS 8.9382854 0.4361307
OS 8.91332228 0.43474386
OS 8.90222756 0.43474386
OS 8.89390652 0.4361307
OS 8.88419864 0.4361307
OS 8.87310392 0.43751754
OS 8.8481408 0.44167806
OS 8.820404 0.44861226
OS 8.78989352 0.45832014
OS 8.76215672 0.47218854
OS 8.7371936 0.49021746
OS 8.73441992 0.49299114
OS 8.72748572 0.49992534
OS 8.71777784 0.5124069
OS 8.70668312 0.52904898
OS 8.6955884 0.54985158
OS 8.68588052 0.57342786
OS 8.67894632 0.6025515
OS 8.67755948 0.6164199
OS 8.67617264 0.63306198
OS 8.67617264 0.63583566
OS 8.67617264 0.64138302
OS 8.67755948 0.6510909
OS 8.67894632 0.66357246
OS 8.68172 0.6788277
OS 8.68588052 0.69408294
OS 8.69142788 0.71072502
OS 8.69836208 0.72598026
OS 8.69974892 0.7273671
OS 8.7025226 0.73291446
OS 8.70806996 0.7412355
OS 8.71500416 0.75094338
OS 8.7233252 0.7620381
OS 8.73441992 0.77313282
OS 8.74551464 0.78422754
OS 8.75938304 0.79393542
OS 8.76076988 0.79532226
OS 8.76631724 0.79809594
OS 8.77325144 0.8036433
OS 8.78434616 0.80919066
OS 8.79682772 0.81473802
OS 8.81208296 0.82167222
OS 8.8273382 0.82721958
OS 8.84536712 0.83276694
OS 8.84675396 0.83276694
OS 8.85230132 0.83415378
OS 8.86062236 0.83692746
OS 8.87171708 0.8383143
OS 8.88558548 0.84108798
OS 8.9036144 0.84386166
OS 8.924417 0.84802218
OS 8.94938012 0.85079586
OS 8.95076696 0.85079586
OS 8.95631432 0.8521827
OS 8.96324852 0.8521827
OS 8.9729564 0.85356954
OS 8.98405112 0.85495638
OS 8.99791952 0.85773006
OS 9.01317476 0.8591169
OS 9.02981684 0.86189058
OS 9.063101 0.86882478
OS 9.09915884 0.87575898
OS 9.13105616 0.88408002
OS 9.1463114 0.88824054
OS 9.1601798 0.89240106
OS 9.1601798 0.8937879
OS 9.1601798 0.89656158
OS 9.16156664 0.90488262
OS 9.16156664 0.9145905
OS 9.16156664 0.92013786
OS 9.16156664 0.92291154
OS 9.16156664 0.92429838
OS 9.16156664 0.92568522
OS 9.16156664 0.93400626
OS 9.1601798 0.94787466
OS 9.15740612 0.9631299
OS 9.1532456 0.97977198
OS 9.1463114 0.99641406
OS 9.13799036 1.0116693
OS 9.12689564 1.02415086
OS 9.1255088 1.0255377
OS 9.1185746 1.03108506
OS 9.10747988 1.03663242
OS 9.09361148 1.04495346
OS 9.07419572 1.05188766
OS 9.05200628 1.05882186
OS 9.02426948 1.06298238
OS 8.99237216 1.06436922
OS 8.97850376 1.06436922
OS 8.96463536 1.06298238
OS 8.9452196 1.0602087
OS 8.92580384 1.05743502
OS 8.90500124 1.05188766
OS 8.88558548 1.04495346
OS 8.8689434 1.03524558
OS 8.86755656 1.03385874
OS 8.8620092 1.02969822
OS 8.855075 1.02276402
OS 8.84675396 1.0116693
OS 8.83843292 0.9978009
OS 8.82872504 0.97977198
OS 8.820404 0.95758254
OS 8.81208296 0.93261942
OS 8.69697524 0.94787466
OS 8.69697524 0.9492615
OS 8.69836208 0.95064834
OS 8.69836208 0.95480886
OS 8.69974892 0.96035622
OS 8.70390944 0.97283778
OS 8.7094568 0.9908667
OS 8.716391 1.00889562
OS 8.72471204 1.02831138
OS 8.73580676 1.04772714
OS 8.74828832 1.06575606
OS 8.74967516 1.0671429
OS 8.75522252 1.07269026
OS 8.76354356 1.0810113
OS 8.77463828 1.09210602
OS 8.78989352 1.10320074
OS 8.80792244 1.11429546
OS 8.82872504 1.12677702
OS 8.85230132 1.1364849
OS 8.85368816 1.1364849
OS 8.855075 1.13787174
OS 8.85923552 1.13925858
OS 8.86478288 1.14064542
OS 8.87865128 1.14480594
OS 8.89806704 1.14896646
OS 8.92025648 1.15312698
OS 8.94799328 1.1572875
OS 8.97711692 1.16006118
OS 9.01040108 1.16144802
OS 9.02565632 1.16144802
OS 9.04091156 1.16006118
OE
OB 9.16156664 0.79948278 H
OS 9.1601798 0.79948278
OS 9.15879296 0.79809594
OS 9.15463244 0.7967091
OS 9.14908508 0.79532226
OS 9.14215088 0.79254858
OS 9.13382984 0.7897749
OS 9.12412196 0.78700122
OS 9.11302724 0.78422754
OS 9.10054568 0.78006702
OS 9.08529044 0.77729334
OS 9.0700352 0.77313282
OS 9.05200628 0.7689723
OS 9.03259052 0.76481178
OS 9.01317476 0.76065126
OS 8.99098532 0.75787758
OS 8.96740904 0.75371706
OS 8.96463536 0.75371706
OS 8.95631432 0.75233022
OS 8.94244592 0.74955654
OS 8.92719068 0.74678286
OS 8.9105486 0.74400918
OS 8.89390652 0.73984866
OS 8.87865128 0.73568814
OS 8.86478288 0.73014078
OS 8.86339604 0.73014078
OS 8.85923552 0.7273671
OS 8.85368816 0.72459342
OS 8.8481408 0.7204329
OS 8.83149872 0.70933818
OS 8.81763032 0.6926961
OS 8.81763032 0.69130926
OS 8.81485664 0.68853558
OS 8.8134698 0.68298822
OS 8.81069612 0.67605402
OS 8.80792244 0.66773298
OS 8.80514876 0.65941194
OS 8.80376192 0.64831722
OS 8.80237508 0.6372225
OS 8.80237508 0.63583566
OS 8.80237508 0.62890146
OS 8.80376192 0.62058042
OS 8.8065356 0.6094857
OS 8.81069612 0.59700414
OS 8.81763032 0.58452258
OS 8.82595136 0.57065418
OS 8.83704608 0.55817262
OS 8.83843292 0.55678578
OS 8.84398028 0.5540121
OS 8.85230132 0.54846474
OS 8.86339604 0.54291738
OS 8.87865128 0.53737002
OS 8.8966802 0.53182266
OS 8.9174828 0.52904898
OS 8.94244592 0.52766214
OS 8.95354064 0.52766214
OS 8.96740904 0.52904898
OS 8.98266428 0.53182266
OS 9.00208004 0.53459634
OS 9.0214958 0.5401437
OS 9.0422984 0.5470779
OS 9.063101 0.55678578
OS 9.06587468 0.55817262
OS 9.07142204 0.56233314
OS 9.08112992 0.56926734
OS 9.09222464 0.57897522
OS 9.1047062 0.59006994
OS 9.1185746 0.60393834
OS 9.12966932 0.62058042
OS 9.14076404 0.63860934
OS 9.14215088 0.63999618
OS 9.14353772 0.64554354
OS 9.1463114 0.65525142
OS 9.15047192 0.66773298
OS 9.15463244 0.68437506
OS 9.15740612 0.70379082
OS 9.15879296 0.7273671
OS 9.1601798 0.7551039
OS 9.16156664 0.79948278
OE
OB 13.33872872 0.79948278 H
OS 13.33734188 0.79948278
OS 13.33595504 0.79809594
OS 13.33179452 0.7967091
OS 13.32624716 0.79532226
OS 13.31931296 0.79254858
OS 13.31099192 0.7897749
OS 13.30128404 0.78700122
OS 13.29018932 0.78422754
OS 13.27770776 0.78006702
OS 13.26245252 0.77729334
OS 13.24719728 0.77313282
OS 13.22916836 0.7689723
OS 13.2097526 0.76481178
OS 13.19033684 0.76065126
OS 13.1681474 0.75787758
OS 13.14457112 0.75371706
OS 13.14179744 0.75371706
OS 13.1334764 0.75233022
OS 13.119608 0.74955654
OS 13.10435276 0.74678286
OS 13.08771068 0.74400918
OS 13.0710686 0.73984866
OS 13.05581336 0.73568814
OS 13.04194496 0.73014078
OS 13.04055812 0.73014078
OS 13.0363976 0.7273671
OS 13.03085024 0.72459342
OS 13.02530288 0.7204329
OS 13.0086608 0.70933818
OS 12.9947924 0.6926961
OS 12.9947924 0.69130926
OS 12.99201872 0.68853558
OS 12.99063188 0.68298822
OS 12.9878582 0.67605402
OS 12.98508452 0.66773298
OS 12.98231084 0.65941194
OS 12.980924 0.64831722
OS 12.97953716 0.6372225
OS 12.97953716 0.63583566
OS 12.97953716 0.62890146
OS 12.980924 0.62058042
OS 12.98369768 0.6094857
OS 12.9878582 0.59700414
OS 12.9947924 0.58452258
OS 13.00311344 0.57065418
OS 13.01420816 0.55817262
OS 13.015595 0.55678578
OS 13.02114236 0.5540121
OS 13.0294634 0.54846474
OS 13.04055812 0.54291738
OS 13.05581336 0.53737002
OS 13.07384228 0.53182266
OS 13.09464488 0.52904898
OS 13.119608 0.52766214
OS 13.13070272 0.52766214
OS 13.14457112 0.52904898
OS 13.15982636 0.53182266
OS 13.17924212 0.53459634
OS 13.19865788 0.5401437
OS 13.21946048 0.5470779
OS 13.24026308 0.55678578
OS 13.24303676 0.55817262
OS 13.24858412 0.56233314
OS 13.258292 0.56926734
OS 13.26938672 0.57897522
OS 13.28186828 0.59006994
OS 13.29573668 0.60393834
OS 13.3068314 0.62058042
OS 13.31792612 0.63860934
OS 13.31931296 0.63999618
OS 13.3206998 0.64554354
OS 13.32347348 0.65525142
OS 13.327634 0.66773298
OS 13.33179452 0.68437506
OS 13.3345682 0.70379082
OS 13.33595504 0.7273671
OS 13.33734188 0.7551039
OS 13.33872872 0.79948278
OE
OB 15.04315508 1.06437176 H
OS 15.03483404 1.06437176
OS 15.02928668 1.06298492
OS 15.01403144 1.06159808
OS 14.99600252 1.05743756
OS 14.97381308 1.05050336
OS 14.9502368 1.04079548
OS 14.92804736 1.02692708
OS 14.90585792 1.00889816
OS 14.90308424 1.00612448
OS 14.89753688 0.99919028
OS 14.887829 0.98670872
OS 14.87812112 0.97006664
OS 14.8670264 0.95065088
OS 14.85731852 0.92568776
OS 14.84899748 0.89656412
OS 14.84483696 0.8646668
OS 15.234539 0.8646668
OS 15.234539 0.86605364
OS 15.234539 0.86882732
OS 15.23315216 0.87298784
OS 15.23315216 0.8785352
OS 15.23037848 0.89517728
OS 15.22621796 0.9132062
OS 15.21928376 0.93539564
OS 15.21234956 0.95619824
OS 15.20125484 0.97700084
OS 15.18877328 0.99502976
OS 15.18877328 0.9964166
OS 15.1859996 0.99780344
OS 15.1790654 1.00612448
OS 15.16658384 1.0172192
OS 15.14994176 1.02970076
OS 15.12913916 1.04218232
OS 15.10417604 1.05327704
OS 15.0750524 1.06159808
OS 15.05979716 1.06298492
OS 15.04315508 1.06437176
OE
SE
S P 0
OB 13.71958902 -0.91785694 I
OS 13.72097586 -0.9164701
OS 13.7223627 -0.91369642
OS 13.72652322 -0.9095359
OS 13.73345742 -0.9026017
OS 13.74039162 -0.8956675
OS 13.74871266 -0.88734646
OS 13.75980738 -0.87902542
OS 13.7709021 -0.87070438
OS 13.7986389 -0.85267546
OS 13.83053622 -0.83880706
OS 13.84856514 -0.83187286
OS 13.8679809 -0.82771234
OS 13.8887835 -0.82493866
OS 13.9095861 -0.82355182
OS 13.92068082 -0.82355182
OS 13.93316238 -0.82493866
OS 13.94841762 -0.8263255
OS 13.96644654 -0.83048602
OS 13.98724914 -0.83464654
OS 14.00943858 -0.84158074
OS 14.03024118 -0.84990178
OS 14.03301486 -0.85128862
OS 14.03994906 -0.8540623
OS 14.05104378 -0.8609965
OS 14.06352534 -0.86931754
OS 14.07878058 -0.87902542
OS 14.09403582 -0.89150698
OS 14.1106779 -0.90676222
OS 14.1245463 -0.9234043
OS 14.12593314 -0.92479114
OS 14.13009366 -0.93172534
OS 14.13702786 -0.94143322
OS 14.1453489 -0.95391478
OS 14.15505678 -0.97055686
OS 14.16476466 -0.98997262
OS 14.17447254 -1.01216206
OS 14.18279358 -1.03573834
OS 14.18279358 -1.03712518
OS 14.18418042 -1.03851202
OS 14.18556726 -1.04267254
OS 14.1869541 -1.04683306
OS 14.18972778 -1.06070146
OS 14.1938883 -1.07873038
OS 14.19804882 -1.09953298
OS 14.20220934 -1.12310926
OS 14.20359618 -1.14945922
OS 14.20498302 -1.17719602
OS 14.20498302 -1.17858286
OS 14.20498302 -1.18551706
OS 14.20498302 -1.1938381
OS 14.20359618 -1.20631966
OS 14.20220934 -1.2215749
OS 14.2008225 -1.23821698
OS 14.19804882 -1.25763274
OS 14.1938883 -1.27843534
OS 14.18279358 -1.32281422
OS 14.17585938 -1.3463905
OS 14.16753834 -1.36857994
OS 14.15783046 -1.39215622
OS 14.1453489 -1.41295882
OS 14.1314805 -1.43376142
OS 14.11622526 -1.45317718
OS 14.11483842 -1.45456402
OS 14.11206474 -1.4573377
OS 14.10790422 -1.46149822
OS 14.10097002 -1.46843242
OS 14.09126214 -1.47536662
OS 14.08155426 -1.48368766
OS 14.07045954 -1.4920087
OS 14.05659114 -1.50171658
OS 14.0413359 -1.51003762
OS 14.02608066 -1.5197455
OS 13.98863598 -1.53500074
OS 13.96922022 -1.54193494
OS 13.94841762 -1.54609546
OS 13.92622818 -1.54886914
OS 13.90403874 -1.55025598
OS 13.89849138 -1.55025598
OS 13.89155718 -1.54886914
OS 13.88323614 -1.54886914
OS 13.87352826 -1.5474823
OS 13.8610467 -1.54470862
OS 13.8333099 -1.53777442
OS 13.81805466 -1.53222706
OS 13.80279942 -1.52529286
OS 13.78615734 -1.51697182
OS 13.7709021 -1.50726394
OS 13.75426002 -1.49478238
OS 13.73900478 -1.48091398
OS 13.72513638 -1.46565874
OS 13.71126798 -1.44762982
OS 13.71126798 -1.53500074
OS 13.60170762 -1.53500074
OS 13.60170762 -0.57530746
OS 13.71958902 -0.57530746
OS 13.71958902 -0.91785694
OE
OB 13.16346618 -0.82493866 I
OS 13.17594774 -0.8263255
OS 13.18981614 -0.82909918
OS 13.20507138 -0.83187286
OS 13.2231003 -0.83464654
OS 13.26054498 -0.8471281
OS 13.27996074 -0.8540623
OS 13.2993765 -0.86377018
OS 13.31879226 -0.87347806
OS 13.33820802 -0.88734646
OS 13.35623694 -0.90121486
OS 13.37426586 -0.91785694
OS 13.3756527 -0.91924378
OS 13.37842638 -0.92201746
OS 13.3825869 -0.92756482
OS 13.38813426 -0.93449902
OS 13.39506846 -0.9442069
OS 13.4033895 -0.95668846
OS 13.41171054 -0.97055686
OS 13.42003158 -0.9858121
OS 13.42835262 -1.00245418
OS 13.43667366 -1.02325678
OS 13.4449947 -1.04405938
OS 13.4519289 -1.06763566
OS 13.45747626 -1.09259878
OS 13.46163678 -1.11894874
OS 13.46441046 -1.14668554
OS 13.4657973 -1.17719602
OS 13.4657973 -1.17858286
OS 13.4657973 -1.18274338
OS 13.4657973 -1.18967758
OS 13.4657973 -1.19938546
OS 13.46441046 -1.21048018
OS 13.46302362 -1.22434858
OS 13.46302362 -1.23821698
OS 13.46024994 -1.25347222
OS 13.45608942 -1.28814322
OS 13.44776838 -1.32281422
OS 13.4380605 -1.35748522
OS 13.4241921 -1.38938254
OS 13.4241921 -1.39076938
OS 13.42280526 -1.39215622
OS 13.42003158 -1.39631674
OS 13.4172579 -1.4018641
OS 13.40755002 -1.4157325
OS 13.39506846 -1.43237458
OS 13.37842638 -1.45179034
OS 13.35762378 -1.4712061
OS 13.3340475 -1.49062186
OS 13.3063107 -1.50865078
OS 13.30492386 -1.50865078
OS 13.30353702 -1.51003762
OS 13.2993765 -1.5128113
OS 13.2924423 -1.51558498
OS 13.2855081 -1.51835866
OS 13.27718706 -1.52113234
OS 13.25638446 -1.52945338
OS 13.23280818 -1.53638758
OS 13.20368454 -1.54332178
OS 13.17317406 -1.54886914
OS 13.1398899 -1.55025598
OS 13.1260215 -1.55025598
OS 13.11492678 -1.54886914
OS 13.10244522 -1.5474823
OS 13.08857682 -1.54470862
OS 13.07193474 -1.54193494
OS 13.05529266 -1.53916126
OS 13.01784798 -1.52806654
OS 12.99704538 -1.5197455
OS 12.97762962 -1.51142446
OS 12.95821386 -1.50032974
OS 12.9387981 -1.48784818
OS 12.92076918 -1.47397978
OS 12.90274026 -1.4573377
OS 12.90135342 -1.45595086
OS 12.89857974 -1.45317718
OS 12.89441922 -1.44762982
OS 12.88887186 -1.43930878
OS 12.88193766 -1.4296009
OS 12.87500346 -1.41850618
OS 12.86668242 -1.40463778
OS 12.85836138 -1.3879957
OS 12.85004034 -1.36996678
OS 12.8417193 -1.34916418
OS 12.8347851 -1.32697474
OS 12.8278509 -1.30339846
OS 12.82230354 -1.2770485
OS 12.81814302 -1.2493117
OS 12.81536934 -1.21880122
OS 12.8139825 -1.1869039
OS 12.8139825 -1.18413022
OS 12.8139825 -1.17858286
OS 12.81536934 -1.16887498
OS 12.81536934 -1.15500658
OS 12.81675618 -1.13975134
OS 12.81952986 -1.12033558
OS 12.82230354 -1.10091982
OS 12.8278509 -1.07873038
OS 12.83339826 -1.05654094
OS 12.84033246 -1.03296466
OS 12.8486535 -1.00800154
OS 12.85974822 -0.98442526
OS 12.87084294 -0.96223582
OS 12.88609818 -0.94004638
OS 12.90135342 -0.91924378
OS 12.92076918 -0.90121486
OS 12.92215602 -0.89982802
OS 12.9249297 -0.89844118
OS 12.93047706 -0.89428066
OS 12.93741126 -0.8887333
OS 12.9457323 -0.88318594
OS 12.95682702 -0.87625174
OS 12.96792174 -0.86931754
OS 12.98179014 -0.86238334
OS 12.99704538 -0.85544914
OS 13.01368746 -0.84851494
OS 13.05113214 -0.83603338
OS 13.09412418 -0.8263255
OS 13.11631362 -0.82493866
OS 13.1398899 -0.82355182
OS 13.1537583 -0.82355182
OS 13.16346618 -0.82493866
OE
OB 12.3632595 -0.5766943 I
OS 12.37574106 -0.5766943
OS 12.4048647 -0.57808114
OS 12.43537518 -0.58224166
OS 12.46865934 -0.58640218
OS 12.49916982 -0.59333638
OS 12.51442506 -0.5974969
OS 12.52690662 -0.60165742
OS 12.52829346 -0.60165742
OS 12.5296803 -0.60304426
OS 12.53800134 -0.60720478
OS 12.5504829 -0.61275214
OS 12.56573814 -0.62246002
OS 12.58238022 -0.63494158
OS 12.60040914 -0.65158366
OS 12.61705122 -0.67099942
OS 12.6336933 -0.69318886
OS 12.6336933 -0.6945757
OS 12.63508014 -0.69596254
OS 12.6406275 -0.70428358
OS 12.64617486 -0.71815198
OS 12.6544959 -0.7361809
OS 12.6614301 -0.7569835
OS 12.6683643 -0.78194662
OS 12.67252482 -0.80829658
OS 12.67391166 -0.83742022
OS 12.67391166 -0.83880706
OS 12.67391166 -0.84158074
OS 12.67391166 -0.8471281
OS 12.67252482 -0.8540623
OS 12.67252482 -0.86377018
OS 12.67113798 -0.87347806
OS 12.66559062 -0.89705434
OS 12.65726958 -0.92479114
OS 12.64617486 -0.95391478
OS 12.62953278 -0.98303842
OS 12.61843806 -0.99690682
OS 12.60734334 -1.01077522
OS 12.6059565 -1.01216206
OS 12.60456966 -1.0135489
OS 12.60040914 -1.01770942
OS 12.59486178 -1.02186994
OS 12.58792758 -1.0274173
OS 12.57960654 -1.03296466
OS 12.56851182 -1.03989886
OS 12.5574171 -1.0482199
OS 12.5435487 -1.0551541
OS 12.52829346 -1.0620883
OS 12.51165138 -1.07040934
OS 12.49362246 -1.07734354
OS 12.47281986 -1.0828909
OS 12.45201726 -1.0898251
OS 12.42844098 -1.09398562
OS 12.40347786 -1.09814614
OS 12.40625154 -1.09953298
OS 12.4117989 -1.10230666
OS 12.42011994 -1.10785402
OS 12.43121466 -1.11340138
OS 12.45617778 -1.12865662
OS 12.46865934 -1.1383645
OS 12.47975406 -1.14668554
OS 12.48252774 -1.14945922
OS 12.48946194 -1.15639342
OS 12.50055666 -1.16748814
OS 12.51442506 -1.18135654
OS 12.5296803 -1.2007723
OS 12.54770922 -1.2215749
OS 12.56573814 -1.24653802
OS 12.5851539 -1.27427482
OS 12.75018786 -1.53500074
OS 12.5920881 -1.53500074
OS 12.46588566 -1.33529578
OS 12.46588566 -1.33390894
OS 12.46311198 -1.33113526
OS 12.4603383 -1.32697474
OS 12.45617778 -1.32142738
OS 12.4464699 -1.30617214
OS 12.43398834 -1.28675638
OS 12.4187331 -1.26595378
OS 12.40347786 -1.24376434
OS 12.38822262 -1.22296174
OS 12.37435422 -1.20354598
OS 12.37296738 -1.20215914
OS 12.36880686 -1.19661178
OS 12.36187266 -1.18829074
OS 12.35216478 -1.17858286
OS 12.33136218 -1.15778026
OS 12.32026746 -1.14807238
OS 12.30917274 -1.13975134
OS 12.3077859 -1.1383645
OS 12.30501222 -1.13697766
OS 12.29946486 -1.13420398
OS 12.29114382 -1.13004346
OS 12.28282278 -1.12588294
OS 12.2731149 -1.12172242
OS 12.25092546 -1.11478822
OS 12.24953862 -1.11478822
OS 12.24676494 -1.11340138
OS 12.24121758 -1.11340138
OS 12.23428338 -1.11201454
OS 12.2245755 -1.1106277
OS 12.21348078 -1.1106277
OS 12.19822554 -1.10924086
OS 12.03457842 -1.10924086
OS 12.03457842 -1.53500074
OS 11.90698914 -1.53500074
OS 11.90698914 -0.57530746
OS 12.35216478 -0.57530746
OS 12.3632595 -0.5766943
OE
OB 15.65145714 -0.82493612 I
OS 15.67225974 -0.82632296
OS 15.69444918 -0.82909664
OS 15.71802546 -0.834644
OS 15.74298858 -0.84019136
OS 15.76656486 -0.8485124
OS 15.7679517 -0.8485124
OS 15.76933854 -0.84989924
OS 15.77627274 -0.85267292
OS 15.78736746 -0.85822028
OS 15.80123586 -0.86515448
OS 15.8164911 -0.87486236
OS 15.83174634 -0.88595708
OS 15.84561474 -0.89843864
OS 15.8580963 -0.91230704
OS 15.85948314 -0.91369388
OS 15.86225682 -0.91924124
OS 15.86780418 -0.92894912
OS 15.87473838 -0.94004384
OS 15.88167258 -0.95668592
OS 15.88860678 -0.97471484
OS 15.89415414 -0.99551744
OS 15.8997015 -1.01909372
OS 15.78459378 -1.03434896
OS 15.78459378 -1.03157528
OS 15.78320694 -1.02602792
OS 15.78043326 -1.01632004
OS 15.77627274 -1.00383848
OS 15.76933854 -0.99135692
OS 15.7610175 -0.97748852
OS 15.75130962 -0.96362012
OS 15.73744122 -0.95113856
OS 15.73605438 -0.94975172
OS 15.73050702 -0.94697804
OS 15.72218598 -0.94143068
OS 15.70970442 -0.93588332
OS 15.69583602 -0.93033596
OS 15.6778071 -0.9247886
OS 15.65561766 -0.92201492
OS 15.63204138 -0.92062808
OS 15.61817298 -0.92063062
OS 15.60430458 -0.92201746
OS 15.58627566 -0.9234043
OS 15.56824674 -0.92756482
OS 15.54883098 -0.93172534
OS 15.53080206 -0.93865954
OS 15.51554682 -0.94836742
OS 15.51415998 -0.94975426
OS 15.50999946 -0.95252794
OS 15.5044521 -0.9580753
OS 15.49890474 -0.96639634
OS 15.49197054 -0.97471738
OS 15.48642318 -0.9858121
OS 15.48226266 -0.99829366
OS 15.48087582 -1.01077522
OS 15.48087582 -1.01216206
OS 15.48087582 -1.01493574
OS 15.48226266 -1.01909626
OS 15.48226266 -1.02464362
OS 15.48642318 -1.03851202
OS 15.49474422 -1.05238042
OS 15.49613106 -1.05376726
OS 15.4975179 -1.0551541
OS 15.50029158 -1.05931462
OS 15.50583894 -1.06347514
OS 15.5113863 -1.06763566
OS 15.51970734 -1.07318302
OS 15.52941522 -1.07734354
OS 15.54050994 -1.0828909
OS 15.54189678 -1.0828909
OS 15.54467046 -1.08427774
OS 15.55021782 -1.08566458
OS 15.5599257 -1.0898251
OS 15.5737941 -1.09398562
OS 15.59182302 -1.09814614
OS 15.60291774 -1.10230666
OS 15.6153993 -1.10508034
OS 15.6292677 -1.10923832
OS 15.64452294 -1.11339884
OS 15.64590978 -1.11339884
OS 15.6500703 -1.11478568
OS 15.6570045 -1.11617252
OS 15.66532554 -1.1189462
OS 15.67503342 -1.12171988
OS 15.68751498 -1.12449356
OS 15.71386494 -1.1328146
OS 15.74298858 -1.14113564
OS 15.77211222 -1.15084352
OS 15.79846218 -1.1605514
OS 15.8095569 -1.16471192
OS 15.81926478 -1.16887244
OS 15.82203846 -1.17025928
OS 15.82758582 -1.17303296
OS 15.83590686 -1.17719348
OS 15.84838842 -1.18412768
OS 15.86086998 -1.19244872
OS 15.87335154 -1.20354344
OS 15.8858331 -1.216025
OS 15.89692782 -1.2298934
OS 15.89831466 -1.23128024
OS 15.90108834 -1.2368276
OS 15.9066357 -1.24514864
OS 15.91218306 -1.2576302
OS 15.91634358 -1.27288544
OS 15.92189094 -1.28952752
OS 15.92466462 -1.30894328
OS 15.92605146 -1.33113272
OS 15.92605146 -1.3339064
OS 15.92605146 -1.3408406
OS 15.92466462 -1.35193532
OS 15.92189094 -1.36719056
OS 15.91773042 -1.38383264
OS 15.91079622 -1.40186156
OS 15.90247518 -1.42266416
OS 15.89138046 -1.44207992
OS 15.88999362 -1.4448536
OS 15.88444626 -1.45040096
OS 15.87751206 -1.46010884
OS 15.86641734 -1.47120356
OS 15.8511621 -1.48368512
OS 15.83452002 -1.49755352
OS 15.81510426 -1.51003508
OS 15.79152798 -1.52251664
OS 15.79014114 -1.52251664
OS 15.7887543 -1.52390348
OS 15.78043326 -1.52667716
OS 15.76656486 -1.53083768
OS 15.74853594 -1.53638504
OS 15.7263465 -1.5419324
OS 15.70138338 -1.54609292
OS 15.67503342 -1.5488666
OS 15.64452294 -1.55025344
OS 15.63204138 -1.55025344
OS 15.6223335 -1.54886914
OS 15.61123878 -1.54886914
OS 15.59737038 -1.5474823
OS 15.58350198 -1.54609546
OS 15.56824674 -1.54332178
OS 15.53496258 -1.53638758
OS 15.50029158 -1.5266797
OS 15.46700742 -1.5128113
OS 15.45175218 -1.50449026
OS 15.43788378 -1.49478238
OS 15.43649694 -1.49339554
OS 15.4351101 -1.4920087
OS 15.42678906 -1.48368766
OS 15.4143075 -1.4712061
OS 15.4004391 -1.45179034
OS 15.38518386 -1.42821406
OS 15.36992862 -1.40047726
OS 15.35744706 -1.36580626
OS 15.34773918 -1.32697474
OS 15.46423374 -1.30894582
OS 15.46423374 -1.31033266
OS 15.46423374 -1.3117195
OS 15.46700742 -1.32004054
OS 15.4697811 -1.33390894
OS 15.47532846 -1.34916418
OS 15.48226266 -1.36580626
OS 15.4905837 -1.38383518
OS 15.50306526 -1.4018641
OS 15.5183205 -1.41711934
OS 15.52109418 -1.41850618
OS 15.52664154 -1.4226667
OS 15.53773626 -1.42821406
OS 15.55160466 -1.43514826
OS 15.56963358 -1.44208246
OS 15.59043618 -1.44762982
OS 15.6153993 -1.45179034
OS 15.64452294 -1.45317464
OS 15.65839134 -1.45317464
OS 15.67225974 -1.4517878
OS 15.69028866 -1.44901412
OS 15.70970442 -1.4448536
OS 15.73050702 -1.43930624
OS 15.74853594 -1.43237204
OS 15.76517802 -1.42127732
OS 15.76656486 -1.41989048
OS 15.77211222 -1.41572996
OS 15.77765958 -1.40879576
OS 15.78598062 -1.39908788
OS 15.79291482 -1.38799316
OS 15.79984902 -1.37412476
OS 15.80400954 -1.36025636
OS 15.80539638 -1.34361428
OS 15.80539638 -1.34222744
OS 15.80539638 -1.33668008
OS 15.80400954 -1.32974588
OS 15.80123586 -1.320038
OS 15.79707534 -1.31033012
OS 15.79014114 -1.30062224
OS 15.7818201 -1.28952752
OS 15.76933854 -1.28120648
OS 15.7679517 -1.27981964
OS 15.76379118 -1.2784328
OS 15.75685698 -1.27427228
OS 15.74576226 -1.27011176
OS 15.72912018 -1.2645644
OS 15.7194123 -1.26040388
OS 15.70831758 -1.2576302
OS 15.69583602 -1.25346968
OS 15.68196762 -1.24930916
OS 15.66671238 -1.24514864
OS 15.64868346 -1.24098812
OS 15.64729662 -1.24098812
OS 15.6431361 -1.23960128
OS 15.6362019 -1.23821444
OS 15.62788086 -1.2354433
OS 15.61678614 -1.23266962
OS 15.60430458 -1.2285091
OS 15.57795462 -1.2215749
OS 15.54744414 -1.21186702
OS 15.5183205 -1.20354598
OS 15.4905837 -1.1938381
OS 15.47810214 -1.18829074
OS 15.46839426 -1.18413022
OS 15.46562058 -1.18274338
OS 15.46007322 -1.1799697
OS 15.45175218 -1.17442234
OS 15.44065746 -1.16748814
OS 15.4281759 -1.15778026
OS 15.41569434 -1.14668554
OS 15.40321278 -1.13420398
OS 15.39211806 -1.11894874
OS 15.39073122 -1.1175619
OS 15.38795754 -1.11201454
OS 15.38379702 -1.10230666
OS 15.3796365 -1.09121194
OS 15.37547598 -1.07734354
OS 15.37131546 -1.06070146
OS 15.36854178 -1.04405938
OS 15.36715494 -1.02464362
OS 15.36715494 -1.02186994
OS 15.36715494 -1.01632258
OS 15.36854178 -1.00800154
OS 15.36992862 -0.99551998
OS 15.3727023 -0.98303842
OS 15.37547598 -0.96778318
OS 15.38102334 -0.95391478
OS 15.38795754 -0.93865954
OS 15.38934438 -0.9372727
OS 15.39211806 -0.93172534
OS 15.39627858 -0.92479114
OS 15.40321278 -0.91508326
OS 15.41153382 -0.90537538
OS 15.4212417 -0.89289382
OS 15.43233642 -0.8817991
OS 15.44620482 -0.87209122
OS 15.44759166 -0.87070438
OS 15.45175218 -0.86931754
OS 15.45729954 -0.86515702
OS 15.46562058 -0.8609965
OS 15.4767153 -0.85544914
OS 15.48919686 -0.84990178
OS 15.5044521 -0.84435442
OS 15.52109418 -0.83880706
OS 15.52386786 -0.83742022
OS 15.52941522 -0.83603338
OS 15.5391231 -0.8332597
OS 15.55160466 -0.83048602
OS 15.5668599 -0.82771234
OS 15.58350198 -0.8263255
OS 15.60291774 -0.82355182
OS 15.6362019 -0.82354928
OS 15.65145714 -0.82493612
OE
OB 14.46570894 -1.53500074 I
OS 14.34782754 -1.53500074
OS 14.34782754 -0.57530746
OS 14.46570894 -0.57530746
OS 14.46570894 -1.53500074
OE
OB 14.9566503 -0.82493866 I
OS 14.96774502 -0.8263255
OS 14.98161342 -0.82909918
OS 14.99686866 -0.83187286
OS 15.01489758 -0.83603338
OS 15.03153966 -0.8401939
OS 15.05095542 -0.8471281
OS 15.06898434 -0.8540623
OS 15.0884001 -0.86377018
OS 15.10781586 -0.8748649
OS 15.12723162 -0.88734646
OS 15.14526054 -0.9026017
OS 15.16190262 -0.91924378
OS 15.16328946 -0.92063062
OS 15.16606314 -0.9234043
OS 15.17022366 -0.92895166
OS 15.17577102 -0.9372727
OS 15.18270522 -0.94698058
OS 15.18963942 -0.9580753
OS 15.19796046 -0.9719437
OS 15.2062815 -0.98858578
OS 15.21460254 -1.0066147
OS 15.22292358 -1.02603046
OS 15.22985778 -1.0482199
OS 15.23679198 -1.07179618
OS 15.24233934 -1.09814614
OS 15.24649986 -1.12588294
OS 15.24927354 -1.15500658
OS 15.25066038 -1.1869039
OS 15.25066038 -1.18829074
OS 15.25066038 -1.1938381
OS 15.25066038 -1.20354598
OS 15.24927354 -1.21741438
OS 14.72920854 -1.21741438
OS 14.72920854 -1.21880122
OS 14.72920854 -1.22296174
OS 14.73059538 -1.2285091
OS 14.73059538 -1.23683014
OS 14.73198222 -1.24653802
OS 14.7347559 -1.25763274
OS 14.73891642 -1.28259586
OS 14.74723746 -1.31033266
OS 14.75833218 -1.34084314
OS 14.77358742 -1.36857994
OS 14.79300318 -1.39354306
OS 14.79439002 -1.39354306
OS 14.79577686 -1.39631674
OS 14.8040979 -1.40325094
OS 14.81657946 -1.41295882
OS 14.83322154 -1.4226667
OS 14.85541098 -1.43376142
OS 14.8803741 -1.4434693
OS 14.9081109 -1.4504035
OS 14.92336614 -1.45179034
OS 14.94000822 -1.45317718
OS 14.95110294 -1.45317718
OS 14.9635845 -1.45179034
OS 14.97883974 -1.44901666
OS 14.99548182 -1.44485614
OS 15.01489758 -1.43930878
OS 15.0329265 -1.43098774
OS 15.05095542 -1.41989302
OS 15.05234226 -1.41850618
OS 15.05927646 -1.41295882
OS 15.0675975 -1.40463778
OS 15.07730538 -1.39354306
OS 15.0884001 -1.37828782
OS 15.10088166 -1.35887206
OS 15.11336322 -1.33668262
OS 15.12445794 -1.31033266
OS 15.24649986 -1.3255879
OS 15.24649986 -1.32697474
OS 15.24511302 -1.32974842
OS 15.24372618 -1.33529578
OS 15.2409525 -1.34361682
OS 15.23679198 -1.35193786
OS 15.23263146 -1.36303258
OS 15.22153674 -1.38660886
OS 15.20766834 -1.41295882
OS 15.18825258 -1.44069562
OS 15.16606314 -1.46704558
OS 15.13832634 -1.4920087
OS 15.1369395 -1.4920087
OS 15.13416582 -1.49478238
OS 15.1300053 -1.49755606
OS 15.12445794 -1.50171658
OS 15.1161369 -1.5058771
OS 15.10781586 -1.51003762
OS 15.09672114 -1.51558498
OS 15.08423958 -1.52113234
OS 15.07037118 -1.5266797
OS 15.05650278 -1.53222706
OS 15.02183178 -1.5405481
OS 14.98300026 -1.5474823
OS 14.94000822 -1.55025598
OS 14.92475298 -1.55025598
OS 14.9150451 -1.54886914
OS 14.90256354 -1.5474823
OS 14.8873083 -1.54470862
OS 14.87066622 -1.54193494
OS 14.8526373 -1.53916126
OS 14.81380578 -1.52806654
OS 14.79300318 -1.5197455
OS 14.77358742 -1.51142446
OS 14.75278482 -1.50032974
OS 14.73336906 -1.48784818
OS 14.71534014 -1.47397978
OS 14.69731122 -1.4573377
OS 14.69592438 -1.45595086
OS 14.6931507 -1.45317718
OS 14.68899018 -1.44762982
OS 14.68344282 -1.43930878
OS 14.67650862 -1.4296009
OS 14.66957442 -1.41850618
OS 14.66125338 -1.40463778
OS 14.65293234 -1.38938254
OS 14.6446113 -1.37135362
OS 14.63629026 -1.35193786
OS 14.62935606 -1.32974842
OS 14.62242186 -1.30617214
OS 14.6168745 -1.28120902
OS 14.61271398 -1.25347222
OS 14.6099403 -1.22434858
OS 14.60855346 -1.1938381
OS 14.60855346 -1.19245126
OS 14.60855346 -1.18551706
OS 14.60855346 -1.17719602
OS 14.6099403 -1.16471446
OS 14.61132714 -1.14945922
OS 14.61271398 -1.13281714
OS 14.61548766 -1.11340138
OS 14.61964818 -1.09398562
OS 14.6307429 -1.04960674
OS 14.6376771 -1.0274173
OS 14.64599814 -1.00384102
OS 14.65709286 -0.98165158
OS 14.66957442 -0.96084898
OS 14.68344282 -0.94004638
OS 14.69869806 -0.92063062
OS 14.7000849 -0.91924378
OS 14.70285858 -0.9164701
OS 14.70840594 -0.91230958
OS 14.71534014 -0.90537538
OS 14.72366118 -0.89844118
OS 14.7347559 -0.89012014
OS 14.74723746 -0.88041226
OS 14.7624927 -0.87209122
OS 14.77774794 -0.86238334
OS 14.79577686 -0.8540623
OS 14.81519262 -0.84574126
OS 14.83599522 -0.83880706
OS 14.85818466 -0.83187286
OS 14.88176094 -0.82771234
OS 14.90672406 -0.82493866
OS 14.93307402 -0.82355182
OS 14.94694242 -0.82355182
OS 14.9566503 -0.82493866
OE
OB 10.66576734 -1.53500074 I
OS 10.54788594 -1.53500074
OS 10.54788594 -0.83880706
OS 10.66576734 -0.83880706
OS 10.66576734 -1.53500074
OE
OB 10.37869146 -0.82493866 I
OS 10.3939467 -0.82771234
OS 10.41197562 -0.8332597
OS 10.43139138 -0.8401939
OS 10.45358082 -0.84990178
OS 10.4771571 -0.86238334
OS 10.43416506 -0.97055686
OS 10.43277822 -0.96917002
OS 10.42723086 -0.96639634
OS 10.41890982 -0.96223582
OS 10.4078151 -0.9580753
OS 10.39533354 -0.95391478
OS 10.3800783 -0.94975426
OS 10.36482306 -0.94698058
OS 10.34956782 -0.94559374
OS 10.34263362 -0.94559374
OS 10.33569942 -0.94698058
OS 10.32599154 -0.94836742
OS 10.31628366 -0.9511411
OS 10.3038021 -0.95530162
OS 10.29132054 -0.96084898
OS 10.28022582 -0.96917002
OS 10.27883898 -0.97055686
OS 10.27467846 -0.97333054
OS 10.27051794 -0.9788779
OS 10.26358374 -0.9858121
OS 10.25664954 -0.99551998
OS 10.24971534 -1.0066147
OS 10.24278114 -1.01909626
OS 10.23723378 -1.0343515
OS 10.23584694 -1.03712518
OS 10.2344601 -1.04544622
OS 10.23168642 -1.05792778
OS 10.2275259 -1.07456986
OS 10.22336538 -1.09537246
OS 10.2205917 -1.11894874
OS 10.21920486 -1.14391186
OS 10.21781802 -1.17164866
OS 10.21781802 -1.53500074
OS 10.09993662 -1.53500074
OS 10.09993662 -0.83880706
OS 10.2067233 -0.83880706
OS 10.2067233 -0.9442069
OS 10.20811014 -0.94282006
OS 10.2136575 -0.93311218
OS 10.2205917 -0.92063062
OS 10.23168642 -0.90537538
OS 10.24278114 -0.89012014
OS 10.2552627 -0.87347806
OS 10.26774426 -0.85960966
OS 10.28022582 -0.84851494
OS 10.28161266 -0.8471281
OS 10.28577318 -0.84435442
OS 10.29409422 -0.8401939
OS 10.30241526 -0.83603338
OS 10.31350998 -0.83187286
OS 10.32737838 -0.82771234
OS 10.34124678 -0.82493866
OS 10.35650202 -0.82355182
OS 10.3662099 -0.82355182
OS 10.37869146 -0.82493866
OE
OB 10.66576734 -0.70983094 I
OS 10.54788594 -0.70983094
OS 10.54788594 -0.57530746
OS 10.66576734 -0.57530746
OS 10.66576734 -0.70983094
OE
OB 8.8406859 -0.56005222 I
OS 8.85316746 -0.56143906
OS 8.8684227 -0.5628259
OS 8.88367794 -0.56421274
OS 8.90170686 -0.56837326
OS 8.93915154 -0.5766943
OS 8.98075674 -0.58917586
OS 9.00155934 -0.5974969
OS 9.0209751 -0.60720478
OS 9.04039086 -0.61968634
OS 9.05980662 -0.6321679
OS 9.06119346 -0.63355474
OS 9.06396714 -0.63494158
OS 9.0695145 -0.6391021
OS 9.0764487 -0.6460363
OS 9.0833829 -0.6529705
OS 9.09309078 -0.66267838
OS 9.10279866 -0.6737731
OS 9.11389338 -0.68486782
OS 9.1249881 -0.69873622
OS 9.13608282 -0.7153783
OS 9.14856438 -0.73202038
OS 9.1596591 -0.7500493
OS 9.16936698 -0.7708519
OS 9.1804617 -0.7916545
OS 9.18878274 -0.81384394
OS 9.19710378 -0.83880706
OS 9.07228818 -0.8679307
OS 9.07228818 -0.86654386
OS 9.07090134 -0.86377018
OS 9.06812766 -0.85822282
OS 9.06535398 -0.85128862
OS 9.0625803 -0.84296758
OS 9.05841978 -0.83187286
OS 9.04732506 -0.80968342
OS 9.03345666 -0.7847203
OS 9.01681458 -0.75975718
OS 8.99601198 -0.7361809
OS 8.97382254 -0.7153783
OS 8.97104886 -0.71260462
OS 8.96272782 -0.70705726
OS 8.94885942 -0.70012306
OS 8.9308305 -0.69041518
OS 8.90725422 -0.68209414
OS 8.88090426 -0.6737731
OS 8.84900694 -0.66822574
OS 8.81433594 -0.6668389
OS 8.80324122 -0.6668389
OS 8.79630702 -0.66822574
OS 8.78659914 -0.66822574
OS 8.77550442 -0.66961258
OS 8.74915446 -0.6737731
OS 8.72003082 -0.67932046
OS 8.68952034 -0.68902834
OS 8.65762302 -0.70289674
OS 8.62849938 -0.72092566
OS 8.62711254 -0.72092566
OS 8.6257257 -0.72369934
OS 8.61601782 -0.73063354
OS 8.60353626 -0.74172826
OS 8.58828102 -0.75837034
OS 8.5702521 -0.77917294
OS 8.55361002 -0.80274922
OS 8.53835478 -0.83187286
OS 8.52448638 -0.86377018
OS 8.52448638 -0.86515702
OS 8.52309954 -0.8679307
OS 8.5217127 -0.87209122
OS 8.52032586 -0.87902542
OS 8.51755218 -0.88734646
OS 8.5147785 -0.89705434
OS 8.51061798 -0.92063062
OS 8.50507062 -0.94836742
OS 8.49952326 -0.9788779
OS 8.49674958 -1.01216206
OS 8.49536274 -1.0482199
OS 8.49536274 -1.04960674
OS 8.49536274 -1.05376726
OS 8.49536274 -1.06070146
OS 8.49536274 -1.0690225
OS 8.49674958 -1.07873038
OS 8.49674958 -1.09121194
OS 8.49813642 -1.10508034
OS 8.49952326 -1.12033558
OS 8.50368378 -1.15361974
OS 8.51061798 -1.18967758
OS 8.51893902 -1.22573542
OS 8.53003374 -1.26179326
OS 8.53003374 -1.2631801
OS 8.53142058 -1.26595378
OS 8.53419426 -1.2701143
OS 8.53696794 -1.2770485
OS 8.54528898 -1.29369058
OS 8.55777054 -1.31310634
OS 8.57302578 -1.33529578
OS 8.59244154 -1.35887206
OS 8.61463098 -1.37967466
OS 8.64098094 -1.39909042
OS 8.64236778 -1.39909042
OS 8.64514146 -1.40047726
OS 8.64930198 -1.40325094
OS 8.65484934 -1.40602462
OS 8.66178354 -1.4087983
OS 8.67010458 -1.41295882
OS 8.68952034 -1.42127986
OS 8.71448346 -1.4296009
OS 8.74222026 -1.4365351
OS 8.77273074 -1.44208246
OS 8.80462806 -1.4434693
OS 8.81433594 -1.4434693
OS 8.82265698 -1.44208246
OS 8.83236486 -1.44208246
OS 8.84207274 -1.44069562
OS 8.86703586 -1.43514826
OS 8.8961595 -1.42821406
OS 8.92528314 -1.41711934
OS 8.95579362 -1.4018641
OS 8.97104886 -1.39354306
OS 8.98491726 -1.38244834
OS 8.9863041 -1.3810615
OS 8.98769094 -1.37967466
OS 8.99185146 -1.37551414
OS 8.99739882 -1.37135362
OS 9.00294618 -1.36441942
OS 9.00988038 -1.35609838
OS 9.01820142 -1.34777734
OS 9.02513562 -1.33668262
OS 9.03345666 -1.32420106
OS 9.04316454 -1.31033266
OS 9.05148558 -1.29646426
OS 9.05980662 -1.27982218
OS 9.06674082 -1.26179326
OS 9.07367502 -1.2423775
OS 9.08060922 -1.2215749
OS 9.08615658 -1.19938546
OS 9.21374586 -1.23128278
OS 9.21374586 -1.23266962
OS 9.21235902 -1.23821698
OS 9.20958534 -1.24653802
OS 9.20542482 -1.25763274
OS 9.2012643 -1.2701143
OS 9.19571694 -1.28536954
OS 9.18878274 -1.30201162
OS 9.1804617 -1.32004054
OS 9.16104594 -1.35887206
OS 9.13608282 -1.39770358
OS 9.12082758 -1.41711934
OS 9.10557234 -1.4365351
OS 9.08893026 -1.45317718
OS 9.0695145 -1.46981926
OS 9.06812766 -1.4712061
OS 9.06535398 -1.47397978
OS 9.05841978 -1.47675346
OS 9.05148558 -1.48230082
OS 9.04039086 -1.48923502
OS 9.02929614 -1.49616922
OS 9.0140409 -1.50310342
OS 8.99878566 -1.51003762
OS 8.98075674 -1.51835866
OS 8.96134098 -1.52529286
OS 8.94053838 -1.53222706
OS 8.91834894 -1.53916126
OS 8.89477266 -1.54470862
OS 8.86980954 -1.5474823
OS 8.84345958 -1.55025598
OS 8.81572278 -1.55164282
OS 8.80046754 -1.55164282
OS 8.78937282 -1.55025598
OS 8.77689126 -1.55025598
OS 8.76163602 -1.54886914
OS 8.74499394 -1.54609546
OS 8.72557818 -1.54332178
OS 8.68535982 -1.53638758
OS 8.64375462 -1.52529286
OS 8.60214942 -1.51003762
OS 8.58273366 -1.50032974
OS 8.5633179 -1.48923502
OS 8.56193106 -1.48784818
OS 8.55915738 -1.48646134
OS 8.55361002 -1.48230082
OS 8.54806266 -1.47675346
OS 8.53974162 -1.4712061
OS 8.53003374 -1.46288506
OS 8.51893902 -1.45317718
OS 8.5078443 -1.44208246
OS 8.49674958 -1.4296009
OS 8.48426802 -1.41711934
OS 8.4593049 -1.38522202
OS 8.43572862 -1.34777734
OS 8.41492602 -1.30617214
OS 8.41492602 -1.3047853
OS 8.41215234 -1.30062478
OS 8.4107655 -1.29369058
OS 8.40660498 -1.28536954
OS 8.4038313 -1.27427482
OS 8.39967078 -1.26040642
OS 8.39412342 -1.24515118
OS 8.3899629 -1.2285091
OS 8.38580238 -1.21048018
OS 8.38025502 -1.18967758
OS 8.37332082 -1.14668554
OS 8.36777346 -1.09814614
OS 8.36499978 -1.0482199
OS 8.36499978 -1.04683306
OS 8.36499978 -1.0412857
OS 8.36499978 -1.03296466
OS 8.36638662 -1.02325678
OS 8.36638662 -1.00938838
OS 8.36777346 -0.99551998
OS 8.3691603 -0.97749106
OS 8.37193398 -0.95946214
OS 8.37886818 -0.91924378
OS 8.38857606 -0.8748649
OS 8.40244446 -0.83048602
OS 8.42186022 -0.78749398
OS 8.42324706 -0.78610714
OS 8.4246339 -0.78194662
OS 8.42740758 -0.77639926
OS 8.43295494 -0.76946506
OS 8.4385023 -0.75975718
OS 8.4454365 -0.74866246
OS 8.46346542 -0.72369934
OS 8.4870417 -0.69596254
OS 8.5147785 -0.66822574
OS 8.54667582 -0.64048894
OS 8.5841205 -0.61691266
OS 8.58550734 -0.61552582
OS 8.58966786 -0.61413898
OS 8.59521522 -0.6113653
OS 8.60214942 -0.60720478
OS 8.61324414 -0.60304426
OS 8.62433886 -0.59888374
OS 8.63820726 -0.59333638
OS 8.6534625 -0.58778902
OS 8.67010458 -0.58224166
OS 8.6881335 -0.5766943
OS 8.72696502 -0.56837326
OS 8.7713439 -0.56143906
OS 8.81710962 -0.55866538
OS 8.83097802 -0.55866538
OS 8.8406859 -0.56005222
OE
OB 11.10262194 -0.82493866 I
OS 11.12342454 -0.8263255
OS 11.14561398 -0.82909918
OS 11.16919026 -0.83464654
OS 11.19415338 -0.8401939
OS 11.21772966 -0.84851494
OS 11.2191165 -0.84851494
OS 11.22050334 -0.84990178
OS 11.22743754 -0.85267546
OS 11.23853226 -0.85822282
OS 11.25240066 -0.86515702
OS 11.2676559 -0.8748649
OS 11.28291114 -0.88595962
OS 11.29677954 -0.89844118
OS 11.3092611 -0.91230958
OS 11.31064794 -0.91369642
OS 11.31342162 -0.91924378
OS 11.31896898 -0.92895166
OS 11.32590318 -0.94004638
OS 11.33283738 -0.95668846
OS 11.33977158 -0.97471738
OS 11.34531894 -0.99551998
OS 11.3508663 -1.01909626
OS 11.23575858 -1.0343515
OS 11.23575858 -1.03157782
OS 11.23437174 -1.02603046
OS 11.23159806 -1.01632258
OS 11.22743754 -1.00384102
OS 11.22050334 -0.99135946
OS 11.2121823 -0.97749106
OS 11.20247442 -0.96362266
OS 11.18860602 -0.9511411
OS 11.18721918 -0.94975426
OS 11.18167182 -0.94698058
OS 11.17335078 -0.94143322
OS 11.16086922 -0.93588586
OS 11.14700082 -0.9303385
OS 11.1289719 -0.92479114
OS 11.10678246 -0.92201746
OS 11.08320618 -0.92063062
OS 11.06933778 -0.92063062
OS 11.05546938 -0.92201746
OS 11.03744046 -0.9234043
OS 11.01941154 -0.92756482
OS 10.99999578 -0.93172534
OS 10.98196686 -0.93865954
OS 10.96671162 -0.94836742
OS 10.96532478 -0.94975426
OS 10.96116426 -0.95252794
OS 10.9556169 -0.9580753
OS 10.95006954 -0.96639634
OS 10.94313534 -0.97471738
OS 10.93758798 -0.9858121
OS 10.93342746 -0.99829366
OS 10.93204062 -1.01077522
OS 10.93204062 -1.01216206
OS 10.93204062 -1.01493574
OS 10.93342746 -1.01909626
OS 10.93342746 -1.02464362
OS 10.93758798 -1.03851202
OS 10.94590902 -1.05238042
OS 10.94729586 -1.05376726
OS 10.9486827 -1.0551541
OS 10.95145638 -1.05931462
OS 10.95700374 -1.06347514
OS 10.9625511 -1.06763566
OS 10.97087214 -1.07318302
OS 10.98058002 -1.07734354
OS 10.99167474 -1.0828909
OS 10.99306158 -1.0828909
OS 10.99583526 -1.08427774
OS 11.00138262 -1.08566458
OS 11.0110905 -1.0898251
OS 11.0249589 -1.09398562
OS 11.04298782 -1.09814614
OS 11.05408254 -1.10230666
OS 11.0665641 -1.10508034
OS 11.0804325 -1.10924086
OS 11.09568774 -1.11340138
OS 11.09707458 -1.11340138
OS 11.1012351 -1.11478822
OS 11.1081693 -1.11617506
OS 11.11649034 -1.11894874
OS 11.12619822 -1.12172242
OS 11.13867978 -1.1244961
OS 11.16502974 -1.13281714
OS 11.19415338 -1.14113818
OS 11.22327702 -1.15084606
OS 11.24962698 -1.16055394
OS 11.2607217 -1.16471446
OS 11.27042958 -1.16887498
OS 11.27320326 -1.17026182
OS 11.27875062 -1.1730355
OS 11.28707166 -1.17719602
OS 11.29955322 -1.18413022
OS 11.31203478 -1.19245126
OS 11.32451634 -1.20354598
OS 11.3369979 -1.21602754
OS 11.34809262 -1.22989594
OS 11.34947946 -1.23128278
OS 11.35225314 -1.23683014
OS 11.3578005 -1.24515118
OS 11.36334786 -1.25763274
OS 11.36750838 -1.27288798
OS 11.37305574 -1.28953006
OS 11.37582942 -1.30894582
OS 11.37721626 -1.33113526
OS 11.37721626 -1.33390894
OS 11.37721626 -1.34084314
OS 11.37582942 -1.35193786
OS 11.37305574 -1.3671931
OS 11.36889522 -1.38383518
OS 11.36196102 -1.4018641
OS 11.35363998 -1.4226667
OS 11.34254526 -1.44208246
OS 11.34115842 -1.44485614
OS 11.33561106 -1.4504035
OS 11.32867686 -1.46011138
OS 11.31758214 -1.4712061
OS 11.3023269 -1.48368766
OS 11.28568482 -1.49755606
OS 11.26626906 -1.51003762
OS 11.24269278 -1.52251918
OS 11.24130594 -1.52251918
OS 11.2399191 -1.52390602
OS 11.23159806 -1.5266797
OS 11.21772966 -1.53084022
OS 11.19970074 -1.53638758
OS 11.1775113 -1.54193494
OS 11.15254818 -1.54609546
OS 11.12619822 -1.54886914
OS 11.09568774 -1.55025598
OS 11.08320618 -1.55025598
OS 11.0734983 -1.54886914
OS 11.06240358 -1.54886914
OS 11.04853518 -1.5474823
OS 11.03466678 -1.54609546
OS 11.01941154 -1.54332178
OS 10.98612738 -1.53638758
OS 10.95145638 -1.5266797
OS 10.91817222 -1.5128113
OS 10.90291698 -1.50449026
OS 10.88904858 -1.49478238
OS 10.88766174 -1.49339554
OS 10.8862749 -1.4920087
OS 10.87795386 -1.48368766
OS 10.8654723 -1.4712061
OS 10.8516039 -1.45179034
OS 10.83634866 -1.42821406
OS 10.82109342 -1.40047726
OS 10.80861186 -1.36580626
OS 10.79890398 -1.32697474
OS 10.91539854 -1.30894582
OS 10.91539854 -1.31033266
OS 10.91539854 -1.3117195
OS 10.91817222 -1.32004054
OS 10.9209459 -1.33390894
OS 10.92649326 -1.34916418
OS 10.93342746 -1.36580626
OS 10.9417485 -1.38383518
OS 10.95423006 -1.4018641
OS 10.9694853 -1.41711934
OS 10.97225898 -1.41850618
OS 10.97780634 -1.4226667
OS 10.98890106 -1.42821406
OS 11.00276946 -1.43514826
OS 11.02079838 -1.44208246
OS 11.04160098 -1.44762982
OS 11.0665641 -1.45179034
OS 11.09568774 -1.45317718
OS 11.10955614 -1.45317718
OS 11.12342454 -1.45179034
OS 11.14145346 -1.44901666
OS 11.16086922 -1.44485614
OS 11.18167182 -1.43930878
OS 11.19970074 -1.43237458
OS 11.21634282 -1.42127986
OS 11.21772966 -1.41989302
OS 11.22327702 -1.4157325
OS 11.22882438 -1.4087983
OS 11.23714542 -1.39909042
OS 11.24407962 -1.3879957
OS 11.25101382 -1.3741273
OS 11.25517434 -1.3602589
OS 11.25656118 -1.34361682
OS 11.25656118 -1.34222998
OS 11.25656118 -1.33668262
OS 11.25517434 -1.32974842
OS 11.25240066 -1.32004054
OS 11.24824014 -1.31033266
OS 11.24130594 -1.30062478
OS 11.2329849 -1.28953006
OS 11.22050334 -1.28120902
OS 11.2191165 -1.27982218
OS 11.21495598 -1.27843534
OS 11.20802178 -1.27427482
OS 11.19692706 -1.2701143
OS 11.18028498 -1.26456694
OS 11.1705771 -1.26040642
OS 11.15948238 -1.25763274
OS 11.14700082 -1.25347222
OS 11.13313242 -1.2493117
OS 11.11787718 -1.24515118
OS 11.09984826 -1.24099066
OS 11.09846142 -1.24099066
OS 11.0943009 -1.23960382
OS 11.0873667 -1.23821698
OS 11.07904566 -1.2354433
OS 11.06795094 -1.23266962
OS 11.05546938 -1.2285091
OS 11.02911942 -1.2215749
OS 10.99860894 -1.21186702
OS 10.9694853 -1.20354598
OS 10.9417485 -1.1938381
OS 10.92926694 -1.18829074
OS 10.91955906 -1.18413022
OS 10.91678538 -1.18274338
OS 10.91123802 -1.1799697
OS 10.90291698 -1.17442234
OS 10.89182226 -1.16748814
OS 10.8793407 -1.15778026
OS 10.86685914 -1.14668554
OS 10.85437758 -1.13420398
OS 10.84328286 -1.11894874
OS 10.84189602 -1.1175619
OS 10.83912234 -1.11201454
OS 10.83496182 -1.10230666
OS 10.8308013 -1.09121194
OS 10.82664078 -1.07734354
OS 10.82248026 -1.06070146
OS 10.81970658 -1.04405938
OS 10.81831974 -1.02464362
OS 10.81831974 -1.02186994
OS 10.81831974 -1.01632258
OS 10.81970658 -1.00800154
OS 10.82109342 -0.99551998
OS 10.8238671 -0.98303842
OS 10.82664078 -0.96778318
OS 10.83218814 -0.95391478
OS 10.83912234 -0.93865954
OS 10.84050918 -0.9372727
OS 10.84328286 -0.93172534
OS 10.84744338 -0.92479114
OS 10.85437758 -0.91508326
OS 10.86269862 -0.90537538
OS 10.8724065 -0.89289382
OS 10.88350122 -0.8817991
OS 10.89736962 -0.87209122
OS 10.89875646 -0.87070438
OS 10.90291698 -0.86931754
OS 10.90846434 -0.86515702
OS 10.91678538 -0.8609965
OS 10.9278801 -0.85544914
OS 10.94036166 -0.84990178
OS 10.9556169 -0.84435442
OS 10.97225898 -0.83880706
OS 10.97503266 -0.83742022
OS 10.98058002 -0.83603338
OS 10.9902879 -0.8332597
OS 11.00276946 -0.83048602
OS 11.0180247 -0.82771234
OS 11.03466678 -0.8263255
OS 11.05408254 -0.82355182
OS 11.0873667 -0.82355182
OS 11.10262194 -0.82493866
OE
OB 9.47308494 -0.91924378 I
OS 9.47447178 -0.91785694
OS 9.47724546 -0.91508326
OS 9.48140598 -0.91092274
OS 9.48834018 -0.90398854
OS 9.49527438 -0.89705434
OS 9.50498226 -0.8887333
OS 9.51746382 -0.88041226
OS 9.52994538 -0.87070438
OS 9.54381378 -0.86238334
OS 9.55906902 -0.8540623
OS 9.59512686 -0.83880706
OS 9.61454262 -0.83187286
OS 9.63534522 -0.82771234
OS 9.65753466 -0.82493866
OS 9.6797241 -0.82355182
OS 9.69220566 -0.82355182
OS 9.7074609 -0.82493866
OS 9.72548982 -0.82771234
OS 9.74629242 -0.83048602
OS 9.76848186 -0.83603338
OS 9.7906713 -0.84435442
OS 9.81286074 -0.8540623
OS 9.81563442 -0.85544914
OS 9.82256862 -0.85960966
OS 9.8322765 -0.86654386
OS 9.84475806 -0.87625174
OS 9.85723962 -0.8887333
OS 9.87110802 -0.9026017
OS 9.88358958 -0.91924378
OS 9.8946843 -0.93865954
OS 9.89607114 -0.94143322
OS 9.89884482 -0.94836742
OS 9.90300534 -0.96084898
OS 9.90716586 -0.9788779
OS 9.91132638 -1.00106734
OS 9.9154869 -1.0274173
OS 9.91826058 -1.05931462
OS 9.91964742 -1.09537246
OS 9.91964742 -1.53500074
OS 9.80176602 -1.53500074
OS 9.80176602 -1.09398562
OS 9.80176602 -1.09259878
OS 9.80176602 -1.0898251
OS 9.80176602 -1.08566458
OS 9.80176602 -1.08011722
OS 9.80037918 -1.06486198
OS 9.7976055 -1.04544622
OS 9.79205814 -1.02464362
OS 9.78512394 -1.00384102
OS 9.77541606 -0.98303842
OS 9.7629345 -0.96639634
OS 9.76154766 -0.9650095
OS 9.7560003 -0.95946214
OS 9.74767926 -0.95252794
OS 9.7351977 -0.94559374
OS 9.71994246 -0.9372727
OS 9.70191354 -0.93172534
OS 9.6797241 -0.92617798
OS 9.65476098 -0.92479114
OS 9.64643994 -0.92479114
OS 9.63673206 -0.92617798
OS 9.62286366 -0.92756482
OS 9.60899526 -0.93172534
OS 9.59235318 -0.93588586
OS 9.5757111 -0.94282006
OS 9.55768218 -0.95252794
OS 9.55629534 -0.95391478
OS 9.55074798 -0.9580753
OS 9.54242694 -0.96362266
OS 9.53271906 -0.9719437
OS 9.52162434 -0.98303842
OS 9.51052962 -0.99551998
OS 9.50082174 -1.01077522
OS 9.4925007 -1.0274173
OS 9.49111386 -1.03019098
OS 9.48972702 -1.03573834
OS 9.48695334 -1.04683306
OS 9.48279282 -1.06070146
OS 9.4786323 -1.07873038
OS 9.47585862 -1.10091982
OS 9.47447178 -1.12588294
OS 9.47308494 -1.15500658
OS 9.47308494 -1.53500074
OS 9.35520354 -1.53500074
OS 9.35520354 -0.57530746
OS 9.47308494 -0.57530746
OS 9.47308494 -0.91924378
OE
OB 14.93446086 -0.92063062 H
OS 14.92613982 -0.92063062
OS 14.92059246 -0.92201746
OS 14.90533722 -0.9234043
OS 14.8873083 -0.92756482
OS 14.86511886 -0.93449902
OS 14.84154258 -0.9442069
OS 14.81935314 -0.9580753
OS 14.7971637 -0.97610422
OS 14.79439002 -0.9788779
OS 14.78884266 -0.9858121
OS 14.77913478 -0.99829366
OS 14.7694269 -1.01493574
OS 14.75833218 -1.0343515
OS 14.7486243 -1.05931462
OS 14.74030326 -1.08843826
OS 14.73614274 -1.12033558
OS 15.12584478 -1.12033558
OS 15.12584478 -1.11894874
OS 15.12584478 -1.11617506
OS 15.12445794 -1.11201454
OS 15.12445794 -1.10646718
OS 15.12168426 -1.0898251
OS 15.11752374 -1.07179618
OS 15.11058954 -1.04960674
OS 15.10365534 -1.02880414
OS 15.09256062 -1.00800154
OS 15.08007906 -0.98997262
OS 15.08007906 -0.98858578
OS 15.07730538 -0.98719894
OS 15.07037118 -0.9788779
OS 15.05788962 -0.96778318
OS 15.04124754 -0.95530162
OS 15.02044494 -0.94282006
OS 14.99548182 -0.93172534
OS 14.96635818 -0.9234043
OS 14.95110294 -0.92201746
OS 14.93446086 -0.92063062
OE
OB 12.33690954 -0.68209414 H
OS 12.03457842 -0.68209414
OS 12.03457842 -0.9996805
OS 12.32026746 -0.9996805
OS 12.33690954 -0.99829366
OS 12.3563253 -0.99690682
OS 12.37851474 -0.99551998
OS 12.40070418 -0.9927463
OS 12.42289362 -0.98858578
OS 12.44230938 -0.98303842
OS 12.44508306 -0.98165158
OS 12.45063042 -0.9788779
OS 12.45895146 -0.97471738
OS 12.47004618 -0.96917002
OS 12.48252774 -0.96084898
OS 12.4950093 -0.9511411
OS 12.50749086 -0.93865954
OS 12.51719874 -0.92479114
OS 12.51858558 -0.9234043
OS 12.52135926 -0.91785694
OS 12.52551978 -0.9095359
OS 12.53106714 -0.89844118
OS 12.53522766 -0.88595962
OS 12.53938818 -0.87209122
OS 12.54216186 -0.85544914
OS 12.5435487 -0.83880706
OS 12.5435487 -0.83742022
OS 12.5435487 -0.83603338
OS 12.54216186 -0.82771234
OS 12.54077502 -0.81523078
OS 12.53800134 -0.7985887
OS 12.53106714 -0.78194662
OS 12.5227461 -0.76253086
OS 12.51026454 -0.74450194
OS 12.49362246 -0.72647302
OS 12.49084878 -0.72508618
OS 12.48391458 -0.71953882
OS 12.47281986 -0.71260462
OS 12.45479094 -0.70428358
OS 12.43398834 -0.69596254
OS 12.40625154 -0.68902834
OS 12.37435422 -0.68348098
OS 12.33690954 -0.68209414
OE
OB 13.1398899 -0.92063062 H
OS 13.13156886 -0.92063062
OS 13.12463466 -0.92201746
OS 13.10937942 -0.9234043
OS 13.08857682 -0.92895166
OS 13.06500054 -0.9372727
OS 13.04003742 -0.94836742
OS 13.01646114 -0.9650095
OS 13.00397958 -0.97610422
OS 12.99288486 -0.98719894
OS 12.99288486 -0.98858578
OS 12.99011118 -0.98997262
OS 12.9873375 -0.99413314
OS 12.98317698 -0.9996805
OS 12.97901646 -1.0066147
OS 12.97485594 -1.01493574
OS 12.96930858 -1.02603046
OS 12.96376122 -1.03712518
OS 12.95821386 -1.05099358
OS 12.9526665 -1.06486198
OS 12.94850598 -1.08150406
OS 12.94434546 -1.09953298
OS 12.94018494 -1.11894874
OS 12.93741126 -1.13975134
OS 12.93602442 -1.16332762
OS 12.93463758 -1.1869039
OS 12.93463758 -1.18829074
OS 12.93463758 -1.19245126
OS 12.93463758 -1.19938546
OS 12.93602442 -1.20909334
OS 12.93602442 -1.22018806
OS 12.93741126 -1.23266962
OS 12.94157178 -1.26179326
OS 12.94850598 -1.29507742
OS 12.9596007 -1.32836158
OS 12.9734691 -1.3602589
OS 12.98317698 -1.3741273
OS 12.99288486 -1.3879957
OS 12.9942717 -1.3879957
OS 12.99565854 -1.39076938
OS 13.00397958 -1.39770358
OS 13.01646114 -1.4087983
OS 13.03310322 -1.41989302
OS 13.05390582 -1.43237458
OS 13.07886894 -1.4434693
OS 13.10799258 -1.4504035
OS 13.12324782 -1.45179034
OS 13.1398899 -1.45317718
OS 13.14821094 -1.45317718
OS 13.15514514 -1.45179034
OS 13.17040038 -1.44901666
OS 13.19120298 -1.44485614
OS 13.21339242 -1.4365351
OS 13.23835554 -1.42544038
OS 13.26193182 -1.4087983
OS 13.27441338 -1.39770358
OS 13.2855081 -1.38660886
OS 13.28689494 -1.38522202
OS 13.28828178 -1.38383518
OS 13.29105546 -1.37967466
OS 13.29521598 -1.3741273
OS 13.2993765 -1.3671931
OS 13.30492386 -1.35887206
OS 13.31047122 -1.34777734
OS 13.31601858 -1.33668262
OS 13.32156594 -1.32281422
OS 13.32572646 -1.30755898
OS 13.33127382 -1.2909169
OS 13.33543434 -1.27288798
OS 13.33959486 -1.25208538
OS 13.34236854 -1.23128278
OS 13.34514222 -1.2077065
OS 13.34514222 -1.18274338
OS 13.34514222 -1.18135654
OS 13.34514222 -1.17719602
OS 13.34514222 -1.17026182
OS 13.34375538 -1.16194078
OS 13.34375538 -1.15084606
OS 13.34236854 -1.1383645
OS 13.33820802 -1.10924086
OS 13.33127382 -1.07873038
OS 13.3201791 -1.04544622
OS 13.30492386 -1.01493574
OS 13.29660282 -0.9996805
OS 13.2855081 -0.98719894
OS 13.2855081 -0.9858121
OS 13.28273442 -0.98442526
OS 13.27441338 -0.97610422
OS 13.26193182 -0.96639634
OS 13.24528974 -0.95391478
OS 13.22448714 -0.94143322
OS 13.19952402 -0.9303385
OS 13.17178722 -0.9234043
OS 13.15653198 -0.92201746
OS 13.1398899 -0.92063062
OE
OB 13.91235978 -0.92063062 H
OS 13.89155718 -0.92063062
OS 13.88600982 -0.92201746
OS 13.87075458 -0.92479114
OS 13.85272566 -0.92895166
OS 13.83192306 -0.9372727
OS 13.80973362 -0.94975426
OS 13.7986389 -0.95668846
OS 13.78754418 -0.96639634
OS 13.77644946 -0.97610422
OS 13.76535474 -0.98858578
OS 13.76535474 -0.98997262
OS 13.76258106 -0.99135946
OS 13.75980738 -0.99551998
OS 13.7570337 -1.00106734
OS 13.75287318 -1.00800154
OS 13.74732582 -1.01632258
OS 13.7431653 -1.02603046
OS 13.73761794 -1.03712518
OS 13.73207058 -1.05099358
OS 13.72791006 -1.06486198
OS 13.7223627 -1.08150406
OS 13.71820218 -1.09814614
OS 13.7154285 -1.1175619
OS 13.71265482 -1.1383645
OS 13.70988114 -1.1591671
OS 13.70988114 -1.18274338
OS 13.70988114 -1.18413022
OS 13.70988114 -1.18829074
OS 13.70988114 -1.19522494
OS 13.70988114 -1.20354598
OS 13.71126798 -1.21325386
OS 13.71126798 -1.22573542
OS 13.71404166 -1.25208538
OS 13.71820218 -1.28120902
OS 13.72374954 -1.3117195
OS 13.73207058 -1.3394563
OS 13.73761794 -1.35193786
OS 13.7431653 -1.36303258
OS 13.7431653 -1.36441942
OS 13.74593898 -1.3671931
OS 13.74871266 -1.37135362
OS 13.75287318 -1.37690098
OS 13.76535474 -1.39215622
OS 13.78338366 -1.40741146
OS 13.80418626 -1.42405354
OS 13.83053622 -1.43930878
OS 13.84440462 -1.44485614
OS 13.8610467 -1.44901666
OS 13.87630194 -1.45179034
OS 13.89433086 -1.45317718
OS 13.90126506 -1.45317718
OS 13.90681242 -1.45179034
OS 13.92206766 -1.44901666
OS 13.94009658 -1.44485614
OS 13.96089918 -1.4365351
OS 13.98308862 -1.42544038
OS 14.00527806 -1.4087983
OS 14.01637278 -1.39770358
OS 14.0274675 -1.38660886
OS 14.0274675 -1.38522202
OS 14.03024118 -1.38383518
OS 14.03301486 -1.37967466
OS 14.03578854 -1.3741273
OS 14.0413359 -1.3671931
OS 14.04549642 -1.35887206
OS 14.05104378 -1.34777734
OS 14.05659114 -1.33668262
OS 14.06075166 -1.32281422
OS 14.06629902 -1.30894582
OS 14.07184638 -1.29230374
OS 14.0760069 -1.27427482
OS 14.07878058 -1.25485906
OS 14.08155426 -1.23405646
OS 14.08432794 -1.21048018
OS 14.08432794 -1.1869039
OS 14.08432794 -1.18551706
OS 14.08432794 -1.18135654
OS 14.08432794 -1.17442234
OS 14.0829411 -1.16471446
OS 14.0829411 -1.15361974
OS 14.08155426 -1.13975134
OS 14.07739374 -1.1106277
OS 14.07184638 -1.07873038
OS 14.0621385 -1.04405938
OS 14.0482701 -1.0135489
OS 14.03994906 -0.99829366
OS 14.03024118 -0.9858121
OS 14.03024118 -0.98442526
OS 14.0274675 -0.98303842
OS 14.0205333 -0.97610422
OS 14.00943858 -0.9650095
OS 13.99418334 -0.95252794
OS 13.97476758 -0.94143322
OS 13.95257814 -0.9303385
OS 13.92622818 -0.9234043
OS 13.91235978 -0.92063062
OE
SE
S P 0
OB 35.73690338 -37.45999874 I
OS 35.61486146 -37.45999874
OS 35.61486146 -36.65701838
OS 35.33471978 -37.45999874
OS 35.2209989 -37.45999874
OS 34.9436309 -36.64314998
OS 34.9436309 -37.45999874
OS 34.82158898 -37.45999874
OS 34.82158898 -36.50030546
OS 35.01158606 -36.50030546
OS 35.23902782 -37.1812439
OS 35.23902782 -37.18263074
OS 35.24041466 -37.18540442
OS 35.2418015 -37.18956494
OS 35.24457518 -37.19649914
OS 35.25012254 -37.21314122
OS 35.25705674 -37.23394382
OS 35.26399094 -37.2575201
OS 35.27231198 -37.28109638
OS 35.27924618 -37.30328582
OS 35.28479354 -37.32270158
OS 35.28618038 -37.3199279
OS 35.28756722 -37.3129937
OS 35.29172774 -37.30051214
OS 35.2972751 -37.28387006
OS 35.3042093 -37.26168062
OS 35.31391718 -37.23533066
OS 35.32362506 -37.20482018
OS 35.33610662 -37.16876234
OS 35.56632206 -36.50030546
OS 35.73690338 -36.50030546
OS 35.73690338 -37.45999874
OE
OB 34.61356298 -37.05504146 I
OS 34.61356298 -37.0564283
OS 34.61356298 -37.06197566
OS 34.61356298 -37.06890986
OS 34.61356298 -37.07861774
OS 34.61217614 -37.0910993
OS 34.61217614 -37.1049677
OS 34.6107893 -37.12160978
OS 34.60940246 -37.13825186
OS 34.60524194 -37.17569654
OS 34.59969458 -37.21452806
OS 34.59137354 -37.25197274
OS 34.58582618 -37.27000166
OS 34.58027882 -37.28664374
OS 34.58027882 -37.28803058
OS 34.57889198 -37.29080426
OS 34.5761183 -37.29496478
OS 34.57334462 -37.30051214
OS 34.56502358 -37.31576738
OS 34.55254202 -37.33518314
OS 34.53589994 -37.35737258
OS 34.51648418 -37.37956202
OS 34.49152106 -37.4031383
OS 34.46101058 -37.4239409
OS 34.45962374 -37.4239409
OS 34.45685006 -37.42671458
OS 34.45268954 -37.42810142
OS 34.44575534 -37.43226194
OS 34.4374343 -37.43642246
OS 34.42633958 -37.44058298
OS 34.41524486 -37.4447435
OS 34.40137646 -37.45029086
OS 34.38612122 -37.45583822
OS 34.36947914 -37.45999874
OS 34.35145022 -37.46415926
OS 34.33064762 -37.46831978
OS 34.30984502 -37.47109346
OS 34.28765558 -37.47386714
OS 34.23772934 -37.47664082
OS 34.22524778 -37.47664082
OS 34.2155399 -37.47525398
OS 34.20444518 -37.47525398
OS 34.19057678 -37.47386714
OS 34.17532154 -37.4724803
OS 34.1600663 -37.47109346
OS 34.1253953 -37.4655461
OS 34.08795062 -37.45722506
OS 34.05189278 -37.44613034
OS 34.01722178 -37.4308751
OS 34.01583494 -37.4308751
OS 34.01306126 -37.42810142
OS 34.00890074 -37.42532774
OS 34.00335338 -37.42255406
OS 33.98809814 -37.41145934
OS 33.97006922 -37.3962041
OS 33.94926662 -37.37678834
OS 33.92985086 -37.3545989
OS 33.9104351 -37.3268621
OS 33.89517986 -37.29635162
OS 33.89517986 -37.29496478
OS 33.89379302 -37.2921911
OS 33.89240618 -37.28664374
OS 33.8896325 -37.27970954
OS 33.88685882 -37.2713885
OS 33.88408514 -37.26029378
OS 33.87992462 -37.24781222
OS 33.87715094 -37.23255698
OS 33.87437726 -37.2159149
OS 33.87021674 -37.19788598
OS 33.86744306 -37.17847022
OS 33.86466938 -37.15766762
OS 33.8618957 -37.13409134
OS 33.86050886 -37.10912822
OS 33.85912202 -37.08277826
OS 33.85912202 -37.05504146
OS 33.85912202 -36.50030546
OS 33.9867113 -36.50030546
OS 33.9867113 -37.05504146
OS 33.9867113 -37.0564283
OS 33.9867113 -37.06058882
OS 33.9867113 -37.06752302
OS 33.9867113 -37.07584406
OS 33.98809814 -37.08555194
OS 33.98809814 -37.0980335
OS 33.98948498 -37.12438346
OS 33.99225866 -37.15489394
OS 33.99641918 -37.18540442
OS 34.00196654 -37.21452806
OS 34.00474022 -37.22700962
OS 34.00890074 -37.23949118
OS 34.01028758 -37.24226486
OS 34.01306126 -37.24919906
OS 34.01999546 -37.25890694
OS 34.0283165 -37.27277534
OS 34.03802438 -37.28664374
OS 34.05189278 -37.30189898
OS 34.06853486 -37.31715422
OS 34.08795062 -37.32963578
OS 34.0907243 -37.33102262
OS 34.0976585 -37.33518314
OS 34.11014006 -37.33934366
OS 34.12678214 -37.34489102
OS 34.1461979 -37.35182522
OS 34.17116102 -37.35598574
OS 34.19751098 -37.36014626
OS 34.22663462 -37.3615331
OS 34.24050302 -37.3615331
OS 34.24882406 -37.36014626
OS 34.26130562 -37.36014626
OS 34.27378718 -37.35875942
OS 34.30429766 -37.35321206
OS 34.33758182 -37.34627786
OS 34.36947914 -37.33518314
OS 34.39998962 -37.3199279
OS 34.41385802 -37.31022002
OS 34.42633958 -37.2991253
OS 34.42772642 -37.29773846
OS 34.42911326 -37.29635162
OS 34.43188694 -37.2921911
OS 34.43604746 -37.28664374
OS 34.44020798 -37.2783227
OS 34.44575534 -37.27000166
OS 34.4513027 -37.2575201
OS 34.45685006 -37.24503854
OS 34.46239742 -37.2297833
OS 34.46655794 -37.21175438
OS 34.4721053 -37.19095178
OS 34.47626582 -37.16876234
OS 34.48042634 -37.14379922
OS 34.48320002 -37.11744926
OS 34.4859737 -37.08693878
OS 34.4859737 -37.05504146
OS 34.4859737 -36.50030546
OS 34.61356298 -36.50030546
OS 34.61356298 -37.05504146
OE
OB 33.64416182 -37.45999874 I
OS 33.51241202 -37.45999874
OS 33.01037594 -36.70694462
OS 33.01037594 -37.45999874
OS 32.88833402 -37.45999874
OS 32.88833402 -36.50030546
OS 33.01869698 -36.50030546
OS 33.5221199 -37.25474642
OS 33.5221199 -36.50030546
OS 33.64416182 -36.50030546
OS 33.64416182 -37.45999874
OE
OB 38.19022334 -36.5016923 I
OS 38.2027049 -36.5016923
OS 38.23182854 -36.50307914
OS 38.26233902 -36.50723966
OS 38.29562318 -36.51140018
OS 38.32613366 -36.51833438
OS 38.3413889 -36.5224949
OS 38.35387046 -36.52665542
OS 38.3552573 -36.52665542
OS 38.35664414 -36.52804226
OS 38.36496518 -36.53220278
OS 38.37744674 -36.53775014
OS 38.39270198 -36.54745802
OS 38.40934406 -36.55993958
OS 38.42737298 -36.57658166
OS 38.44401506 -36.59599742
OS 38.46065714 -36.61818686
OS 38.46065714 -36.6195737
OS 38.46204398 -36.62096054
OS 38.46759134 -36.62928158
OS 38.4731387 -36.64314998
OS 38.48145974 -36.6611789
OS 38.48839394 -36.6819815
OS 38.49532814 -36.70694462
OS 38.49948866 -36.73329458
OS 38.5008755 -36.76241822
OS 38.5008755 -36.76380506
OS 38.5008755 -36.76657874
OS 38.5008755 -36.7721261
OS 38.49948866 -36.7790603
OS 38.49948866 -36.78876818
OS 38.49810182 -36.79847606
OS 38.49255446 -36.82205234
OS 38.48423342 -36.84978914
OS 38.4731387 -36.87891278
OS 38.45649662 -36.90803642
OS 38.4454019 -36.92190482
OS 38.43430718 -36.93577322
OS 38.43292034 -36.93716006
OS 38.4315335 -36.9385469
OS 38.42737298 -36.94270742
OS 38.42182562 -36.94686794
OS 38.41489142 -36.9524153
OS 38.40657038 -36.95796266
OS 38.39547566 -36.96489686
OS 38.38438094 -36.9732179
OS 38.37051254 -36.9801521
OS 38.3552573 -36.9870863
OS 38.33861522 -36.99540734
OS 38.3205863 -37.00234154
OS 38.2997837 -37.0078889
OS 38.2789811 -37.0148231
OS 38.25540482 -37.01898362
OS 38.2304417 -37.02314414
OS 38.23321538 -37.02453098
OS 38.23876274 -37.02730466
OS 38.24708378 -37.03285202
OS 38.2581785 -37.03839938
OS 38.28314162 -37.05365462
OS 38.29562318 -37.0633625
OS 38.3067179 -37.07168354
OS 38.30949158 -37.07445722
OS 38.31642578 -37.08139142
OS 38.3275205 -37.09248614
OS 38.3413889 -37.10635454
OS 38.35664414 -37.1257703
OS 38.37467306 -37.1465729
OS 38.39270198 -37.17153602
OS 38.41211774 -37.19927282
OS 38.5771517 -37.45999874
OS 38.41905194 -37.45999874
OS 38.2928495 -37.26029378
OS 38.2928495 -37.25890694
OS 38.29007582 -37.25613326
OS 38.28730214 -37.25197274
OS 38.28314162 -37.24642538
OS 38.27343374 -37.23117014
OS 38.26095218 -37.21175438
OS 38.24569694 -37.19095178
OS 38.2304417 -37.16876234
OS 38.21518646 -37.14795974
OS 38.20131806 -37.12854398
OS 38.19993122 -37.12715714
OS 38.1957707 -37.12160978
OS 38.1888365 -37.11328874
OS 38.17912862 -37.10358086
OS 38.15832602 -37.08277826
OS 38.1472313 -37.07307038
OS 38.13613658 -37.06474934
OS 38.13474974 -37.0633625
OS 38.13197606 -37.06197566
OS 38.1264287 -37.05920198
OS 38.11810766 -37.05504146
OS 38.10978662 -37.05088094
OS 38.10007874 -37.04672042
OS 38.0778893 -37.03978622
OS 38.07650246 -37.03978622
OS 38.07372878 -37.03839938
OS 38.06818142 -37.03839938
OS 38.06124722 -37.03701254
OS 38.05153934 -37.0356257
OS 38.04044462 -37.0356257
OS 38.02518938 -37.03423886
OS 37.86154226 -37.03423886
OS 37.86154226 -37.45999874
OS 37.73395298 -37.45999874
OS 37.73395298 -36.50030546
OS 38.17912862 -36.50030546
OS 38.19022334 -36.5016923
OE
OB 37.53424802 -36.61402634 I
OS 36.96703046 -36.61402634
OS 36.96703046 -36.90664958
OS 37.49819018 -36.90664958
OS 37.49819018 -37.02037046
OS 36.96703046 -37.02037046
OS 36.96703046 -37.34627786
OS 37.55643746 -37.34627786
OS 37.55643746 -37.45999874
OS 36.83944118 -37.45999874
OS 36.83944118 -36.50030546
OS 37.53424802 -36.50030546
OS 37.53424802 -36.61402634
OE
OB 36.32492354 -36.5016923 I
OS 36.33601826 -36.5016923
OS 36.36098138 -36.50446598
OS 36.38871818 -36.50723966
OS 36.41784182 -36.51278702
OS 36.44696546 -36.51972122
OS 36.47331542 -36.5294291
OS 36.47470226 -36.5294291
OS 36.4760891 -36.53081594
OS 36.48441014 -36.53497646
OS 36.4968917 -36.54191066
OS 36.5107601 -36.55161854
OS 36.52740218 -36.5641001
OS 36.5454311 -36.57935534
OS 36.56207318 -36.5987711
OS 36.57732842 -36.6195737
OS 36.57871526 -36.62234738
OS 36.58287578 -36.63066842
OS 36.58980998 -36.64176314
OS 36.59674418 -36.65840522
OS 36.60367838 -36.67782098
OS 36.61061258 -36.69862358
OS 36.6147731 -36.72219986
OS 36.61615994 -36.74577614
OS 36.61615994 -36.74854982
OS 36.61615994 -36.75548402
OS 36.6147731 -36.76796558
OS 36.61199942 -36.78322082
OS 36.6078389 -36.80124974
OS 36.6009047 -36.8206655
OS 36.59258366 -36.84008126
OS 36.58148894 -36.86088386
OS 36.5801021 -36.86365754
OS 36.57594158 -36.8692049
OS 36.56762054 -36.88029962
OS 36.55652582 -36.89139434
OS 36.54265742 -36.90526274
OS 36.52601534 -36.92051798
OS 36.50521274 -36.93438638
OS 36.48163646 -36.94825478
OS 36.4830233 -36.94825478
OS 36.48579698 -36.94964162
OS 36.4899575 -36.95102846
OS 36.49550486 -36.95380214
OS 36.51214694 -36.9593495
OS 36.5315627 -36.96905738
OS 36.5523653 -36.98153894
OS 36.57594158 -36.99679418
OS 36.59674418 -37.0148231
OS 36.61615994 -37.03701254
OS 36.61754678 -37.03978622
OS 36.62309414 -37.04810726
OS 36.63141518 -37.06058882
OS 36.63973622 -37.0772309
OS 36.64805726 -37.09942034
OS 36.6563783 -37.12299662
OS 36.66192566 -37.15073342
OS 36.6633125 -37.1812439
OS 36.6633125 -37.18263074
OS 36.6633125 -37.18401758
OS 36.6633125 -37.19233862
OS 36.66192566 -37.20620702
OS 36.65915198 -37.2228491
OS 36.6563783 -37.24226486
OS 36.65083094 -37.26306746
OS 36.64389674 -37.2852569
OS 36.63418886 -37.30744634
OS 36.63280202 -37.31022002
OS 36.6286415 -37.31715422
OS 36.62309414 -37.3268621
OS 36.6147731 -37.3407305
OS 36.60367838 -37.3545989
OS 36.59258366 -37.36985414
OS 36.57871526 -37.38510938
OS 36.56346002 -37.39759094
OS 36.56207318 -37.39897778
OS 36.55652582 -37.4031383
OS 36.54681794 -37.40868566
OS 36.53433638 -37.41423302
OS 36.51908114 -37.42255406
OS 36.50105222 -37.4308751
OS 36.48163646 -37.4378093
OS 36.45806018 -37.4447435
OS 36.4552865 -37.4447435
OS 36.44696546 -37.44751718
OS 36.43309706 -37.44890402
OS 36.41506814 -37.4516777
OS 36.3928787 -37.45445138
OS 36.36652874 -37.45722506
OS 36.3374051 -37.4586119
OS 36.30412094 -37.45999874
OS 35.93799518 -37.45999874
OS 35.93799518 -36.50030546
OS 36.31521566 -36.50030546
OS 36.32492354 -36.5016923
OE
OB 32.3849111 -36.61402634 I
OS 32.06871158 -36.61402634
OS 32.06871158 -37.45999874
OS 31.9411223 -37.45999874
OS 31.9411223 -36.61402634
OS 31.62492278 -36.61402634
OS 31.62492278 -36.50030546
OS 32.3849111 -36.50030546
OS 32.3849111 -36.61402634
OE
OB 30.62639798 -37.45999874 I
OS 30.48216662 -37.45999874
OS 30.36983258 -37.16876234
OS 29.96764898 -37.16876234
OS 29.86363598 -37.45999874
OS 29.7291125 -37.45999874
OS 30.09523826 -36.50030546
OS 30.23392226 -36.50030546
OS 30.62639798 -37.45999874
OE
OB 29.3546657 -36.5016923 I
OS 29.37824198 -36.50307914
OS 29.4032051 -36.50446598
OS 29.42678138 -36.50723966
OS 29.44758398 -36.51001334
OS 29.45035766 -36.51001334
OS 29.46006554 -36.51278702
OS 29.4725471 -36.5155607
OS 29.48918918 -36.51972122
OS 29.5072181 -36.52665542
OS 29.52663386 -36.53497646
OS 29.54743646 -36.54468434
OS 29.56546538 -36.55577906
OS 29.56823906 -36.5571659
OS 29.57378642 -36.56132642
OS 29.58210746 -36.56964746
OS 29.59320218 -36.57935534
OS 29.60568374 -36.5918369
OS 29.6181653 -36.60847898
OS 29.6320337 -36.6265079
OS 29.64312842 -36.6473105
OS 29.64451526 -36.65008418
OS 29.64728894 -36.65701838
OS 29.6528363 -36.66949994
OS 29.65838366 -36.68614202
OS 29.66254418 -36.70555778
OS 29.66809154 -36.72774722
OS 29.67086522 -36.75271034
OS 29.67225206 -36.7790603
OS 29.67225206 -36.78044714
OS 29.67225206 -36.78460766
OS 29.67225206 -36.79015502
OS 29.67086522 -36.7998629
OS 29.66947838 -36.80957078
OS 29.66809154 -36.82205234
OS 29.66531786 -36.83592074
OS 29.66254418 -36.85117598
OS 29.6528363 -36.8830733
OS 29.64728894 -36.89971538
OS 29.6389679 -36.9177443
OS 29.62926002 -36.93577322
OS 29.61955214 -36.9524153
OS 29.60707058 -36.96905738
OS 29.59320218 -36.98569946
OS 29.59181534 -36.9870863
OS 29.58904166 -36.98985998
OS 29.58488114 -36.9940205
OS 29.57794694 -36.99818102
OS 29.5696259 -37.00511522
OS 29.55853118 -37.01204942
OS 29.54466278 -37.02037046
OS 29.52940754 -37.02730466
OS 29.51137862 -37.0356257
OS 29.49057602 -37.04394674
OS 29.46838658 -37.05088094
OS 29.44203662 -37.0564283
OS 29.41429982 -37.06197566
OS 29.38378934 -37.06613618
OS 29.34911834 -37.06890986
OS 29.3130605 -37.0702967
OS 29.06758982 -37.0702967
OS 29.06758982 -37.45999874
OS 28.94000054 -37.45999874
OS 28.94000054 -36.50030546
OS 29.3338631 -36.50030546
OS 29.3546657 -36.5016923
OE
OB 31.18668134 -36.5016923 I
OS 31.1991629 -36.5016923
OS 31.22828654 -36.50307914
OS 31.25879702 -36.50723966
OS 31.29208118 -36.51140018
OS 31.32259166 -36.51833438
OS 31.3378469 -36.5224949
OS 31.35032846 -36.52665542
OS 31.3517153 -36.52665542
OS 31.35310214 -36.52804226
OS 31.36142318 -36.53220278
OS 31.37390474 -36.53775014
OS 31.38915998 -36.54745802
OS 31.40580206 -36.55993958
OS 31.42383098 -36.57658166
OS 31.44047306 -36.59599742
OS 31.45711514 -36.61818686
OS 31.45711514 -36.6195737
OS 31.45850198 -36.62096054
OS 31.46404934 -36.62928158
OS 31.4695967 -36.64314998
OS 31.47791774 -36.6611789
OS 31.48485194 -36.6819815
OS 31.49178614 -36.70694462
OS 31.49594666 -36.73329458
OS 31.4973335 -36.76241822
OS 31.4973335 -36.76380506
OS 31.4973335 -36.76657874
OS 31.4973335 -36.7721261
OS 31.49594666 -36.7790603
OS 31.49594666 -36.78876818
OS 31.49455982 -36.79847606
OS 31.48901246 -36.82205234
OS 31.48069142 -36.84978914
OS 31.4695967 -36.87891278
OS 31.45295462 -36.90803642
OS 31.4418599 -36.92190482
OS 31.43076518 -36.93577322
OS 31.42937834 -36.93716006
OS 31.4279915 -36.9385469
OS 31.42383098 -36.94270742
OS 31.41828362 -36.94686794
OS 31.41134942 -36.9524153
OS 31.40302838 -36.95796266
OS 31.39193366 -36.96489686
OS 31.38083894 -36.9732179
OS 31.36697054 -36.9801521
OS 31.3517153 -36.9870863
OS 31.33507322 -36.99540734
OS 31.3170443 -37.00234154
OS 31.2962417 -37.0078889
OS 31.2754391 -37.0148231
OS 31.25186282 -37.01898362
OS 31.2268997 -37.02314414
OS 31.22967338 -37.02453098
OS 31.23522074 -37.02730466
OS 31.24354178 -37.03285202
OS 31.2546365 -37.03839938
OS 31.27959962 -37.05365462
OS 31.29208118 -37.0633625
OS 31.3031759 -37.07168354
OS 31.30594958 -37.07445722
OS 31.31288378 -37.08139142
OS 31.3239785 -37.09248614
OS 31.3378469 -37.10635454
OS 31.35310214 -37.1257703
OS 31.37113106 -37.1465729
OS 31.38915998 -37.17153602
OS 31.40857574 -37.19927282
OS 31.5736097 -37.45999874
OS 31.41550994 -37.45999874
OS 31.2893075 -37.26029378
OS 31.2893075 -37.25890694
OS 31.28653382 -37.25613326
OS 31.28376014 -37.25197274
OS 31.27959962 -37.24642538
OS 31.26989174 -37.23117014
OS 31.25741018 -37.21175438
OS 31.24215494 -37.19095178
OS 31.2268997 -37.16876234
OS 31.21164446 -37.14795974
OS 31.19777606 -37.12854398
OS 31.19638922 -37.12715714
OS 31.1922287 -37.12160978
OS 31.1852945 -37.11328874
OS 31.17558662 -37.10358086
OS 31.15478402 -37.08277826
OS 31.1436893 -37.07307038
OS 31.13259458 -37.06474934
OS 31.13120774 -37.0633625
OS 31.12843406 -37.06197566
OS 31.1228867 -37.05920198
OS 31.11456566 -37.05504146
OS 31.10624462 -37.05088094
OS 31.09653674 -37.04672042
OS 31.0743473 -37.03978622
OS 31.07296046 -37.03978622
OS 31.07018678 -37.03839938
OS 31.06463942 -37.03839938
OS 31.05770522 -37.03701254
OS 31.04799734 -37.0356257
OS 31.03690262 -37.0356257
OS 31.02164738 -37.03423886
OS 30.85800026 -37.03423886
OS 30.85800026 -37.45999874
OS 30.73041098 -37.45999874
OS 30.73041098 -36.50030546
OS 31.17558662 -36.50030546
OS 31.18668134 -36.5016923
OE
OB 38.16387338 -36.60709214 H
OS 37.86154226 -36.60709214
OS 37.86154226 -36.9246785
OS 38.1472313 -36.9246785
OS 38.16387338 -36.92329166
OS 38.18328914 -36.92190482
OS 38.20547858 -36.92051798
OS 38.22766802 -36.9177443
OS 38.24985746 -36.91358378
OS 38.26927322 -36.90803642
OS 38.2720469 -36.90664958
OS 38.27759426 -36.9038759
OS 38.2859153 -36.89971538
OS 38.29701002 -36.89416802
OS 38.30949158 -36.88584698
OS 38.32197314 -36.8761391
OS 38.3344547 -36.86365754
OS 38.34416258 -36.84978914
OS 38.34554942 -36.8484023
OS 38.3483231 -36.84285494
OS 38.35248362 -36.8345339
OS 38.35803098 -36.82343918
OS 38.3621915 -36.81095762
OS 38.36635202 -36.79708922
OS 38.3691257 -36.78044714
OS 38.37051254 -36.76380506
OS 38.37051254 -36.76241822
OS 38.37051254 -36.76103138
OS 38.3691257 -36.75271034
OS 38.36773886 -36.74022878
OS 38.36496518 -36.7235867
OS 38.35803098 -36.70694462
OS 38.34970994 -36.68752886
OS 38.33722838 -36.66949994
OS 38.3205863 -36.65147102
OS 38.31781262 -36.65008418
OS 38.31087842 -36.64453682
OS 38.2997837 -36.63760262
OS 38.28175478 -36.62928158
OS 38.26095218 -36.62096054
OS 38.23321538 -36.61402634
OS 38.20131806 -36.60847898
OS 38.16387338 -36.60709214
OE
OB 29.34218414 -36.61402634 H
OS 29.06758982 -36.61402634
OS 29.06758982 -36.95657582
OS 29.32554206 -36.95657582
OS 29.33524994 -36.95518898
OS 29.34495782 -36.95518898
OS 29.35605254 -36.95380214
OS 29.3824025 -36.95102846
OS 29.41152614 -36.9454811
OS 29.44064978 -36.93716006
OS 29.46699974 -36.92606534
OS 29.4794813 -36.91913114
OS 29.48918918 -36.9108101
OS 29.49196286 -36.90803642
OS 29.49751022 -36.90248906
OS 29.50583126 -36.89139434
OS 29.51553914 -36.87752594
OS 29.52524702 -36.85949702
OS 29.53356806 -36.83730758
OS 29.53911542 -36.81234446
OS 29.5418891 -36.78322082
OS 29.5418891 -36.78183398
OS 29.5418891 -36.78044714
OS 29.5418891 -36.77351294
OS 29.54050226 -36.76103138
OS 29.53772858 -36.74716298
OS 29.5349549 -36.73190774
OS 29.52940754 -36.71387882
OS 29.5210865 -36.69723674
OS 29.51137862 -36.68059466
OS 29.50999178 -36.67920782
OS 29.50583126 -36.67366046
OS 29.49889706 -36.66672626
OS 29.49057602 -36.65701838
OS 29.47809446 -36.6473105
OS 29.46422606 -36.63898946
OS 29.44897082 -36.63066842
OS 29.4309419 -36.62373422
OS 29.42955506 -36.62373422
OS 29.4240077 -36.62234738
OS 29.41568666 -36.62096054
OS 29.40459194 -36.61818686
OS 29.38794986 -36.61680002
OS 29.36714726 -36.61541318
OS 29.34218414 -36.61402634
OE
OB 30.16180658 -36.60015794 H
OS 30.16180658 -36.60154478
OS 30.16041974 -36.60431846
OS 30.16041974 -36.60986582
OS 30.15764606 -36.61541318
OS 30.15625922 -36.62512106
OS 30.15348554 -36.63482894
OS 30.14793818 -36.65840522
OS 30.14100398 -36.68614202
OS 30.1312961 -36.7166525
OS 30.12158822 -36.74993666
OS 30.10910666 -36.78460766
OS 30.00509366 -37.06474934
OS 30.32961422 -37.06474934
OS 30.22976174 -36.80124974
OS 30.22976174 -36.7998629
OS 30.2283749 -36.79570238
OS 30.22560122 -36.78876818
OS 30.22282754 -36.78044714
OS 30.21866702 -36.77073926
OS 30.2145065 -36.7582577
OS 30.21034598 -36.7443893
OS 30.20479862 -36.7305209
OS 30.1937039 -36.69862358
OS 30.18260918 -36.66533942
OS 30.17151446 -36.63205526
OS 30.16180658 -36.60015794
OE
OB 31.16033138 -36.60709214 H
OS 30.85800026 -36.60709214
OS 30.85800026 -36.9246785
OS 31.1436893 -36.9246785
OS 31.16033138 -36.92329166
OS 31.17974714 -36.92190482
OS 31.20193658 -36.92051798
OS 31.22412602 -36.9177443
OS 31.24631546 -36.91358378
OS 31.26573122 -36.90803642
OS 31.2685049 -36.90664958
OS 31.27405226 -36.9038759
OS 31.2823733 -36.89971538
OS 31.29346802 -36.89416802
OS 31.30594958 -36.88584698
OS 31.31843114 -36.8761391
OS 31.3309127 -36.86365754
OS 31.34062058 -36.84978914
OS 31.34200742 -36.8484023
OS 31.3447811 -36.84285494
OS 31.34894162 -36.8345339
OS 31.35448898 -36.82343918
OS 31.3586495 -36.81095762
OS 31.36281002 -36.79708922
OS 31.3655837 -36.78044714
OS 31.36697054 -36.76380506
OS 31.36697054 -36.76241822
OS 31.36697054 -36.76103138
OS 31.3655837 -36.75271034
OS 31.36419686 -36.74022878
OS 31.36142318 -36.7235867
OS 31.35448898 -36.70694462
OS 31.34616794 -36.68752886
OS 31.33368638 -36.66949994
OS 31.3170443 -36.65147102
OS 31.31427062 -36.65008418
OS 31.30733642 -36.64453682
OS 31.2962417 -36.63760262
OS 31.27821278 -36.62928158
OS 31.25741018 -36.62096054
OS 31.22967338 -36.61402634
OS 31.19777606 -36.60847898
OS 31.16033138 -36.60709214
OE
OB 36.29302622 -36.61402634 H
OS 36.06558446 -36.61402634
OS 36.06558446 -36.90248906
OS 36.30134726 -36.90248906
OS 36.31937618 -36.90110222
OS 36.33879194 -36.89971538
OS 36.3582077 -36.89832854
OS 36.37762346 -36.89555486
OS 36.3928787 -36.89278118
OS 36.39565238 -36.89139434
OS 36.40119974 -36.8900075
OS 36.40952078 -36.88584698
OS 36.4206155 -36.88029962
OS 36.43171022 -36.87475226
OS 36.44419178 -36.86643122
OS 36.45667334 -36.8553365
OS 36.46638122 -36.84424178
OS 36.46776806 -36.84285494
OS 36.47054174 -36.83869442
OS 36.47470226 -36.83037338
OS 36.47886278 -36.8206655
OS 36.4830233 -36.80957078
OS 36.48718382 -36.79570238
OS 36.4899575 -36.7790603
OS 36.49134434 -36.76103138
OS 36.49134434 -36.7582577
OS 36.49134434 -36.75271034
OS 36.4899575 -36.7443893
OS 36.48857066 -36.73329458
OS 36.48579698 -36.71942618
OS 36.48163646 -36.70555778
OS 36.4760891 -36.69168938
OS 36.46776806 -36.67782098
OS 36.46638122 -36.67643414
OS 36.46360754 -36.67227362
OS 36.45806018 -36.66533942
OS 36.45112598 -36.65840522
OS 36.4414181 -36.65008418
OS 36.43032338 -36.64176314
OS 36.41645498 -36.6334421
OS 36.40119974 -36.62789474
OS 36.3998129 -36.62789474
OS 36.3928787 -36.62512106
OS 36.38317082 -36.62373422
OS 36.36791558 -36.62096054
OS 36.34711298 -36.61818686
OS 36.3235367 -36.61680002
OS 36.29302622 -36.61402634
OE
OB 36.31798934 -37.01620994 H
OS 36.06558446 -37.01620994
OS 36.06558446 -37.34627786
OS 36.33879194 -37.34627786
OS 36.36791558 -37.34489102
OS 36.38039714 -37.34350418
OS 36.39149186 -37.34211734
OS 36.3928787 -37.34211734
OS 36.39842606 -37.3407305
OS 36.4067471 -37.33934366
OS 36.41645498 -37.33656998
OS 36.44003126 -37.32824894
OS 36.46360754 -37.31715422
OS 36.46499438 -37.31576738
OS 36.4691549 -37.3129937
OS 36.47470226 -37.30883318
OS 36.48163646 -37.30328582
OS 36.48857066 -37.29496478
OS 36.49827854 -37.28664374
OS 36.50521274 -37.27554902
OS 36.51353378 -37.26306746
OS 36.51492062 -37.26168062
OS 36.51630746 -37.2575201
OS 36.51908114 -37.24919906
OS 36.52324166 -37.23949118
OS 36.52740218 -37.22839646
OS 36.53017586 -37.21452806
OS 36.5315627 -37.19788598
OS 36.53294954 -37.1812439
OS 36.53294954 -37.17847022
OS 36.53294954 -37.17292286
OS 36.5315627 -37.16182814
OS 36.52878902 -37.14934658
OS 36.52601534 -37.13547818
OS 36.52046798 -37.12022294
OS 36.51353378 -37.1049677
OS 36.5038259 -37.08971246
OS 36.50243906 -37.08832562
OS 36.49827854 -37.08277826
OS 36.49273118 -37.07584406
OS 36.48441014 -37.06752302
OS 36.47331542 -37.05781514
OS 36.45944702 -37.04810726
OS 36.44419178 -37.03978622
OS 36.42616286 -37.03285202
OS 36.42338918 -37.03146518
OS 36.41784182 -37.03007834
OS 36.40536026 -37.02730466
OS 36.39010502 -37.02453098
OS 36.37068926 -37.0217573
OS 36.34711298 -37.01898362
OS 36.31798934 -37.01620994
OE
SE
S P 0
OB 40.9056459 -38.32112732 I
OS 40.92136342 -38.32205188
OS 40.9380055 -38.32297644
OS 40.95372302 -38.32482556
OS 40.96759142 -38.32667468
OS 40.96944054 -38.32667468
OS 40.97591246 -38.3285238
OS 40.9842335 -38.33037292
OS 40.99532822 -38.3331466
OS 41.0073475 -38.3377694
OS 41.02029134 -38.34331676
OS 41.03415974 -38.34978868
OS 41.04617902 -38.35718516
OS 41.04802814 -38.35810972
OS 41.05172638 -38.3608834
OS 41.05727374 -38.36643076
OS 41.06467022 -38.37290268
OS 41.07299126 -38.38122372
OS 41.0813123 -38.39231844
OS 41.0905579 -38.40433772
OS 41.09795438 -38.41820612
OS 41.09887894 -38.42005524
OS 41.10072806 -38.42467804
OS 41.1044263 -38.43299908
OS 41.10812454 -38.4440938
OS 41.11089822 -38.45703764
OS 41.11459646 -38.4718306
OS 41.11644558 -38.48847268
OS 41.11737014 -38.50603932
OS 41.11737014 -38.50696388
OS 41.11737014 -38.50973756
OS 41.11737014 -38.5134358
OS 41.11644558 -38.51990772
OS 41.11552102 -38.52637964
OS 41.11459646 -38.53470068
OS 41.11274734 -38.54394628
OS 41.11089822 -38.55411644
OS 41.1044263 -38.57538132
OS 41.10072806 -38.58647604
OS 41.0951807 -38.59849532
OS 41.08870878 -38.6105146
OS 41.08223686 -38.62160932
OS 41.07391582 -38.63270404
OS 41.06467022 -38.64379876
OS 41.06374566 -38.64472332
OS 41.06189654 -38.64657244
OS 41.05912286 -38.64934612
OS 41.05450006 -38.6521198
OS 41.0489527 -38.6567426
OS 41.04155622 -38.6613654
OS 41.03231062 -38.66691276
OS 41.02214046 -38.67153556
OS 41.01012118 -38.67708292
OS 40.99625278 -38.68263028
OS 40.98145982 -38.68725308
OS 40.96389318 -38.69095132
OS 40.94540198 -38.69464956
OS 40.92506166 -38.69742324
OS 40.90194766 -38.69927236
OS 40.8779091 -38.70019692
OS 40.71426198 -38.70019692
OS 40.71426198 -38.95999828
OS 40.62920246 -38.95999828
OS 40.62920246 -38.32020276
OS 40.8917775 -38.32020276
OS 40.9056459 -38.32112732
OE
OB 40.49791494 -38.98403684 I
OS 40.49791494 -38.9849614
OS 40.49791494 -38.98773508
OS 40.49791494 -38.99235788
OS 40.49791494 -38.99790524
OS 40.49699038 -39.00530172
OS 40.49699038 -39.0126982
OS 40.49514126 -39.0311894
OS 40.49236758 -39.05060516
OS 40.48866934 -39.07094548
OS 40.48312198 -39.08851212
OS 40.47942374 -39.09683316
OS 40.4757255 -39.10330508
OS 40.4757255 -39.10422964
OS 40.47480094 -39.1051542
OS 40.47017814 -39.109777
OS 40.46278166 -39.11717348
OS 40.45353606 -39.12549452
OS 40.44059222 -39.13381556
OS 40.42395014 -39.14028748
OS 40.40453438 -39.14583484
OS 40.39343966 -39.1467594
OS 40.38142038 -39.14768396
OS 40.37587302 -39.14768396
OS 40.37032566 -39.1467594
OS 40.36200462 -39.1467594
OS 40.35275902 -39.14583484
OS 40.34258886 -39.14398572
OS 40.32039942 -39.13843836
OS 40.33519238 -39.07187004
OS 40.33611694 -39.07187004
OS 40.33889062 -39.0727946
OS 40.34351342 -39.07371916
OS 40.34813622 -39.07464372
OS 40.3601555 -39.0774174
OS 40.36570286 -39.07834196
OS 40.37494846 -39.07834196
OS 40.37957126 -39.0774174
OS 40.38511862 -39.07649284
OS 40.39066598 -39.07464372
OS 40.39621334 -39.07094548
OS 40.40268526 -39.06724724
OS 40.40730806 -39.06169988
OS 40.40823262 -39.06077532
OS 40.40915718 -39.05800164
OS 40.4110063 -39.05337884
OS 40.41377998 -39.04598236
OS 40.4156291 -39.0358122
OS 40.41655366 -39.02841572
OS 40.41747822 -39.0219438
OS 40.41840278 -39.01362276
OS 40.41840278 -39.0034526
OS 40.41932734 -38.99328244
OS 40.41932734 -38.98218772
OS 40.41932734 -38.49586916
OS 40.49791494 -38.49586916
OS 40.49791494 -38.98403684
OE
OB 41.51770462 -38.3100326 I
OS 41.52602566 -38.31095716
OS 41.53619582 -38.31188172
OS 41.54636598 -38.31280628
OS 41.55838526 -38.31557996
OS 41.58334838 -38.32112732
OS 41.61108518 -38.32944836
OS 41.62495358 -38.33499572
OS 41.63789742 -38.34146764
OS 41.65084126 -38.34978868
OS 41.6637851 -38.35810972
OS 41.66470966 -38.35903428
OS 41.66655878 -38.35995884
OS 41.67025702 -38.36273252
OS 41.67487982 -38.36735532
OS 41.67950262 -38.37197812
OS 41.68597454 -38.37845004
OS 41.69244646 -38.38584652
OS 41.69984294 -38.393243
OS 41.70723942 -38.4024886
OS 41.7146359 -38.41358332
OS 41.72295694 -38.42467804
OS 41.73035342 -38.43669732
OS 41.73682534 -38.45056572
OS 41.74422182 -38.46443412
OS 41.74976918 -38.47922708
OS 41.75531654 -38.49586916
OS 41.67210614 -38.51528492
OS 41.67210614 -38.51436036
OS 41.67118158 -38.51251124
OS 41.66933246 -38.508813
OS 41.66748334 -38.5041902
OS 41.66563422 -38.49864284
OS 41.66286054 -38.49124636
OS 41.65546406 -38.4764534
OS 41.64621846 -38.45981132
OS 41.63512374 -38.44316924
OS 41.62125534 -38.42745172
OS 41.60646238 -38.41358332
OS 41.60461326 -38.4117342
OS 41.5990659 -38.40803596
OS 41.5898203 -38.40341316
OS 41.57780102 -38.39694124
OS 41.5620835 -38.39139388
OS 41.54451686 -38.38584652
OS 41.52325198 -38.38214828
OS 41.50013798 -38.38122372
OS 41.4927415 -38.38122372
OS 41.4881187 -38.38214828
OS 41.48164678 -38.38214828
OS 41.4742503 -38.38307284
OS 41.45668366 -38.38584652
OS 41.4372679 -38.38954476
OS 41.41692758 -38.39601668
OS 41.3956627 -38.40526228
OS 41.37624694 -38.41728156
OS 41.37532238 -38.41728156
OS 41.37439782 -38.41913068
OS 41.3679259 -38.42375348
OS 41.35960486 -38.43114996
OS 41.3494347 -38.44224468
OS 41.33741542 -38.45611308
OS 41.3263207 -38.4718306
OS 41.31615054 -38.49124636
OS 41.30690494 -38.51251124
OS 41.30690494 -38.5134358
OS 41.30598038 -38.51528492
OS 41.30505582 -38.5180586
OS 41.30413126 -38.5226814
OS 41.30228214 -38.52822876
OS 41.30043302 -38.53470068
OS 41.29765934 -38.5504182
OS 41.2939611 -38.5689094
OS 41.29026286 -38.58924972
OS 41.28841374 -38.61143916
OS 41.28748918 -38.63547772
OS 41.28748918 -38.63640228
OS 41.28748918 -38.63917596
OS 41.28748918 -38.64379876
OS 41.28748918 -38.64934612
OS 41.28841374 -38.65581804
OS 41.28841374 -38.66413908
OS 41.2893383 -38.67338468
OS 41.29026286 -38.68355484
OS 41.29303654 -38.70574428
OS 41.29765934 -38.72978284
OS 41.3032067 -38.7538214
OS 41.31060318 -38.77785996
OS 41.31060318 -38.77878452
OS 41.31152774 -38.78063364
OS 41.31337686 -38.78340732
OS 41.31522598 -38.78803012
OS 41.32077334 -38.79912484
OS 41.32909438 -38.81206868
OS 41.33926454 -38.82686164
OS 41.35220838 -38.84257916
OS 41.36700134 -38.85644756
OS 41.38456798 -38.8693914
OS 41.38549254 -38.8693914
OS 41.38734166 -38.87031596
OS 41.39011534 -38.87216508
OS 41.39381358 -38.8740142
OS 41.39843638 -38.87586332
OS 41.40398374 -38.878637
OS 41.41692758 -38.88418436
OS 41.43356966 -38.88973172
OS 41.45206086 -38.89435452
OS 41.47240118 -38.89805276
OS 41.49366606 -38.89897732
OS 41.50013798 -38.89897732
OS 41.50568534 -38.89805276
OS 41.51215726 -38.89805276
OS 41.51862918 -38.8971282
OS 41.53527126 -38.89342996
OS 41.55468702 -38.88880716
OS 41.57410278 -38.88141068
OS 41.5944431 -38.87124052
OS 41.60461326 -38.86569316
OS 41.61385886 -38.85829668
OS 41.61478342 -38.85737212
OS 41.61570798 -38.85644756
OS 41.61848166 -38.85367388
OS 41.6221799 -38.8509002
OS 41.62587814 -38.8462774
OS 41.63050094 -38.84073004
OS 41.6360483 -38.83518268
OS 41.6406711 -38.8277862
OS 41.64621846 -38.81946516
OS 41.65269038 -38.81021956
OS 41.65823774 -38.80097396
OS 41.6637851 -38.78987924
OS 41.6684079 -38.77785996
OS 41.6730307 -38.76491612
OS 41.6776535 -38.75104772
OS 41.68135174 -38.73625476
OS 41.76641126 -38.75751964
OS 41.76641126 -38.7584442
OS 41.7654867 -38.76214244
OS 41.76363758 -38.7676898
OS 41.7608639 -38.77508628
OS 41.75809022 -38.78340732
OS 41.75439198 -38.79357748
OS 41.74976918 -38.8046722
OS 41.74422182 -38.81669148
OS 41.73127798 -38.84257916
OS 41.7146359 -38.86846684
OS 41.70446574 -38.88141068
OS 41.69429558 -38.89435452
OS 41.68320086 -38.90544924
OS 41.67025702 -38.91654396
OS 41.66933246 -38.91746852
OS 41.66748334 -38.91931764
OS 41.66286054 -38.92116676
OS 41.65823774 -38.924865
OS 41.65084126 -38.9294878
OS 41.64344478 -38.9341106
OS 41.63327462 -38.9387334
OS 41.62310446 -38.9433562
OS 41.61108518 -38.94890356
OS 41.59814134 -38.95352636
OS 41.58427294 -38.95814916
OS 41.56947998 -38.96277196
OS 41.55376246 -38.9664702
OS 41.53712038 -38.96831932
OS 41.51955374 -38.97016844
OS 41.50106254 -38.971093
OS 41.49089238 -38.971093
OS 41.4834959 -38.97016844
OS 41.47517486 -38.97016844
OS 41.4650047 -38.96924388
OS 41.45390998 -38.96739476
OS 41.44096614 -38.96554564
OS 41.4141539 -38.96092284
OS 41.3864171 -38.95352636
OS 41.3586803 -38.9433562
OS 41.34573646 -38.93688428
OS 41.33279262 -38.9294878
OS 41.33186806 -38.92856324
OS 41.33001894 -38.92763868
OS 41.3263207 -38.924865
OS 41.32262246 -38.92116676
OS 41.3170751 -38.91746852
OS 41.31060318 -38.91192116
OS 41.3032067 -38.90544924
OS 41.29581022 -38.89805276
OS 41.28841374 -38.88973172
OS 41.2800927 -38.88141068
OS 41.26345062 -38.8601458
OS 41.2477331 -38.83518268
OS 41.2338647 -38.80744588
OS 41.2338647 -38.80652132
OS 41.23201558 -38.80374764
OS 41.23109102 -38.79912484
OS 41.22831734 -38.79357748
OS 41.22646822 -38.786181
OS 41.22369454 -38.7769354
OS 41.2199963 -38.76676524
OS 41.21722262 -38.75567052
OS 41.21444894 -38.74365124
OS 41.2107507 -38.72978284
OS 41.2061279 -38.70112148
OS 41.20242966 -38.66876188
OS 41.20058054 -38.63547772
OS 41.20058054 -38.63455316
OS 41.20058054 -38.63085492
OS 41.20058054 -38.62530756
OS 41.2015051 -38.61883564
OS 41.2015051 -38.60959004
OS 41.20242966 -38.60034444
OS 41.20335422 -38.58832516
OS 41.20520334 -38.57630588
OS 41.20982614 -38.54949364
OS 41.21629806 -38.51990772
OS 41.22554366 -38.4903218
OS 41.2384875 -38.46166044
OS 41.23941206 -38.46073588
OS 41.24033662 -38.4579622
OS 41.24218574 -38.45426396
OS 41.24588398 -38.44964116
OS 41.24958222 -38.44316924
OS 41.25420502 -38.43577276
OS 41.2662243 -38.41913068
OS 41.28194182 -38.40063948
OS 41.30043302 -38.38214828
OS 41.3216979 -38.36365708
OS 41.34666102 -38.34793956
OS 41.34758558 -38.347015
OS 41.35035926 -38.34609044
OS 41.3540575 -38.34424132
OS 41.3586803 -38.34146764
OS 41.36607678 -38.33869396
OS 41.37347326 -38.33592028
OS 41.38271886 -38.33222204
OS 41.39288902 -38.3285238
OS 41.40398374 -38.32482556
OS 41.41600302 -38.32112732
OS 41.4418907 -38.31557996
OS 41.47147662 -38.31095716
OS 41.5019871 -38.30910804
OS 41.5112327 -38.30910804
OS 41.51770462 -38.3100326
OE
OB 42.90454462 -39.1375138 I
OS 42.38401734 -39.1375138
OS 42.38401734 -39.08111564
OS 42.90454462 -39.08111564
OS 42.90454462 -39.1375138
OE
OB 42.12514054 -38.32112732 I
OS 42.13253702 -38.32112732
OS 42.1491791 -38.32297644
OS 42.1676703 -38.32482556
OS 42.18708606 -38.3285238
OS 42.20650182 -38.3331466
OS 42.22406846 -38.33961852
OS 42.22499302 -38.33961852
OS 42.22591758 -38.34054308
OS 42.23146494 -38.34331676
OS 42.23978598 -38.34793956
OS 42.24903158 -38.35441148
OS 42.2601263 -38.36273252
OS 42.27214558 -38.37290268
OS 42.2832403 -38.38584652
OS 42.29341046 -38.39971492
OS 42.29433502 -38.40156404
OS 42.2971087 -38.4071114
OS 42.3017315 -38.41450788
OS 42.3063543 -38.4256026
OS 42.3109771 -38.43854644
OS 42.3155999 -38.45241484
OS 42.31837358 -38.46813236
OS 42.31929814 -38.48384988
OS 42.31929814 -38.485699
OS 42.31929814 -38.4903218
OS 42.31837358 -38.49864284
OS 42.31652446 -38.508813
OS 42.31375078 -38.52083228
OS 42.30912798 -38.53377612
OS 42.30358062 -38.54671996
OS 42.29618414 -38.56058836
OS 42.29525958 -38.56243748
OS 42.2924859 -38.56613572
OS 42.28693854 -38.5735322
OS 42.27954206 -38.58092868
OS 42.27029646 -38.59017428
OS 42.25920174 -38.60034444
OS 42.24533334 -38.60959004
OS 42.22961582 -38.61883564
OS 42.23054038 -38.61883564
OS 42.2323895 -38.6197602
OS 42.23516318 -38.62068476
OS 42.23886142 -38.62253388
OS 42.24995614 -38.62623212
OS 42.26289998 -38.63270404
OS 42.27676838 -38.64102508
OS 42.2924859 -38.65119524
OS 42.3063543 -38.66321452
OS 42.31929814 -38.67800748
OS 42.3202227 -38.6798566
OS 42.32392094 -38.68540396
OS 42.3294683 -38.693725
OS 42.33501566 -38.70481972
OS 42.34056302 -38.71961268
OS 42.34611038 -38.7353302
OS 42.34980862 -38.7538214
OS 42.35073318 -38.77416172
OS 42.35073318 -38.77508628
OS 42.35073318 -38.77601084
OS 42.35073318 -38.7815582
OS 42.34980862 -38.7908038
OS 42.3479595 -38.80189852
OS 42.34611038 -38.81484236
OS 42.34241214 -38.82871076
OS 42.33778934 -38.84350372
OS 42.33131742 -38.85829668
OS 42.33039286 -38.8601458
OS 42.32761918 -38.8647686
OS 42.32392094 -38.87124052
OS 42.31837358 -38.88048612
OS 42.3109771 -38.88973172
OS 42.30358062 -38.89990188
OS 42.29433502 -38.91007204
OS 42.28416486 -38.91839308
OS 42.2832403 -38.91931764
OS 42.27954206 -38.92209132
OS 42.27307014 -38.92578956
OS 42.2647491 -38.9294878
OS 42.25457894 -38.93503516
OS 42.24255966 -38.94058252
OS 42.22961582 -38.94520532
OS 42.2138983 -38.94982812
OS 42.21204918 -38.94982812
OS 42.20650182 -38.95167724
OS 42.19725622 -38.9526018
OS 42.18523694 -38.95445092
OS 42.17044398 -38.95630004
OS 42.15287734 -38.95814916
OS 42.13346158 -38.95907372
OS 42.11127214 -38.95999828
OS 41.8671883 -38.95999828
OS 41.8671883 -38.32020276
OS 42.11866862 -38.32020276
OS 42.12514054 -38.32112732
OE
OB 40.30745558 -38.48662356 I
OS 40.31762574 -38.48847268
OS 40.32964502 -38.49217092
OS 40.34258886 -38.49679372
OS 40.35738182 -38.50326564
OS 40.37309934 -38.51158668
OS 40.34443798 -38.58370236
OS 40.34351342 -38.5827778
OS 40.33981518 -38.58092868
OS 40.33426782 -38.578155
OS 40.32687134 -38.57538132
OS 40.3185503 -38.57260764
OS 40.30838014 -38.56983396
OS 40.29820998 -38.56798484
OS 40.28803982 -38.56706028
OS 40.28341702 -38.56706028
OS 40.27879422 -38.56798484
OS 40.2723223 -38.5689094
OS 40.26585038 -38.57075852
OS 40.25752934 -38.5735322
OS 40.2492083 -38.57723044
OS 40.24181182 -38.5827778
OS 40.24088726 -38.58370236
OS 40.23811358 -38.58555148
OS 40.2353399 -38.58924972
OS 40.2307171 -38.59387252
OS 40.2260943 -38.60034444
OS 40.2214715 -38.60774092
OS 40.2168487 -38.61606196
OS 40.21315046 -38.62623212
OS 40.2122259 -38.62808124
OS 40.21130134 -38.6336286
OS 40.20945222 -38.64194964
OS 40.20667854 -38.65304436
OS 40.20390486 -38.66691276
OS 40.20205574 -38.68263028
OS 40.20113118 -38.69927236
OS 40.20020662 -38.71776356
OS 40.20020662 -38.95999828
OS 40.12161902 -38.95999828
OS 40.12161902 -38.49586916
OS 40.19281014 -38.49586916
OS 40.19281014 -38.56613572
OS 40.1937347 -38.56521116
OS 40.19743294 -38.55873924
OS 40.20205574 -38.5504182
OS 40.20945222 -38.54024804
OS 40.2168487 -38.53007788
OS 40.22516974 -38.51898316
OS 40.23349078 -38.50973756
OS 40.24181182 -38.50234108
OS 40.24273638 -38.50141652
OS 40.24551006 -38.4995674
OS 40.25105742 -38.49679372
OS 40.25660478 -38.49402004
OS 40.26400126 -38.49124636
OS 40.27324686 -38.48847268
OS 40.28249246 -38.48662356
OS 40.29266262 -38.485699
OS 40.29913454 -38.485699
OS 40.30745558 -38.48662356
OE
OB 39.48829542 -38.95999828 I
OS 39.3986131 -38.95999828
OS 39.3986131 -38.87031596
OS 39.48829542 -38.87031596
OS 39.48829542 -38.95999828
OE
OB 38.6404739 -38.95999828 I
OS 38.55171614 -38.95999828
OS 38.30393406 -38.32020276
OS 38.39639006 -38.32020276
OS 38.56281086 -38.78525644
OS 38.56281086 -38.786181
OS 38.56373542 -38.78803012
OS 38.56465998 -38.7908038
OS 38.5665091 -38.79450204
OS 38.56743366 -38.8000494
OS 38.56928278 -38.80559676
OS 38.57390558 -38.81946516
OS 38.57945294 -38.83518268
OS 38.5850003 -38.85274932
OS 38.59609502 -38.88973172
OS 38.59609502 -38.88880716
OS 38.59701958 -38.88695804
OS 38.59794414 -38.88418436
OS 38.5988687 -38.88048612
OS 38.60164238 -38.87031596
OS 38.60626518 -38.85644756
OS 38.61088798 -38.84073004
OS 38.61643534 -38.8231634
OS 38.62290726 -38.8046722
OS 38.63030374 -38.78525644
OS 38.80412102 -38.32020276
OS 38.8901051 -38.32020276
OS 38.6404739 -38.95999828
OE
OB 39.27564662 -38.42745172 I
OS 39.25438174 -38.54671996
OS 39.20538006 -38.54671996
OS 39.1859643 -38.42745172
OS 39.1859643 -38.32020276
OS 39.27564662 -38.32020276
OS 39.27564662 -38.42745172
OE
OB 40.49791494 -38.4117342 I
OS 40.41932734 -38.4117342
OS 40.41932734 -38.32020276
OS 40.49791494 -38.32020276
OS 40.49791494 -38.4117342
OE
OB 39.84517558 -38.48662356 I
OS 39.8516475 -38.48754812
OS 39.8655159 -38.48939724
OS 39.88215798 -38.49309548
OS 39.89972462 -38.49864284
OS 39.91729126 -38.50696388
OS 39.9348579 -38.51713404
OS 39.93578246 -38.51713404
OS 39.93670702 -38.51898316
OS 39.94225438 -38.5226814
OS 39.95057542 -38.53007788
OS 39.96074558 -38.53932348
OS 39.9718403 -38.55134276
OS 39.98293502 -38.56613572
OS 39.99402974 -38.58370236
OS 40.00327534 -38.60311812
OS 40.00327534 -38.60404268
OS 40.0041999 -38.6058918
OS 40.00512446 -38.60866548
OS 40.00697358 -38.61236372
OS 40.0088227 -38.61791108
OS 40.01067182 -38.624383
OS 40.01529462 -38.63917596
OS 40.01991742 -38.65766716
OS 40.02361566 -38.67800748
OS 40.02638934 -38.70112148
OS 40.0273139 -38.72516004
OS 40.0273139 -38.7260846
OS 40.0273139 -38.72793372
OS 40.0273139 -38.73163196
OS 40.0273139 -38.73717932
OS 40.02638934 -38.74365124
OS 40.02638934 -38.75104772
OS 40.02454022 -38.7676898
OS 40.02084198 -38.78803012
OS 40.01621918 -38.809295
OS 40.00974726 -38.83148444
OS 40.00142622 -38.85367388
OS 40.00142622 -38.85459844
OS 40.00050166 -38.85644756
OS 39.99865254 -38.85922124
OS 39.99680342 -38.86291948
OS 39.9903315 -38.87308964
OS 39.98201046 -38.88603348
OS 39.9718403 -38.89990188
OS 39.95889646 -38.91377028
OS 39.9441035 -38.92763868
OS 39.92653686 -38.94058252
OS 39.9256123 -38.94058252
OS 39.92468774 -38.94150708
OS 39.92191406 -38.9433562
OS 39.91821582 -38.94520532
OS 39.90897022 -38.94982812
OS 39.89602638 -38.95537548
OS 39.88030886 -38.96092284
OS 39.86366678 -38.96554564
OS 39.84425102 -38.96924388
OS 39.82483526 -38.97016844
OS 39.81836334 -38.97016844
OS 39.81096686 -38.96924388
OS 39.80172126 -38.96831932
OS 39.79062654 -38.9664702
OS 39.77860726 -38.96369652
OS 39.76658798 -38.95999828
OS 39.7545687 -38.95445092
OS 39.75364414 -38.95352636
OS 39.74902134 -38.95167724
OS 39.74347398 -38.947979
OS 39.7360775 -38.94243164
OS 39.72868102 -38.93688428
OS 39.71943542 -38.9294878
OS 39.71111438 -38.92116676
OS 39.7037179 -38.91192116
OS 39.7037179 -39.1375138
OS 39.6251303 -39.1375138
OS 39.6251303 -38.49586916
OS 39.69632142 -38.49586916
OS 39.69632142 -38.55689012
OS 39.69724598 -38.555041
OS 39.70094422 -38.55134276
OS 39.70556702 -38.54487084
OS 39.7129635 -38.53747436
OS 39.72128454 -38.52822876
OS 39.73053014 -38.51990772
OS 39.74162486 -38.51158668
OS 39.75271958 -38.5041902
OS 39.7545687 -38.50326564
OS 39.75826694 -38.50141652
OS 39.76566342 -38.49864284
OS 39.77490902 -38.4949446
OS 39.78600374 -38.49124636
OS 39.79894758 -38.48847268
OS 39.81374054 -38.48662356
OS 39.83038262 -38.485699
OS 39.84055278 -38.485699
OS 39.84517558 -38.48662356
OE
OB 44.92193454 -38.40988508 I
OS 44.84334694 -38.40988508
OS 44.84334694 -38.32020276
OS 44.92193454 -38.32020276
OS 44.92193454 -38.40988508
OE
OB 45.24553054 -38.48662356 I
OS 45.25385158 -38.48754812
OS 45.26309718 -38.48939724
OS 45.27326734 -38.49124636
OS 45.28528662 -38.49309548
OS 45.31024974 -38.50141652
OS 45.32319358 -38.50603932
OS 45.33613742 -38.51251124
OS 45.34908126 -38.51898316
OS 45.3620251 -38.52822876
OS 45.37404438 -38.53747436
OS 45.38606366 -38.54856908
OS 45.38698822 -38.54949364
OS 45.38883734 -38.55134276
OS 45.39161102 -38.555041
OS 45.39530926 -38.5596638
OS 45.39993206 -38.56613572
OS 45.40547942 -38.57445676
OS 45.41102678 -38.58370236
OS 45.41657414 -38.59387252
OS 45.4221215 -38.60496724
OS 45.42766886 -38.61883564
OS 45.43321622 -38.63270404
OS 45.43783902 -38.64842156
OS 45.44153726 -38.66506364
OS 45.44431094 -38.68263028
OS 45.44616006 -38.70112148
OS 45.44708462 -38.7214618
OS 45.44708462 -38.72238636
OS 45.44708462 -38.72516004
OS 45.44708462 -38.72978284
OS 45.44708462 -38.73625476
OS 45.44616006 -38.74365124
OS 45.4452355 -38.75289684
OS 45.4452355 -38.76214244
OS 45.44338638 -38.7723126
OS 45.4406127 -38.7954266
OS 45.43506534 -38.8185406
OS 45.42859342 -38.8416546
OS 45.41934782 -38.86291948
OS 45.41934782 -38.86384404
OS 45.41842326 -38.8647686
OS 45.41657414 -38.86754228
OS 45.41472502 -38.87124052
OS 45.4082531 -38.88048612
OS 45.39993206 -38.89158084
OS 45.38883734 -38.90452468
OS 45.37496894 -38.91746852
OS 45.35925142 -38.93041236
OS 45.34076022 -38.94243164
OS 45.33983566 -38.94243164
OS 45.3389111 -38.9433562
OS 45.33613742 -38.94520532
OS 45.33151462 -38.94705444
OS 45.32689182 -38.94890356
OS 45.32134446 -38.95075268
OS 45.30747606 -38.95630004
OS 45.29175854 -38.96092284
OS 45.27234278 -38.96554564
OS 45.25200246 -38.96924388
OS 45.22981302 -38.97016844
OS 45.22056742 -38.97016844
OS 45.21317094 -38.96924388
OS 45.2048499 -38.96831932
OS 45.1956043 -38.9664702
OS 45.18450958 -38.96462108
OS 45.17341486 -38.96277196
OS 45.14845174 -38.95537548
OS 45.13458334 -38.94982812
OS 45.1216395 -38.94428076
OS 45.10869566 -38.93688428
OS 45.09575182 -38.92856324
OS 45.08373254 -38.91931764
OS 45.07171326 -38.90822292
OS 45.0707887 -38.90729836
OS 45.06893958 -38.90544924
OS 45.0661659 -38.901751
OS 45.06246766 -38.89620364
OS 45.05784486 -38.88973172
OS 45.05322206 -38.88233524
OS 45.0476747 -38.87308964
OS 45.04212734 -38.86199492
OS 45.03657998 -38.84997564
OS 45.03103262 -38.83610724
OS 45.02640982 -38.82131428
OS 45.02178702 -38.80559676
OS 45.01808878 -38.78803012
OS 45.0153151 -38.76953892
OS 45.01346598 -38.7491986
OS 45.01254142 -38.72793372
OS 45.01254142 -38.7260846
OS 45.01254142 -38.72238636
OS 45.01346598 -38.71591444
OS 45.01346598 -38.70666884
OS 45.01439054 -38.69649868
OS 45.01623966 -38.68355484
OS 45.01808878 -38.670611
OS 45.02178702 -38.65581804
OS 45.02548526 -38.64102508
OS 45.03010806 -38.62530756
OS 45.03565542 -38.60866548
OS 45.0430519 -38.59294796
OS 45.05044838 -38.578155
OS 45.06061854 -38.56336204
OS 45.0707887 -38.54949364
OS 45.08373254 -38.53747436
OS 45.0846571 -38.5365498
OS 45.08650622 -38.53562524
OS 45.09020446 -38.53285156
OS 45.09482726 -38.52915332
OS 45.10037462 -38.52545508
OS 45.1077711 -38.52083228
OS 45.11516758 -38.51620948
OS 45.12441318 -38.51158668
OS 45.13458334 -38.50696388
OS 45.14567806 -38.50234108
OS 45.17064118 -38.49402004
OS 45.19930254 -38.48754812
OS 45.2140955 -38.48662356
OS 45.22981302 -38.485699
OS 45.23905862 -38.485699
OS 45.24553054 -38.48662356
OE
OB 44.92193454 -38.95999828 I
OS 44.84334694 -38.95999828
OS 44.84334694 -38.49586916
OS 44.92193454 -38.49586916
OS 44.92193454 -38.95999828
OE
OB 46.10722046 -38.42745172 I
OS 46.08595558 -38.54671996
OS 46.0369539 -38.54671996
OS 46.01753814 -38.42745172
OS 46.01753814 -38.32020276
OS 46.10722046 -38.32020276
OS 46.10722046 -38.42745172
OE
OB 45.77160518 -38.48662356 I
OS 45.78177534 -38.48754812
OS 45.79379462 -38.48939724
OS 45.80673846 -38.49217092
OS 45.82060686 -38.49586916
OS 45.8335507 -38.50141652
OS 45.83539982 -38.50234108
OS 45.83909806 -38.5041902
OS 45.84556998 -38.50696388
OS 45.85296646 -38.51158668
OS 45.86221206 -38.51713404
OS 45.8705331 -38.52453052
OS 45.87885414 -38.531927
OS 45.88625062 -38.5411726
OS 45.88717518 -38.54209716
OS 45.8890243 -38.5457954
OS 45.89179798 -38.5504182
OS 45.89642078 -38.55689012
OS 45.90011902 -38.56613572
OS 45.90381726 -38.57538132
OS 45.90844006 -38.58647604
OS 45.91121374 -38.59849532
OS 45.91121374 -38.59941988
OS 45.9121383 -38.60311812
OS 45.91306286 -38.60866548
OS 45.91398742 -38.61606196
OS 45.91398742 -38.62715668
OS 45.91491198 -38.64010052
OS 45.91583654 -38.65581804
OS 45.91583654 -38.6752338
OS 45.91583654 -38.95999828
OS 45.83724894 -38.95999828
OS 45.83724894 -38.67893204
OS 45.83724894 -38.67800748
OS 45.83724894 -38.67708292
OS 45.83724894 -38.670611
OS 45.83724894 -38.66228996
OS 45.83632438 -38.6521198
OS 45.83539982 -38.64010052
OS 45.8335507 -38.62808124
OS 45.83077702 -38.61698652
OS 45.82800334 -38.60681636
OS 45.82800334 -38.6058918
OS 45.82615422 -38.60311812
OS 45.82338054 -38.59849532
OS 45.82060686 -38.59294796
OS 45.81598406 -38.5874006
OS 45.8104367 -38.58092868
OS 45.80304022 -38.57445676
OS 45.79471918 -38.5689094
OS 45.79379462 -38.56798484
OS 45.79102094 -38.56613572
OS 45.78547358 -38.5642866
OS 45.77900166 -38.56151292
OS 45.77160518 -38.55873924
OS 45.76235958 -38.55596556
OS 45.75126486 -38.555041
OS 45.74017014 -38.55411644
OS 45.73554734 -38.55411644
OS 45.7318491 -38.555041
OS 45.7226035 -38.55596556
OS 45.71058422 -38.55781468
OS 45.69764038 -38.56243748
OS 45.68284742 -38.56798484
OS 45.66805446 -38.57538132
OS 45.65418606 -38.58647604
OS 45.65233694 -38.58832516
OS 45.6486387 -38.59294796
OS 45.64586502 -38.5966462
OS 45.64309134 -38.601269
OS 45.6393931 -38.60681636
OS 45.63661942 -38.61328828
OS 45.63292118 -38.62068476
OS 45.62922294 -38.62993036
OS 45.62644926 -38.64010052
OS 45.62367558 -38.65119524
OS 45.62182646 -38.66321452
OS 45.61997734 -38.67615836
OS 45.61812822 -38.69187588
OS 45.61812822 -38.7075934
OS 45.61812822 -38.95999828
OS 45.53954062 -38.95999828
OS 45.53954062 -38.49586916
OS 45.60980718 -38.49586916
OS 45.60980718 -38.56243748
OS 45.61073174 -38.56151292
OS 45.61258086 -38.55873924
OS 45.61535454 -38.555041
OS 45.61905278 -38.5504182
OS 45.62460014 -38.54487084
OS 45.63107206 -38.53839892
OS 45.63846854 -38.53100244
OS 45.64771414 -38.52360596
OS 45.65695974 -38.51713404
OS 45.66805446 -38.50973756
OS 45.68007374 -38.50326564
OS 45.69301758 -38.49771828
OS 45.70781054 -38.49309548
OS 45.7226035 -38.48939724
OS 45.73924558 -38.48662356
OS 45.75681222 -38.485699
OS 45.7642087 -38.485699
OS 45.77160518 -38.48662356
OE
OB 44.2756671 -38.95999828 I
OS 44.1970795 -38.95999828
OS 44.1970795 -38.49586916
OS 44.2756671 -38.49586916
OS 44.2756671 -38.95999828
OE
OB 43.4574315 -38.48662356 I
OS 43.46482798 -38.48754812
OS 43.47407358 -38.48939724
OS 43.48424374 -38.49124636
OS 43.49626302 -38.49402004
OS 43.50735774 -38.49679372
OS 43.52030158 -38.50141652
OS 43.53232086 -38.50603932
OS 43.5452647 -38.51251124
OS 43.55820854 -38.51990772
OS 43.57115238 -38.52822876
OS 43.58317166 -38.53839892
OS 43.59426638 -38.54949364
OS 43.59519094 -38.5504182
OS 43.59704006 -38.55226732
OS 43.59981374 -38.55596556
OS 43.60351198 -38.56151292
OS 43.60813478 -38.56798484
OS 43.61275758 -38.57538132
OS 43.61830494 -38.58462692
OS 43.6238523 -38.59572164
OS 43.62939966 -38.60774092
OS 43.63494702 -38.62068476
OS 43.63956982 -38.63547772
OS 43.64419262 -38.65119524
OS 43.64789086 -38.66876188
OS 43.65066454 -38.68725308
OS 43.65251366 -38.70666884
OS 43.65343822 -38.72793372
OS 43.65343822 -38.72885828
OS 43.65343822 -38.73255652
OS 43.65343822 -38.73902844
OS 43.65251366 -38.74827404
OS 43.30580366 -38.74827404
OS 43.30580366 -38.7491986
OS 43.30580366 -38.75197228
OS 43.30672822 -38.75567052
OS 43.30672822 -38.76121788
OS 43.30765278 -38.7676898
OS 43.3095019 -38.77508628
OS 43.31227558 -38.79172836
OS 43.31782294 -38.81021956
OS 43.32521942 -38.83055988
OS 43.33538958 -38.84905108
OS 43.34833342 -38.86569316
OS 43.34925798 -38.86569316
OS 43.35018254 -38.86754228
OS 43.3557299 -38.87216508
OS 43.36405094 -38.878637
OS 43.37514566 -38.88510892
OS 43.38993862 -38.8925054
OS 43.4065807 -38.89897732
OS 43.4250719 -38.90360012
OS 43.43524206 -38.90452468
OS 43.44633678 -38.90544924
OS 43.45373326 -38.90544924
OS 43.4620543 -38.90452468
OS 43.47222446 -38.90267556
OS 43.48331918 -38.89990188
OS 43.49626302 -38.89620364
OS 43.5082823 -38.89065628
OS 43.52030158 -38.8832598
OS 43.52122614 -38.88233524
OS 43.52584894 -38.878637
OS 43.5313963 -38.87308964
OS 43.53786822 -38.86569316
OS 43.5452647 -38.855523
OS 43.55358574 -38.84257916
OS 43.56190678 -38.8277862
OS 43.56930326 -38.81021956
OS 43.65066454 -38.82038972
OS 43.65066454 -38.82131428
OS 43.64973998 -38.8231634
OS 43.64881542 -38.82686164
OS 43.6469663 -38.832409
OS 43.64419262 -38.83795636
OS 43.64141894 -38.84535284
OS 43.63402246 -38.86107036
OS 43.62477686 -38.878637
OS 43.61183302 -38.8971282
OS 43.59704006 -38.91469484
OS 43.57854886 -38.93133692
OS 43.5776243 -38.93133692
OS 43.57577518 -38.93318604
OS 43.5730015 -38.93503516
OS 43.56930326 -38.93780884
OS 43.5637559 -38.94058252
OS 43.55820854 -38.9433562
OS 43.55081206 -38.94705444
OS 43.54249102 -38.95075268
OS 43.53324542 -38.95445092
OS 43.52399982 -38.95814916
OS 43.50088582 -38.96369652
OS 43.47499814 -38.96831932
OS 43.44633678 -38.97016844
OS 43.43616662 -38.97016844
OS 43.4296947 -38.96924388
OS 43.42137366 -38.96831932
OS 43.4112035 -38.9664702
OS 43.40010878 -38.96462108
OS 43.3880895 -38.96277196
OS 43.36220182 -38.95537548
OS 43.34833342 -38.94982812
OS 43.33538958 -38.94428076
OS 43.32152118 -38.93688428
OS 43.30857734 -38.92856324
OS 43.29655806 -38.91931764
OS 43.28453878 -38.90822292
OS 43.28361422 -38.90729836
OS 43.2817651 -38.90544924
OS 43.27899142 -38.901751
OS 43.27529318 -38.89620364
OS 43.27067038 -38.88973172
OS 43.26604758 -38.88233524
OS 43.26050022 -38.87308964
OS 43.25495286 -38.86291948
OS 43.2494055 -38.8509002
OS 43.24385814 -38.83795636
OS 43.23923534 -38.8231634
OS 43.23461254 -38.80744588
OS 43.2309143 -38.7908038
OS 43.22814062 -38.7723126
OS 43.2262915 -38.75289684
OS 43.22536694 -38.73255652
OS 43.22536694 -38.73163196
OS 43.22536694 -38.72700916
OS 43.22536694 -38.7214618
OS 43.2262915 -38.71314076
OS 43.22721606 -38.7029706
OS 43.22814062 -38.69187588
OS 43.22998974 -38.67893204
OS 43.23276342 -38.6659882
OS 43.2401599 -38.63640228
OS 43.2447827 -38.62160932
OS 43.25033006 -38.6058918
OS 43.25772654 -38.59109884
OS 43.26604758 -38.57723044
OS 43.27529318 -38.56336204
OS 43.28546334 -38.5504182
OS 43.2863879 -38.54949364
OS 43.28823702 -38.54764452
OS 43.29193526 -38.54487084
OS 43.29655806 -38.54024804
OS 43.30210542 -38.53562524
OS 43.3095019 -38.53007788
OS 43.31782294 -38.52360596
OS 43.3279931 -38.5180586
OS 43.33816326 -38.51158668
OS 43.35018254 -38.50603932
OS 43.36312638 -38.50049196
OS 43.37699478 -38.49586916
OS 43.39178774 -38.49124636
OS 43.40750526 -38.48847268
OS 43.42414734 -38.48662356
OS 43.44171398 -38.485699
OS 43.45095958 -38.485699
OS 43.4574315 -38.48662356
OE
OB 43.13938286 -38.48662356 I
OS 43.14955302 -38.48847268
OS 43.1615723 -38.49217092
OS 43.17451614 -38.49679372
OS 43.1893091 -38.50326564
OS 43.20502662 -38.51158668
OS 43.17636526 -38.58370236
OS 43.1754407 -38.5827778
OS 43.17174246 -38.58092868
OS 43.1661951 -38.578155
OS 43.15879862 -38.57538132
OS 43.15047758 -38.57260764
OS 43.14030742 -38.56983396
OS 43.13013726 -38.56798484
OS 43.1199671 -38.56706028
OS 43.1153443 -38.56706028
OS 43.1107215 -38.56798484
OS 43.10424958 -38.5689094
OS 43.09777766 -38.57075852
OS 43.08945662 -38.5735322
OS 43.08113558 -38.57723044
OS 43.0737391 -38.5827778
OS 43.07281454 -38.58370236
OS 43.07004086 -38.58555148
OS 43.06726718 -38.58924972
OS 43.06264438 -38.59387252
OS 43.05802158 -38.60034444
OS 43.05339878 -38.60774092
OS 43.04877598 -38.61606196
OS 43.04507774 -38.62623212
OS 43.04415318 -38.62808124
OS 43.04322862 -38.6336286
OS 43.0413795 -38.64194964
OS 43.03860582 -38.65304436
OS 43.03583214 -38.66691276
OS 43.03398302 -38.68263028
OS 43.03305846 -38.69927236
OS 43.0321339 -38.71776356
OS 43.0321339 -38.95999828
OS 42.9535463 -38.95999828
OS 42.9535463 -38.49586916
OS 43.02473742 -38.49586916
OS 43.02473742 -38.56613572
OS 43.02566198 -38.56521116
OS 43.02936022 -38.55873924
OS 43.03398302 -38.5504182
OS 43.0413795 -38.54024804
OS 43.04877598 -38.53007788
OS 43.05709702 -38.51898316
OS 43.06541806 -38.50973756
OS 43.0737391 -38.50234108
OS 43.07466366 -38.50141652
OS 43.07743734 -38.4995674
OS 43.0829847 -38.49679372
OS 43.08853206 -38.49402004
OS 43.09592854 -38.49124636
OS 43.10517414 -38.48847268
OS 43.11441974 -38.48662356
OS 43.1245899 -38.485699
OS 43.13106182 -38.485699
OS 43.13938286 -38.48662356
OE
OB 43.95022198 -38.95999828 I
OS 43.87533262 -38.95999828
OS 43.70059078 -38.49586916
OS 43.78380118 -38.49586916
OS 43.88365366 -38.77416172
OS 43.88365366 -38.77508628
OS 43.88457822 -38.77601084
OS 43.88550278 -38.77878452
OS 43.88642734 -38.7815582
OS 43.88920102 -38.7908038
OS 43.89289926 -38.80282308
OS 43.89752206 -38.81669148
OS 43.90306942 -38.832409
OS 43.90769222 -38.84997564
OS 43.91323958 -38.86754228
OS 43.91416414 -38.86569316
OS 43.9150887 -38.86107036
OS 43.91786238 -38.85367388
OS 43.92063606 -38.84257916
OS 43.92525886 -38.83055988
OS 43.92988166 -38.81484236
OS 43.93635358 -38.79820028
OS 43.9428255 -38.77970908
OS 44.04545166 -38.49586916
OS 44.12681294 -38.49586916
OS 43.95022198 -38.95999828
OE
OB 44.2756671 -38.40988508 I
OS 44.1970795 -38.40988508
OS 44.1970795 -38.32020276
OS 44.2756671 -38.32020276
OS 44.2756671 -38.40988508
OE
OB 44.5669035 -38.48662356 I
OS 44.5807719 -38.48754812
OS 44.59556486 -38.48939724
OS 44.61128238 -38.49309548
OS 44.62792446 -38.49679372
OS 44.64364198 -38.50234108
OS 44.64456654 -38.50234108
OS 44.6454911 -38.50326564
OS 44.6501139 -38.50511476
OS 44.65751038 -38.508813
OS 44.66675598 -38.5134358
OS 44.67692614 -38.51990772
OS 44.6870963 -38.5273042
OS 44.6963419 -38.53562524
OS 44.70466294 -38.54487084
OS 44.7055875 -38.5457954
OS 44.70743662 -38.54949364
OS 44.71113486 -38.55596556
OS 44.71575766 -38.56336204
OS 44.72038046 -38.57445676
OS 44.72500326 -38.58647604
OS 44.7287015 -38.60034444
OS 44.73239974 -38.61606196
OS 44.65566126 -38.62623212
OS 44.65566126 -38.624383
OS 44.6547367 -38.62068476
OS 44.65288758 -38.61421284
OS 44.6501139 -38.6058918
OS 44.6454911 -38.59757076
OS 44.63994374 -38.58832516
OS 44.63347182 -38.57907956
OS 44.62422622 -38.57075852
OS 44.62330166 -38.56983396
OS 44.61960342 -38.56798484
OS 44.61405606 -38.5642866
OS 44.60573502 -38.56058836
OS 44.59648942 -38.55689012
OS 44.58447014 -38.55319188
OS 44.56967718 -38.55134276
OS 44.55395966 -38.5504182
OS 44.54471406 -38.5504182
OS 44.53546846 -38.55134276
OS 44.52344918 -38.55226732
OS 44.5114299 -38.555041
OS 44.49848606 -38.55781468
OS 44.48646678 -38.56243748
OS 44.47629662 -38.5689094
OS 44.47537206 -38.56983396
OS 44.47259838 -38.57168308
OS 44.46890014 -38.57538132
OS 44.4652019 -38.58092868
OS 44.4605791 -38.58647604
OS 44.45688086 -38.59387252
OS 44.45410718 -38.60219356
OS 44.45318262 -38.6105146
OS 44.45318262 -38.61143916
OS 44.45318262 -38.61328828
OS 44.45410718 -38.61606196
OS 44.45410718 -38.6197602
OS 44.45688086 -38.6290058
OS 44.46242822 -38.6382514
OS 44.46335278 -38.63917596
OS 44.46427734 -38.64010052
OS 44.46612646 -38.6428742
OS 44.4698247 -38.64564788
OS 44.47352294 -38.64842156
OS 44.4790703 -38.6521198
OS 44.48554222 -38.65489348
OS 44.4929387 -38.65859172
OS 44.49386326 -38.65859172
OS 44.49571238 -38.65951628
OS 44.49941062 -38.66044084
OS 44.50588254 -38.66321452
OS 44.51512814 -38.6659882
OS 44.52714742 -38.66876188
OS 44.5345439 -38.67153556
OS 44.54286494 -38.67338468
OS 44.55211054 -38.67615836
OS 44.5622807 -38.67893204
OS 44.56320526 -38.67893204
OS 44.56597894 -38.6798566
OS 44.57060174 -38.68078116
OS 44.5761491 -38.68263028
OS 44.58262102 -38.6844794
OS 44.59094206 -38.68632852
OS 44.6085087 -38.69187588
OS 44.62792446 -38.69742324
OS 44.64734022 -38.70389516
OS 44.66490686 -38.71036708
OS 44.67230334 -38.71314076
OS 44.67877526 -38.71591444
OS 44.68062438 -38.716839
OS 44.68432262 -38.71868812
OS 44.68986998 -38.7214618
OS 44.69819102 -38.7260846
OS 44.70651206 -38.73163196
OS 44.7148331 -38.73902844
OS 44.72315414 -38.74734948
OS 44.73055062 -38.75659508
OS 44.73147518 -38.75751964
OS 44.7333243 -38.76121788
OS 44.73702254 -38.76676524
OS 44.74072078 -38.77508628
OS 44.74349446 -38.78525644
OS 44.7471927 -38.79635116
OS 44.74904182 -38.809295
OS 44.74996638 -38.82408796
OS 44.74996638 -38.82593708
OS 44.74996638 -38.83055988
OS 44.74904182 -38.83795636
OS 44.7471927 -38.84812652
OS 44.74441902 -38.85922124
OS 44.73979622 -38.87124052
OS 44.73424886 -38.88510892
OS 44.72685238 -38.89805276
OS 44.72592782 -38.89990188
OS 44.72222958 -38.90360012
OS 44.71760678 -38.91007204
OS 44.7102103 -38.91746852
OS 44.70004014 -38.92578956
OS 44.68894542 -38.93503516
OS 44.67600158 -38.9433562
OS 44.66028406 -38.95167724
OS 44.6593595 -38.95167724
OS 44.65843494 -38.9526018
OS 44.65288758 -38.95445092
OS 44.64364198 -38.9572246
OS 44.6316227 -38.96092284
OS 44.61682974 -38.96462108
OS 44.60018766 -38.96739476
OS 44.58262102 -38.96924388
OS 44.5622807 -38.97016844
OS 44.55395966 -38.97016844
OS 44.54748774 -38.96924388
OS 44.54009126 -38.96924388
OS 44.53084566 -38.96831932
OS 44.52160006 -38.96739476
OS 44.5114299 -38.96554564
OS 44.48924046 -38.96092284
OS 44.46612646 -38.95445092
OS 44.44393702 -38.94520532
OS 44.43376686 -38.93965796
OS 44.42452126 -38.93318604
OS 44.4235967 -38.93226148
OS 44.42267214 -38.93133692
OS 44.41712478 -38.92578956
OS 44.40880374 -38.91746852
OS 44.39955814 -38.90452468
OS 44.38938798 -38.88880716
OS 44.37921782 -38.87031596
OS 44.37089678 -38.84720196
OS 44.36442486 -38.82131428
OS 44.4420879 -38.809295
OS 44.4420879 -38.81021956
OS 44.4420879 -38.81114412
OS 44.44393702 -38.81669148
OS 44.44578614 -38.82593708
OS 44.44948438 -38.83610724
OS 44.45410718 -38.84720196
OS 44.45965454 -38.85922124
OS 44.46797558 -38.87124052
OS 44.47814574 -38.88141068
OS 44.47999486 -38.88233524
OS 44.4836931 -38.88510892
OS 44.49108958 -38.88880716
OS 44.50033518 -38.89342996
OS 44.51235446 -38.89805276
OS 44.52622286 -38.901751
OS 44.54286494 -38.90452468
OS 44.5622807 -38.90544924
OS 44.5715263 -38.90544924
OS 44.5807719 -38.90452468
OS 44.59279118 -38.90267556
OS 44.60573502 -38.89990188
OS 44.61960342 -38.89620364
OS 44.6316227 -38.89158084
OS 44.64271742 -38.88418436
OS 44.64364198 -38.8832598
OS 44.64734022 -38.88048612
OS 44.65103846 -38.87586332
OS 44.65658582 -38.8693914
OS 44.66120862 -38.86199492
OS 44.66583142 -38.85274932
OS 44.6686051 -38.84350372
OS 44.66952966 -38.832409
OS 44.66952966 -38.83148444
OS 44.66952966 -38.8277862
OS 44.6686051 -38.8231634
OS 44.66675598 -38.81669148
OS 44.6639823 -38.81021956
OS 44.6593595 -38.80374764
OS 44.65381214 -38.79635116
OS 44.6454911 -38.7908038
OS 44.64456654 -38.78987924
OS 44.64179286 -38.78895468
OS 44.63717006 -38.786181
OS 44.62977358 -38.78340732
OS 44.61867886 -38.77970908
OS 44.61220694 -38.7769354
OS 44.60481046 -38.77508628
OS 44.59648942 -38.7723126
OS 44.58724382 -38.76953892
OS 44.57707366 -38.76676524
OS 44.56505438 -38.76399156
OS 44.56412982 -38.76399156
OS 44.56135614 -38.763067
OS 44.55673334 -38.76214244
OS 44.55118598 -38.76029332
OS 44.5437895 -38.7584442
OS 44.53546846 -38.75567052
OS 44.51790182 -38.75104772
OS 44.4975615 -38.7445758
OS 44.47814574 -38.73902844
OS 44.45965454 -38.73255652
OS 44.4513335 -38.72885828
OS 44.44486158 -38.7260846
OS 44.44301246 -38.72516004
OS 44.43931422 -38.72331092
OS 44.43376686 -38.71961268
OS 44.42637038 -38.71498988
OS 44.41804934 -38.70851796
OS 44.4097283 -38.70112148
OS 44.40140726 -38.69280044
OS 44.39401078 -38.68263028
OS 44.39308622 -38.68170572
OS 44.3912371 -38.67800748
OS 44.38846342 -38.67153556
OS 44.38568974 -38.66413908
OS 44.38291606 -38.65489348
OS 44.38014238 -38.64379876
OS 44.37829326 -38.63270404
OS 44.3773687 -38.6197602
OS 44.3773687 -38.61791108
OS 44.3773687 -38.61421284
OS 44.37829326 -38.60866548
OS 44.37921782 -38.60034444
OS 44.38106694 -38.5920234
OS 44.38291606 -38.58185324
OS 44.3866143 -38.57260764
OS 44.3912371 -38.56243748
OS 44.39216166 -38.56151292
OS 44.39401078 -38.55781468
OS 44.39678446 -38.55319188
OS 44.40140726 -38.54671996
OS 44.40695462 -38.54024804
OS 44.41342654 -38.531927
OS 44.42082302 -38.52453052
OS 44.43006862 -38.5180586
OS 44.43099318 -38.51713404
OS 44.43376686 -38.51620948
OS 44.4374651 -38.5134358
OS 44.44301246 -38.51066212
OS 44.45040894 -38.50696388
OS 44.45872998 -38.50326564
OS 44.46890014 -38.4995674
OS 44.47999486 -38.49586916
OS 44.48184398 -38.4949446
OS 44.48554222 -38.49402004
OS 44.49201414 -38.49217092
OS 44.50033518 -38.4903218
OS 44.51050534 -38.48847268
OS 44.52160006 -38.48754812
OS 44.5345439 -38.485699
OS 44.55673334 -38.485699
OS 44.5669035 -38.48662356
OE
OB 33.15968222 -38.32112732 I
OS 33.17539974 -38.32205188
OS 33.19204182 -38.32297644
OS 33.20775934 -38.32482556
OS 33.22162774 -38.32667468
OS 33.22347686 -38.32667468
OS 33.22994878 -38.3285238
OS 33.23826982 -38.33037292
OS 33.24936454 -38.3331466
OS 33.26138382 -38.3377694
OS 33.27432766 -38.34331676
OS 33.28819606 -38.34978868
OS 33.30021534 -38.35718516
OS 33.30206446 -38.35810972
OS 33.3057627 -38.3608834
OS 33.31131006 -38.36643076
OS 33.31870654 -38.37290268
OS 33.32702758 -38.38122372
OS 33.33534862 -38.39231844
OS 33.34459422 -38.40433772
OS 33.3519907 -38.41820612
OS 33.35291526 -38.42005524
OS 33.35476438 -38.42467804
OS 33.35846262 -38.43299908
OS 33.36216086 -38.4440938
OS 33.36493454 -38.45703764
OS 33.36863278 -38.4718306
OS 33.3704819 -38.48847268
OS 33.37140646 -38.50603932
OS 33.37140646 -38.50696388
OS 33.37140646 -38.50973756
OS 33.37140646 -38.5134358
OS 33.3704819 -38.51990772
OS 33.36955734 -38.52637964
OS 33.36863278 -38.53470068
OS 33.36678366 -38.54394628
OS 33.36493454 -38.55411644
OS 33.35846262 -38.57538132
OS 33.35476438 -38.58647604
OS 33.34921702 -38.59849532
OS 33.3427451 -38.6105146
OS 33.33627318 -38.62160932
OS 33.32795214 -38.63270404
OS 33.31870654 -38.64379876
OS 33.31778198 -38.64472332
OS 33.31593286 -38.64657244
OS 33.31315918 -38.64934612
OS 33.30853638 -38.6521198
OS 33.30298902 -38.6567426
OS 33.29559254 -38.6613654
OS 33.28634694 -38.66691276
OS 33.27617678 -38.67153556
OS 33.2641575 -38.67708292
OS 33.2502891 -38.68263028
OS 33.23549614 -38.68725308
OS 33.2179295 -38.69095132
OS 33.1994383 -38.69464956
OS 33.17909798 -38.69742324
OS 33.15598398 -38.69927236
OS 33.13194542 -38.70019692
OS 32.9682983 -38.70019692
OS 32.9682983 -38.95999828
OS 32.88323878 -38.95999828
OS 32.88323878 -38.32020276
OS 33.14581382 -38.32020276
OS 33.15968222 -38.32112732
OE
OB 32.75195126 -38.98403684 I
OS 32.75195126 -38.9849614
OS 32.75195126 -38.98773508
OS 32.75195126 -38.99235788
OS 32.75195126 -38.99790524
OS 32.7510267 -39.00530172
OS 32.7510267 -39.0126982
OS 32.74917758 -39.0311894
OS 32.7464039 -39.05060516
OS 32.74270566 -39.07094548
OS 32.7371583 -39.08851212
OS 32.73346006 -39.09683316
OS 32.72976182 -39.10330508
OS 32.72976182 -39.10422964
OS 32.72883726 -39.1051542
OS 32.72421446 -39.109777
OS 32.71681798 -39.11717348
OS 32.70757238 -39.12549452
OS 32.69462854 -39.13381556
OS 32.67798646 -39.14028748
OS 32.6585707 -39.14583484
OS 32.64747598 -39.1467594
OS 32.6354567 -39.14768396
OS 32.62990934 -39.14768396
OS 32.62436198 -39.1467594
OS 32.61604094 -39.1467594
OS 32.60679534 -39.14583484
OS 32.59662518 -39.14398572
OS 32.57443574 -39.13843836
OS 32.5892287 -39.07187004
OS 32.59015326 -39.07187004
OS 32.59292694 -39.0727946
OS 32.59754974 -39.07371916
OS 32.60217254 -39.07464372
OS 32.61419182 -39.0774174
OS 32.61973918 -39.07834196
OS 32.62898478 -39.07834196
OS 32.63360758 -39.0774174
OS 32.63915494 -39.07649284
OS 32.6447023 -39.07464372
OS 32.65024966 -39.07094548
OS 32.65672158 -39.06724724
OS 32.66134438 -39.06169988
OS 32.66226894 -39.06077532
OS 32.6631935 -39.05800164
OS 32.66504262 -39.05337884
OS 32.6678163 -39.04598236
OS 32.66966542 -39.0358122
OS 32.67058998 -39.02841572
OS 32.67151454 -39.0219438
OS 32.6724391 -39.01362276
OS 32.6724391 -39.0034526
OS 32.67336366 -38.99328244
OS 32.67336366 -38.98218772
OS 32.67336366 -38.49586916
OS 32.75195126 -38.49586916
OS 32.75195126 -38.98403684
OE
OB 33.77174094 -38.3100326 I
OS 33.78006198 -38.31095716
OS 33.79023214 -38.31188172
OS 33.8004023 -38.31280628
OS 33.81242158 -38.31557996
OS 33.8373847 -38.32112732
OS 33.8651215 -38.32944836
OS 33.8789899 -38.33499572
OS 33.89193374 -38.34146764
OS 33.90487758 -38.34978868
OS 33.91782142 -38.35810972
OS 33.91874598 -38.35903428
OS 33.9205951 -38.35995884
OS 33.92429334 -38.36273252
OS 33.92891614 -38.36735532
OS 33.93353894 -38.37197812
OS 33.94001086 -38.37845004
OS 33.94648278 -38.38584652
OS 33.95387926 -38.393243
OS 33.96127574 -38.4024886
OS 33.96867222 -38.41358332
OS 33.97699326 -38.42467804
OS 33.98438974 -38.43669732
OS 33.99086166 -38.45056572
OS 33.99825814 -38.46443412
OS 34.0038055 -38.47922708
OS 34.00935286 -38.49586916
OS 33.92614246 -38.51528492
OS 33.92614246 -38.51436036
OS 33.9252179 -38.51251124
OS 33.92336878 -38.508813
OS 33.92151966 -38.5041902
OS 33.91967054 -38.49864284
OS 33.91689686 -38.49124636
OS 33.90950038 -38.4764534
OS 33.90025478 -38.45981132
OS 33.88916006 -38.44316924
OS 33.87529166 -38.42745172
OS 33.8604987 -38.41358332
OS 33.85864958 -38.4117342
OS 33.85310222 -38.40803596
OS 33.84385662 -38.40341316
OS 33.83183734 -38.39694124
OS 33.81611982 -38.39139388
OS 33.79855318 -38.38584652
OS 33.7772883 -38.38214828
OS 33.7541743 -38.38122372
OS 33.74677782 -38.38122372
OS 33.74215502 -38.38214828
OS 33.7356831 -38.38214828
OS 33.72828662 -38.38307284
OS 33.71071998 -38.38584652
OS 33.69130422 -38.38954476
OS 33.6709639 -38.39601668
OS 33.64969902 -38.40526228
OS 33.63028326 -38.41728156
OS 33.6293587 -38.41728156
OS 33.62843414 -38.41913068
OS 33.62196222 -38.42375348
OS 33.61364118 -38.43114996
OS 33.60347102 -38.44224468
OS 33.59145174 -38.45611308
OS 33.58035702 -38.4718306
OS 33.57018686 -38.49124636
OS 33.56094126 -38.51251124
OS 33.56094126 -38.5134358
OS 33.5600167 -38.51528492
OS 33.55909214 -38.5180586
OS 33.55816758 -38.5226814
OS 33.55631846 -38.52822876
OS 33.55446934 -38.53470068
OS 33.55169566 -38.5504182
OS 33.54799742 -38.5689094
OS 33.54429918 -38.58924972
OS 33.54245006 -38.61143916
OS 33.5415255 -38.63547772
OS 33.5415255 -38.63640228
OS 33.5415255 -38.63917596
OS 33.5415255 -38.64379876
OS 33.5415255 -38.64934612
OS 33.54245006 -38.65581804
OS 33.54245006 -38.66413908
OS 33.54337462 -38.67338468
OS 33.54429918 -38.68355484
OS 33.54707286 -38.70574428
OS 33.55169566 -38.72978284
OS 33.55724302 -38.7538214
OS 33.5646395 -38.77785996
OS 33.5646395 -38.77878452
OS 33.56556406 -38.78063364
OS 33.56741318 -38.78340732
OS 33.5692623 -38.78803012
OS 33.57480966 -38.79912484
OS 33.5831307 -38.81206868
OS 33.59330086 -38.82686164
OS 33.6062447 -38.84257916
OS 33.62103766 -38.85644756
OS 33.6386043 -38.8693914
OS 33.63952886 -38.8693914
OS 33.64137798 -38.87031596
OS 33.64415166 -38.87216508
OS 33.6478499 -38.8740142
OS 33.6524727 -38.87586332
OS 33.65802006 -38.878637
OS 33.6709639 -38.88418436
OS 33.68760598 -38.88973172
OS 33.70609718 -38.89435452
OS 33.7264375 -38.89805276
OS 33.74770238 -38.89897732
OS 33.7541743 -38.89897732
OS 33.75972166 -38.89805276
OS 33.76619358 -38.89805276
OS 33.7726655 -38.8971282
OS 33.78930758 -38.89342996
OS 33.80872334 -38.88880716
OS 33.8281391 -38.88141068
OS 33.84847942 -38.87124052
OS 33.85864958 -38.86569316
OS 33.86789518 -38.85829668
OS 33.86881974 -38.85737212
OS 33.8697443 -38.85644756
OS 33.87251798 -38.85367388
OS 33.87621622 -38.8509002
OS 33.87991446 -38.8462774
OS 33.88453726 -38.84073004
OS 33.89008462 -38.83518268
OS 33.89470742 -38.8277862
OS 33.90025478 -38.81946516
OS 33.9067267 -38.81021956
OS 33.91227406 -38.80097396
OS 33.91782142 -38.78987924
OS 33.92244422 -38.77785996
OS 33.92706702 -38.76491612
OS 33.93168982 -38.75104772
OS 33.93538806 -38.73625476
OS 34.02044758 -38.75751964
OS 34.02044758 -38.7584442
OS 34.01952302 -38.76214244
OS 34.0176739 -38.7676898
OS 34.01490022 -38.77508628
OS 34.01212654 -38.78340732
OS 34.0084283 -38.79357748
OS 34.0038055 -38.8046722
OS 33.99825814 -38.81669148
OS 33.9853143 -38.84257916
OS 33.96867222 -38.86846684
OS 33.95850206 -38.88141068
OS 33.9483319 -38.89435452
OS 33.93723718 -38.90544924
OS 33.92429334 -38.91654396
OS 33.92336878 -38.91746852
OS 33.92151966 -38.91931764
OS 33.91689686 -38.92116676
OS 33.91227406 -38.924865
OS 33.90487758 -38.9294878
OS 33.8974811 -38.9341106
OS 33.88731094 -38.9387334
OS 33.87714078 -38.9433562
OS 33.8651215 -38.94890356
OS 33.85217766 -38.95352636
OS 33.83830926 -38.95814916
OS 33.8235163 -38.96277196
OS 33.80779878 -38.9664702
OS 33.7911567 -38.96831932
OS 33.77359006 -38.97016844
OS 33.75509886 -38.971093
OS 33.7449287 -38.971093
OS 33.73753222 -38.97016844
OS 33.72921118 -38.97016844
OS 33.71904102 -38.96924388
OS 33.7079463 -38.96739476
OS 33.69500246 -38.96554564
OS 33.66819022 -38.96092284
OS 33.64045342 -38.95352636
OS 33.61271662 -38.9433562
OS 33.59977278 -38.93688428
OS 33.58682894 -38.9294878
OS 33.58590438 -38.92856324
OS 33.58405526 -38.92763868
OS 33.58035702 -38.924865
OS 33.57665878 -38.92116676
OS 33.57111142 -38.91746852
OS 33.5646395 -38.91192116
OS 33.55724302 -38.90544924
OS 33.54984654 -38.89805276
OS 33.54245006 -38.88973172
OS 33.53412902 -38.88141068
OS 33.51748694 -38.8601458
OS 33.50176942 -38.83518268
OS 33.48790102 -38.80744588
OS 33.48790102 -38.80652132
OS 33.4860519 -38.80374764
OS 33.48512734 -38.79912484
OS 33.48235366 -38.79357748
OS 33.48050454 -38.786181
OS 33.47773086 -38.7769354
OS 33.47403262 -38.76676524
OS 33.47125894 -38.75567052
OS 33.46848526 -38.74365124
OS 33.46478702 -38.72978284
OS 33.46016422 -38.70112148
OS 33.45646598 -38.66876188
OS 33.45461686 -38.63547772
OS 33.45461686 -38.63455316
OS 33.45461686 -38.63085492
OS 33.45461686 -38.62530756
OS 33.45554142 -38.61883564
OS 33.45554142 -38.60959004
OS 33.45646598 -38.60034444
OS 33.45739054 -38.58832516
OS 33.45923966 -38.57630588
OS 33.46386246 -38.54949364
OS 33.47033438 -38.51990772
OS 33.47957998 -38.4903218
OS 33.49252382 -38.46166044
OS 33.49344838 -38.46073588
OS 33.49437294 -38.4579622
OS 33.49622206 -38.45426396
OS 33.4999203 -38.44964116
OS 33.50361854 -38.44316924
OS 33.50824134 -38.43577276
OS 33.52026062 -38.41913068
OS 33.53597814 -38.40063948
OS 33.55446934 -38.38214828
OS 33.57573422 -38.36365708
OS 33.60069734 -38.34793956
OS 33.6016219 -38.347015
OS 33.60439558 -38.34609044
OS 33.60809382 -38.34424132
OS 33.61271662 -38.34146764
OS 33.6201131 -38.33869396
OS 33.62750958 -38.33592028
OS 33.63675518 -38.33222204
OS 33.64692534 -38.3285238
OS 33.65802006 -38.32482556
OS 33.67003934 -38.32112732
OS 33.69592702 -38.31557996
OS 33.72551294 -38.31095716
OS 33.75602342 -38.30910804
OS 33.76526902 -38.30910804
OS 33.77174094 -38.3100326
OE
OB 35.15858094 -39.1375138 I
OS 34.63805366 -39.1375138
OS 34.63805366 -39.08111564
OS 35.15858094 -39.08111564
OS 35.15858094 -39.1375138
OE
OB 34.37917686 -38.32112732 I
OS 34.38657334 -38.32112732
OS 34.40321542 -38.32297644
OS 34.42170662 -38.32482556
OS 34.44112238 -38.3285238
OS 34.46053814 -38.3331466
OS 34.47810478 -38.33961852
OS 34.47902934 -38.33961852
OS 34.4799539 -38.34054308
OS 34.48550126 -38.34331676
OS 34.4938223 -38.34793956
OS 34.5030679 -38.35441148
OS 34.51416262 -38.36273252
OS 34.5261819 -38.37290268
OS 34.53727662 -38.38584652
OS 34.54744678 -38.39971492
OS 34.54837134 -38.40156404
OS 34.55114502 -38.4071114
OS 34.55576782 -38.41450788
OS 34.56039062 -38.4256026
OS 34.56501342 -38.43854644
OS 34.56963622 -38.45241484
OS 34.5724099 -38.46813236
OS 34.57333446 -38.48384988
OS 34.57333446 -38.485699
OS 34.57333446 -38.4903218
OS 34.5724099 -38.49864284
OS 34.57056078 -38.508813
OS 34.5677871 -38.52083228
OS 34.5631643 -38.53377612
OS 34.55761694 -38.54671996
OS 34.55022046 -38.56058836
OS 34.5492959 -38.56243748
OS 34.54652222 -38.56613572
OS 34.54097486 -38.5735322
OS 34.53357838 -38.58092868
OS 34.52433278 -38.59017428
OS 34.51323806 -38.60034444
OS 34.49936966 -38.60959004
OS 34.48365214 -38.61883564
OS 34.4845767 -38.61883564
OS 34.48642582 -38.6197602
OS 34.4891995 -38.62068476
OS 34.49289774 -38.62253388
OS 34.50399246 -38.62623212
OS 34.5169363 -38.63270404
OS 34.5308047 -38.64102508
OS 34.54652222 -38.65119524
OS 34.56039062 -38.66321452
OS 34.57333446 -38.67800748
OS 34.57425902 -38.6798566
OS 34.57795726 -38.68540396
OS 34.58350462 -38.693725
OS 34.58905198 -38.70481972
OS 34.59459934 -38.71961268
OS 34.6001467 -38.7353302
OS 34.60384494 -38.7538214
OS 34.6047695 -38.77416172
OS 34.6047695 -38.77508628
OS 34.6047695 -38.77601084
OS 34.6047695 -38.7815582
OS 34.60384494 -38.7908038
OS 34.60199582 -38.80189852
OS 34.6001467 -38.81484236
OS 34.59644846 -38.82871076
OS 34.59182566 -38.84350372
OS 34.58535374 -38.85829668
OS 34.58442918 -38.8601458
OS 34.5816555 -38.8647686
OS 34.57795726 -38.87124052
OS 34.5724099 -38.88048612
OS 34.56501342 -38.88973172
OS 34.55761694 -38.89990188
OS 34.54837134 -38.91007204
OS 34.53820118 -38.91839308
OS 34.53727662 -38.91931764
OS 34.53357838 -38.92209132
OS 34.52710646 -38.92578956
OS 34.51878542 -38.9294878
OS 34.50861526 -38.93503516
OS 34.49659598 -38.94058252
OS 34.48365214 -38.94520532
OS 34.46793462 -38.94982812
OS 34.4660855 -38.94982812
OS 34.46053814 -38.95167724
OS 34.45129254 -38.9526018
OS 34.43927326 -38.95445092
OS 34.4244803 -38.95630004
OS 34.40691366 -38.95814916
OS 34.3874979 -38.95907372
OS 34.36530846 -38.95999828
OS 34.12122462 -38.95999828
OS 34.12122462 -38.32020276
OS 34.37270494 -38.32020276
OS 34.37917686 -38.32112732
OE
OB 31.74233174 -38.95999828 I
OS 31.65264942 -38.95999828
OS 31.65264942 -38.87031596
OS 31.74233174 -38.87031596
OS 31.74233174 -38.95999828
OE
OB 31.52968294 -38.42745172 I
OS 31.50841806 -38.54671996
OS 31.45941638 -38.54671996
OS 31.44000062 -38.42745172
OS 31.44000062 -38.32020276
OS 31.52968294 -38.32020276
OS 31.52968294 -38.42745172
OE
OB 32.0992119 -38.48662356 I
OS 32.10568382 -38.48754812
OS 32.11955222 -38.48939724
OS 32.1361943 -38.49309548
OS 32.15376094 -38.49864284
OS 32.17132758 -38.50696388
OS 32.18889422 -38.51713404
OS 32.18981878 -38.51713404
OS 32.19074334 -38.51898316
OS 32.1962907 -38.5226814
OS 32.20461174 -38.53007788
OS 32.2147819 -38.53932348
OS 32.22587662 -38.55134276
OS 32.23697134 -38.56613572
OS 32.24806606 -38.58370236
OS 32.25731166 -38.60311812
OS 32.25731166 -38.60404268
OS 32.25823622 -38.6058918
OS 32.25916078 -38.60866548
OS 32.2610099 -38.61236372
OS 32.26285902 -38.61791108
OS 32.26470814 -38.624383
OS 32.26933094 -38.63917596
OS 32.27395374 -38.65766716
OS 32.27765198 -38.67800748
OS 32.28042566 -38.70112148
OS 32.28135022 -38.72516004
OS 32.28135022 -38.7260846
OS 32.28135022 -38.72793372
OS 32.28135022 -38.73163196
OS 32.28135022 -38.73717932
OS 32.28042566 -38.74365124
OS 32.28042566 -38.75104772
OS 32.27857654 -38.7676898
OS 32.2748783 -38.78803012
OS 32.2702555 -38.809295
OS 32.26378358 -38.83148444
OS 32.25546254 -38.85367388
OS 32.25546254 -38.85459844
OS 32.25453798 -38.85644756
OS 32.25268886 -38.85922124
OS 32.25083974 -38.86291948
OS 32.24436782 -38.87308964
OS 32.23604678 -38.88603348
OS 32.22587662 -38.89990188
OS 32.21293278 -38.91377028
OS 32.19813982 -38.92763868
OS 32.18057318 -38.94058252
OS 32.17964862 -38.94058252
OS 32.17872406 -38.94150708
OS 32.17595038 -38.9433562
OS 32.17225214 -38.94520532
OS 32.16300654 -38.94982812
OS 32.1500627 -38.95537548
OS 32.13434518 -38.96092284
OS 32.1177031 -38.96554564
OS 32.09828734 -38.96924388
OS 32.07887158 -38.97016844
OS 32.07239966 -38.97016844
OS 32.06500318 -38.96924388
OS 32.05575758 -38.96831932
OS 32.04466286 -38.9664702
OS 32.03264358 -38.96369652
OS 32.0206243 -38.95999828
OS 32.00860502 -38.95445092
OS 32.00768046 -38.95352636
OS 32.00305766 -38.95167724
OS 31.9975103 -38.947979
OS 31.99011382 -38.94243164
OS 31.98271734 -38.93688428
OS 31.97347174 -38.9294878
OS 31.9651507 -38.92116676
OS 31.95775422 -38.91192116
OS 31.95775422 -39.1375138
OS 31.87916662 -39.1375138
OS 31.87916662 -38.49586916
OS 31.95035774 -38.49586916
OS 31.95035774 -38.55689012
OS 31.9512823 -38.555041
OS 31.95498054 -38.55134276
OS 31.95960334 -38.54487084
OS 31.96699982 -38.53747436
OS 31.97532086 -38.52822876
OS 31.98456646 -38.51990772
OS 31.99566118 -38.51158668
OS 32.0067559 -38.5041902
OS 32.00860502 -38.50326564
OS 32.01230326 -38.50141652
OS 32.01969974 -38.49864284
OS 32.02894534 -38.4949446
OS 32.04004006 -38.49124636
OS 32.0529839 -38.48847268
OS 32.06777686 -38.48662356
OS 32.08441894 -38.485699
OS 32.0945891 -38.485699
OS 32.0992119 -38.48662356
OE
OB 32.5614919 -38.48662356 I
OS 32.57166206 -38.48847268
OS 32.58368134 -38.49217092
OS 32.59662518 -38.49679372
OS 32.61141814 -38.50326564
OS 32.62713566 -38.51158668
OS 32.5984743 -38.58370236
OS 32.59754974 -38.5827778
OS 32.5938515 -38.58092868
OS 32.58830414 -38.578155
OS 32.58090766 -38.57538132
OS 32.57258662 -38.57260764
OS 32.56241646 -38.56983396
OS 32.5522463 -38.56798484
OS 32.54207614 -38.56706028
OS 32.53745334 -38.56706028
OS 32.53283054 -38.56798484
OS 32.52635862 -38.5689094
OS 32.5198867 -38.57075852
OS 32.51156566 -38.5735322
OS 32.50324462 -38.57723044
OS 32.49584814 -38.5827778
OS 32.49492358 -38.58370236
OS 32.4921499 -38.58555148
OS 32.48937622 -38.58924972
OS 32.48475342 -38.59387252
OS 32.48013062 -38.60034444
OS 32.47550782 -38.60774092
OS 32.47088502 -38.61606196
OS 32.46718678 -38.62623212
OS 32.46626222 -38.62808124
OS 32.46533766 -38.6336286
OS 32.46348854 -38.64194964
OS 32.46071486 -38.65304436
OS 32.45794118 -38.66691276
OS 32.45609206 -38.68263028
OS 32.4551675 -38.69927236
OS 32.45424294 -38.71776356
OS 32.45424294 -38.95999828
OS 32.37565534 -38.95999828
OS 32.37565534 -38.49586916
OS 32.44684646 -38.49586916
OS 32.44684646 -38.56613572
OS 32.44777102 -38.56521116
OS 32.45146926 -38.55873924
OS 32.45609206 -38.5504182
OS 32.46348854 -38.54024804
OS 32.47088502 -38.53007788
OS 32.47920606 -38.51898316
OS 32.4875271 -38.50973756
OS 32.49584814 -38.50234108
OS 32.4967727 -38.50141652
OS 32.49954638 -38.4995674
OS 32.50509374 -38.49679372
OS 32.5106411 -38.49402004
OS 32.51803758 -38.49124636
OS 32.52728318 -38.48847268
OS 32.53652878 -38.48662356
OS 32.54669894 -38.485699
OS 32.55317086 -38.485699
OS 32.5614919 -38.48662356
OE
OB 32.75195126 -38.4117342 I
OS 32.67336366 -38.4117342
OS 32.67336366 -38.32020276
OS 32.75195126 -38.32020276
OS 32.75195126 -38.4117342
OE
OB 36.56668582 -38.95999828 I
OS 36.47885262 -38.95999828
OS 36.1441619 -38.4579622
OS 36.1441619 -38.95999828
OS 36.06280062 -38.95999828
OS 36.06280062 -38.32020276
OS 36.14970926 -38.32020276
OS 36.48532454 -38.8231634
OS 36.48532454 -38.32020276
OS 36.56668582 -38.32020276
OS 36.56668582 -38.95999828
OE
OB 35.74382742 -38.32112732 I
OS 35.75954494 -38.32205188
OS 35.77618702 -38.32297644
OS 35.79190454 -38.32482556
OS 35.80577294 -38.32667468
OS 35.80762206 -38.32667468
OS 35.81409398 -38.3285238
OS 35.82241502 -38.33037292
OS 35.83350974 -38.3331466
OS 35.84552902 -38.3377694
OS 35.85847286 -38.34331676
OS 35.87234126 -38.34978868
OS 35.88436054 -38.35718516
OS 35.88620966 -38.35810972
OS 35.8899079 -38.3608834
OS 35.89545526 -38.36643076
OS 35.90285174 -38.37290268
OS 35.91117278 -38.38122372
OS 35.91949382 -38.39231844
OS 35.92873942 -38.40433772
OS 35.9361359 -38.41820612
OS 35.93706046 -38.42005524
OS 35.93890958 -38.42467804
OS 35.94260782 -38.43299908
OS 35.94630606 -38.4440938
OS 35.94907974 -38.45703764
OS 35.95277798 -38.4718306
OS 35.9546271 -38.48847268
OS 35.95555166 -38.50603932
OS 35.95555166 -38.50696388
OS 35.95555166 -38.50973756
OS 35.95555166 -38.5134358
OS 35.9546271 -38.51990772
OS 35.95370254 -38.52637964
OS 35.95277798 -38.53470068
OS 35.95092886 -38.54394628
OS 35.94907974 -38.55411644
OS 35.94260782 -38.57538132
OS 35.93890958 -38.58647604
OS 35.93336222 -38.59849532
OS 35.9268903 -38.6105146
OS 35.92041838 -38.62160932
OS 35.91209734 -38.63270404
OS 35.90285174 -38.64379876
OS 35.90192718 -38.64472332
OS 35.90007806 -38.64657244
OS 35.89730438 -38.64934612
OS 35.89268158 -38.6521198
OS 35.88713422 -38.6567426
OS 35.87973774 -38.6613654
OS 35.87049214 -38.66691276
OS 35.86032198 -38.67153556
OS 35.8483027 -38.67708292
OS 35.8344343 -38.68263028
OS 35.81964134 -38.68725308
OS 35.8020747 -38.69095132
OS 35.7835835 -38.69464956
OS 35.76324318 -38.69742324
OS 35.74012918 -38.69927236
OS 35.71609062 -38.70019692
OS 35.5524435 -38.70019692
OS 35.5524435 -38.95999828
OS 35.46738398 -38.95999828
OS 35.46738398 -38.32020276
OS 35.72995902 -38.32020276
OS 35.74382742 -38.32112732
OE
OB 36.76916446 -38.42745172 I
OS 36.74789958 -38.54671996
OS 36.6988979 -38.54671996
OS 36.67948214 -38.42745172
OS 36.67948214 -38.32020276
OS 36.76916446 -38.32020276
OS 36.76916446 -38.42745172
OE
OB 38.2382903 -38.39601668 I
OS 37.86014526 -38.39601668
OS 37.86014526 -38.59109884
OS 38.21425174 -38.59109884
OS 38.21425174 -38.66691276
OS 37.86014526 -38.66691276
OS 37.86014526 -38.88418436
OS 38.25308326 -38.88418436
OS 38.25308326 -38.95999828
OS 37.77508574 -38.95999828
OS 37.77508574 -38.32020276
OS 38.2382903 -38.32020276
OS 38.2382903 -38.39601668
OE
OB 37.4339231 -38.32112732 I
OS 37.44224414 -38.32112732
OS 37.4616599 -38.32205188
OS 37.48200022 -38.32482556
OS 37.50418966 -38.32759924
OS 37.52452998 -38.33222204
OS 37.53470014 -38.33499572
OS 37.54302118 -38.3377694
OS 37.54394574 -38.3377694
OS 37.5448703 -38.33869396
OS 37.55041766 -38.34146764
OS 37.5587387 -38.34516588
OS 37.56890886 -38.3516378
OS 37.58000358 -38.35995884
OS 37.59202286 -38.37105356
OS 37.60311758 -38.3839974
OS 37.6142123 -38.39879036
OS 37.6142123 -38.39971492
OS 37.61513686 -38.40063948
OS 37.6188351 -38.40618684
OS 37.62253334 -38.41543244
OS 37.6280807 -38.42745172
OS 37.6327035 -38.44132012
OS 37.6373263 -38.4579622
OS 37.64009998 -38.47552884
OS 37.64102454 -38.4949446
OS 37.64102454 -38.49586916
OS 37.64102454 -38.49771828
OS 37.64102454 -38.50141652
OS 37.64009998 -38.50603932
OS 37.64009998 -38.51251124
OS 37.63917542 -38.51898316
OS 37.63547718 -38.53470068
OS 37.62992982 -38.55319188
OS 37.62253334 -38.57260764
OS 37.61143862 -38.5920234
OS 37.60404214 -38.601269
OS 37.59664566 -38.6105146
OS 37.5957211 -38.61143916
OS 37.59479654 -38.61236372
OS 37.59202286 -38.6151374
OS 37.58832462 -38.61791108
OS 37.58370182 -38.62160932
OS 37.57815446 -38.62530756
OS 37.57075798 -38.62993036
OS 37.5633615 -38.63547772
OS 37.5541159 -38.64010052
OS 37.54394574 -38.64472332
OS 37.53285102 -38.65027068
OS 37.52083174 -38.65489348
OS 37.50696334 -38.65859172
OS 37.49309494 -38.66321452
OS 37.47737742 -38.6659882
OS 37.46073534 -38.66876188
OS 37.46258446 -38.66968644
OS 37.4662827 -38.67153556
OS 37.47183006 -38.6752338
OS 37.47922654 -38.67893204
OS 37.49586862 -38.6891022
OS 37.50418966 -38.69557412
OS 37.51158614 -38.70112148
OS 37.51343526 -38.7029706
OS 37.51805806 -38.7075934
OS 37.52545454 -38.71498988
OS 37.53470014 -38.72423548
OS 37.5448703 -38.73717932
OS 37.55688958 -38.75104772
OS 37.56890886 -38.7676898
OS 37.5818527 -38.786181
OS 37.69187534 -38.95999828
OS 37.5864755 -38.95999828
OS 37.50234054 -38.82686164
OS 37.50234054 -38.82593708
OS 37.50049142 -38.82408796
OS 37.4986423 -38.82131428
OS 37.49586862 -38.81761604
OS 37.4893967 -38.80744588
OS 37.48107566 -38.79450204
OS 37.4709055 -38.78063364
OS 37.46073534 -38.76584068
OS 37.45056518 -38.75197228
OS 37.44131958 -38.73902844
OS 37.44039502 -38.73810388
OS 37.43762134 -38.73440564
OS 37.43299854 -38.72885828
OS 37.42652662 -38.72238636
OS 37.41265822 -38.70851796
OS 37.40526174 -38.70204604
OS 37.39786526 -38.69649868
OS 37.3969407 -38.69557412
OS 37.39509158 -38.69464956
OS 37.39139334 -38.69280044
OS 37.38584598 -38.69002676
OS 37.38029862 -38.68725308
OS 37.3738267 -38.6844794
OS 37.35903374 -38.6798566
OS 37.35810918 -38.6798566
OS 37.35626006 -38.67893204
OS 37.35256182 -38.67893204
OS 37.34793902 -38.67800748
OS 37.3414671 -38.67708292
OS 37.33407062 -38.67708292
OS 37.32390046 -38.67615836
OS 37.21480238 -38.67615836
OS 37.21480238 -38.95999828
OS 37.12974286 -38.95999828
OS 37.12974286 -38.32020276
OS 37.42652662 -38.32020276
OS 37.4339231 -38.32112732
OE
OB 35.31760526 -38.95999828 I
OS 35.23254574 -38.95999828
OS 35.23254574 -38.32020276
OS 35.31760526 -38.32020276
OS 35.31760526 -38.95999828
OE
OB 42.12051774 -38.66413908 H
OS 41.95224782 -38.66413908
OS 41.95224782 -38.88418436
OS 42.13438614 -38.88418436
OS 42.1538019 -38.8832598
OS 42.16212294 -38.88233524
OS 42.16951942 -38.88141068
OS 42.17044398 -38.88141068
OS 42.17414222 -38.88048612
OS 42.17968958 -38.87956156
OS 42.1861615 -38.87771244
OS 42.20187902 -38.87216508
OS 42.21759654 -38.8647686
OS 42.2185211 -38.86384404
OS 42.22129478 -38.86199492
OS 42.22499302 -38.85922124
OS 42.22961582 -38.855523
OS 42.23423862 -38.84997564
OS 42.24071054 -38.84442828
OS 42.24533334 -38.8370318
OS 42.2508807 -38.82871076
OS 42.25180526 -38.8277862
OS 42.25272982 -38.82501252
OS 42.25457894 -38.81946516
OS 42.25735262 -38.81299324
OS 42.2601263 -38.80559676
OS 42.26197542 -38.79635116
OS 42.26289998 -38.78525644
OS 42.26382454 -38.77416172
OS 42.26382454 -38.7723126
OS 42.26382454 -38.76861436
OS 42.26289998 -38.76121788
OS 42.26105086 -38.75289684
OS 42.25920174 -38.74365124
OS 42.2555035 -38.73348108
OS 42.2508807 -38.72331092
OS 42.24440878 -38.71314076
OS 42.24348422 -38.7122162
OS 42.24071054 -38.70851796
OS 42.2370123 -38.70389516
OS 42.23146494 -38.6983478
OS 42.22406846 -38.69187588
OS 42.21482286 -38.68540396
OS 42.2046527 -38.6798566
OS 42.19263342 -38.6752338
OS 42.1907843 -38.67430924
OS 42.18708606 -38.67338468
OS 42.17876502 -38.67153556
OS 42.16859486 -38.66968644
OS 42.15565102 -38.66783732
OS 42.1399335 -38.6659882
OS 42.12051774 -38.66413908
OE
OB 45.22981302 -38.5504182 H
OS 45.22426566 -38.5504182
OS 45.21964286 -38.55134276
OS 45.2094727 -38.55226732
OS 45.1956043 -38.55596556
OS 45.17988678 -38.56151292
OS 45.1632447 -38.5689094
OS 45.14752718 -38.58000412
OS 45.13920614 -38.5874006
OS 45.13180966 -38.59479708
OS 45.13180966 -38.59572164
OS 45.12996054 -38.5966462
OS 45.12811142 -38.59941988
OS 45.12533774 -38.60311812
OS 45.12256406 -38.60774092
OS 45.11979038 -38.61328828
OS 45.11609214 -38.62068476
OS 45.1123939 -38.62808124
OS 45.10869566 -38.63732684
OS 45.10499742 -38.64657244
OS 45.10222374 -38.65766716
OS 45.09945006 -38.66968644
OS 45.09667638 -38.68263028
OS 45.09482726 -38.69649868
OS 45.0939027 -38.7122162
OS 45.09297814 -38.72793372
OS 45.09297814 -38.72885828
OS 45.09297814 -38.73163196
OS 45.09297814 -38.73625476
OS 45.0939027 -38.74272668
OS 45.0939027 -38.75012316
OS 45.09482726 -38.7584442
OS 45.09760094 -38.77785996
OS 45.10222374 -38.8000494
OS 45.10962022 -38.82223884
OS 45.11886582 -38.84350372
OS 45.12533774 -38.85274932
OS 45.13180966 -38.86199492
OS 45.13273422 -38.86199492
OS 45.13365878 -38.86384404
OS 45.13920614 -38.86846684
OS 45.14752718 -38.87586332
OS 45.1586219 -38.8832598
OS 45.1724903 -38.89158084
OS 45.18913238 -38.89897732
OS 45.20854814 -38.90360012
OS 45.2187183 -38.90452468
OS 45.22981302 -38.90544924
OS 45.23536038 -38.90544924
OS 45.23998318 -38.90452468
OS 45.25015334 -38.90267556
OS 45.26402174 -38.89990188
OS 45.2788147 -38.89435452
OS 45.29545678 -38.88695804
OS 45.3111743 -38.87586332
OS 45.31949534 -38.86846684
OS 45.32689182 -38.86107036
OS 45.32781638 -38.8601458
OS 45.32874094 -38.85922124
OS 45.33059006 -38.85644756
OS 45.33336374 -38.85274932
OS 45.33613742 -38.84812652
OS 45.33983566 -38.84257916
OS 45.3435339 -38.83518268
OS 45.34723214 -38.8277862
OS 45.35093038 -38.8185406
OS 45.35370406 -38.80837044
OS 45.3574023 -38.79727572
OS 45.36017598 -38.78525644
OS 45.36294966 -38.77138804
OS 45.36479878 -38.75751964
OS 45.3666479 -38.74180212
OS 45.3666479 -38.72516004
OS 45.3666479 -38.72423548
OS 45.3666479 -38.7214618
OS 45.3666479 -38.716839
OS 45.36572334 -38.71129164
OS 45.36572334 -38.70389516
OS 45.36479878 -38.69557412
OS 45.3620251 -38.67615836
OS 45.3574023 -38.65581804
OS 45.35000582 -38.6336286
OS 45.33983566 -38.61328828
OS 45.3342883 -38.60311812
OS 45.32689182 -38.59479708
OS 45.32689182 -38.59387252
OS 45.3250427 -38.59294796
OS 45.31949534 -38.5874006
OS 45.3111743 -38.58092868
OS 45.30007958 -38.57260764
OS 45.28621118 -38.5642866
OS 45.2695691 -38.55689012
OS 45.2510779 -38.55226732
OS 45.24090774 -38.55134276
OS 45.22981302 -38.5504182
OE
OB 32.07702246 -38.54764452 H
OS 32.07239966 -38.54764452
OS 32.06870142 -38.54856908
OS 32.05945582 -38.5504182
OS 32.04743654 -38.55319188
OS 32.03356814 -38.55873924
OS 32.01877518 -38.56706028
OS 32.01045414 -38.57260764
OS 32.00305766 -38.57907956
OS 31.99566118 -38.58647604
OS 31.9882647 -38.59479708
OS 31.9882647 -38.59572164
OS 31.98641558 -38.5966462
OS 31.98456646 -38.59941988
OS 31.98271734 -38.60311812
OS 31.97994366 -38.60866548
OS 31.97624542 -38.61421284
OS 31.97254718 -38.62160932
OS 31.9697735 -38.6290058
OS 31.96607526 -38.6382514
OS 31.96237702 -38.64842156
OS 31.95960334 -38.65951628
OS 31.9559051 -38.67153556
OS 31.95405598 -38.68540396
OS 31.95220686 -38.69927236
OS 31.95035774 -38.71406532
OS 31.95035774 -38.7307074
OS 31.95035774 -38.73163196
OS 31.95035774 -38.73440564
OS 31.95035774 -38.73902844
OS 31.9512823 -38.74550036
OS 31.9512823 -38.75289684
OS 31.95220686 -38.76121788
OS 31.95498054 -38.78063364
OS 31.95960334 -38.80282308
OS 31.9651507 -38.82408796
OS 31.9743963 -38.84535284
OS 31.97994366 -38.85459844
OS 31.98641558 -38.86291948
OS 31.9882647 -38.8647686
OS 31.9928875 -38.8693914
OS 32.00028398 -38.87678788
OS 32.01045414 -38.88418436
OS 32.02339798 -38.89158084
OS 32.03819094 -38.89897732
OS 32.05483302 -38.90360012
OS 32.06407862 -38.90452468
OS 32.07332422 -38.90544924
OS 32.07887158 -38.90544924
OS 32.08256982 -38.90452468
OS 32.09181542 -38.90267556
OS 32.10475926 -38.89990188
OS 32.11862766 -38.89435452
OS 32.13342062 -38.88695804
OS 32.14821358 -38.87586332
OS 32.15561006 -38.8693914
OS 32.16300654 -38.86199492
OS 32.16300654 -38.86107036
OS 32.16485566 -38.8601458
OS 32.16670478 -38.85737212
OS 32.1685539 -38.85367388
OS 32.17225214 -38.84905108
OS 32.17502582 -38.84257916
OS 32.17872406 -38.83610724
OS 32.1824223 -38.8277862
OS 32.18519598 -38.81946516
OS 32.18889422 -38.80837044
OS 32.19259246 -38.79727572
OS 32.19536614 -38.78525644
OS 32.19721526 -38.77138804
OS 32.19906438 -38.75659508
OS 32.2009135 -38.74087756
OS 32.2009135 -38.72423548
OS 32.2009135 -38.72331092
OS 32.2009135 -38.72053724
OS 32.2009135 -38.71591444
OS 32.19998894 -38.70944252
OS 32.19998894 -38.70204604
OS 32.19906438 -38.693725
OS 32.1962907 -38.67430924
OS 32.1916679 -38.65304436
OS 32.18519598 -38.63177948
OS 32.17595038 -38.6105146
OS 32.17040302 -38.60034444
OS 32.1639311 -38.5920234
OS 32.1639311 -38.59109884
OS 32.16208198 -38.59017428
OS 32.15745918 -38.58462692
OS 32.1500627 -38.578155
OS 32.13989254 -38.56983396
OS 32.1269487 -38.56151292
OS 32.11215574 -38.55411644
OS 32.09551366 -38.54949364
OS 32.08626806 -38.54856908
OS 32.07702246 -38.54764452
OE
OB 42.10387566 -38.39601668 H
OS 41.95224782 -38.39601668
OS 41.95224782 -38.58832516
OS 42.10942302 -38.58832516
OS 42.1214423 -38.5874006
OS 42.13438614 -38.58647604
OS 42.14732998 -38.58555148
OS 42.16027382 -38.58370236
OS 42.17044398 -38.58185324
OS 42.1722931 -38.58092868
OS 42.17599134 -38.58000412
OS 42.1815387 -38.57723044
OS 42.18893518 -38.5735322
OS 42.19633166 -38.56983396
OS 42.2046527 -38.5642866
OS 42.21297374 -38.55689012
OS 42.21944566 -38.54949364
OS 42.22037022 -38.54856908
OS 42.22221934 -38.5457954
OS 42.22499302 -38.54024804
OS 42.2277667 -38.53377612
OS 42.23054038 -38.52637964
OS 42.23331406 -38.51713404
OS 42.23516318 -38.50603932
OS 42.23608774 -38.49402004
OS 42.23608774 -38.49217092
OS 42.23608774 -38.48847268
OS 42.23516318 -38.48292532
OS 42.23423862 -38.47552884
OS 42.2323895 -38.46628324
OS 42.22961582 -38.45703764
OS 42.22591758 -38.44779204
OS 42.22037022 -38.43854644
OS 42.21944566 -38.43762188
OS 42.21759654 -38.4348482
OS 42.2138983 -38.4302254
OS 42.2092755 -38.4256026
OS 42.20280358 -38.42005524
OS 42.1954071 -38.41450788
OS 42.1861615 -38.40896052
OS 42.17599134 -38.40526228
OS 42.17506678 -38.40526228
OS 42.17044398 -38.40341316
OS 42.16397206 -38.4024886
OS 42.1538019 -38.40063948
OS 42.1399335 -38.39879036
OS 42.12421598 -38.3978658
OS 42.10387566 -38.39601668
OE
OB 37.41635646 -38.39139388 H
OS 37.21480238 -38.39139388
OS 37.21480238 -38.60311812
OS 37.40526174 -38.60311812
OS 37.41635646 -38.60219356
OS 37.4293003 -38.601269
OS 37.44409326 -38.60034444
OS 37.45888622 -38.59849532
OS 37.47367918 -38.59572164
OS 37.48662302 -38.5920234
OS 37.48847214 -38.59109884
OS 37.49217038 -38.58924972
OS 37.49771774 -38.58647604
OS 37.50511422 -38.5827778
OS 37.51343526 -38.57723044
OS 37.5217563 -38.57075852
OS 37.53007734 -38.56243748
OS 37.53654926 -38.55319188
OS 37.53747382 -38.55226732
OS 37.53932294 -38.54856908
OS 37.54209662 -38.54302172
OS 37.54579486 -38.53562524
OS 37.54856854 -38.5273042
OS 37.55134222 -38.5180586
OS 37.55319134 -38.50696388
OS 37.5541159 -38.49586916
OS 37.5541159 -38.4949446
OS 37.5541159 -38.49402004
OS 37.55319134 -38.48847268
OS 37.55226678 -38.48015164
OS 37.55041766 -38.46905692
OS 37.54579486 -38.4579622
OS 37.5402475 -38.44501836
OS 37.53192646 -38.43299908
OS 37.52083174 -38.4209798
OS 37.51898262 -38.42005524
OS 37.51435982 -38.416357
OS 37.50696334 -38.4117342
OS 37.49494406 -38.40618684
OS 37.48107566 -38.40063948
OS 37.46258446 -38.39601668
OS 37.44131958 -38.39231844
OS 37.41635646 -38.39139388
OE
OB 39.82298614 -38.54764452 H
OS 39.81836334 -38.54764452
OS 39.8146651 -38.54856908
OS 39.8054195 -38.5504182
OS 39.79340022 -38.55319188
OS 39.77953182 -38.55873924
OS 39.76473886 -38.56706028
OS 39.75641782 -38.57260764
OS 39.74902134 -38.57907956
OS 39.74162486 -38.58647604
OS 39.73422838 -38.59479708
OS 39.73422838 -38.59572164
OS 39.73237926 -38.5966462
OS 39.73053014 -38.59941988
OS 39.72868102 -38.60311812
OS 39.72590734 -38.60866548
OS 39.7222091 -38.61421284
OS 39.71851086 -38.62160932
OS 39.71573718 -38.6290058
OS 39.71203894 -38.6382514
OS 39.7083407 -38.64842156
OS 39.70556702 -38.65951628
OS 39.70186878 -38.67153556
OS 39.70001966 -38.68540396
OS 39.69817054 -38.69927236
OS 39.69632142 -38.71406532
OS 39.69632142 -38.7307074
OS 39.69632142 -38.73163196
OS 39.69632142 -38.73440564
OS 39.69632142 -38.73902844
OS 39.69724598 -38.74550036
OS 39.69724598 -38.75289684
OS 39.69817054 -38.76121788
OS 39.70094422 -38.78063364
OS 39.70556702 -38.80282308
OS 39.71111438 -38.82408796
OS 39.72035998 -38.84535284
OS 39.72590734 -38.85459844
OS 39.73237926 -38.86291948
OS 39.73422838 -38.8647686
OS 39.73885118 -38.8693914
OS 39.74624766 -38.87678788
OS 39.75641782 -38.88418436
OS 39.76936166 -38.89158084
OS 39.78415462 -38.89897732
OS 39.8007967 -38.90360012
OS 39.8100423 -38.90452468
OS 39.8192879 -38.90544924
OS 39.82483526 -38.90544924
OS 39.8285335 -38.90452468
OS 39.8377791 -38.90267556
OS 39.85072294 -38.89990188
OS 39.86459134 -38.89435452
OS 39.8793843 -38.88695804
OS 39.89417726 -38.87586332
OS 39.90157374 -38.8693914
OS 39.90897022 -38.86199492
OS 39.90897022 -38.86107036
OS 39.91081934 -38.8601458
OS 39.91266846 -38.85737212
OS 39.91451758 -38.85367388
OS 39.91821582 -38.84905108
OS 39.9209895 -38.84257916
OS 39.92468774 -38.83610724
OS 39.92838598 -38.8277862
OS 39.93115966 -38.81946516
OS 39.9348579 -38.80837044
OS 39.93855614 -38.79727572
OS 39.94132982 -38.78525644
OS 39.94317894 -38.77138804
OS 39.94502806 -38.75659508
OS 39.94687718 -38.74087756
OS 39.94687718 -38.72423548
OS 39.94687718 -38.72331092
OS 39.94687718 -38.72053724
OS 39.94687718 -38.71591444
OS 39.94595262 -38.70944252
OS 39.94595262 -38.70204604
OS 39.94502806 -38.693725
OS 39.94225438 -38.67430924
OS 39.93763158 -38.65304436
OS 39.93115966 -38.63177948
OS 39.92191406 -38.6105146
OS 39.9163667 -38.60034444
OS 39.90989478 -38.5920234
OS 39.90989478 -38.59109884
OS 39.90804566 -38.59017428
OS 39.90342286 -38.58462692
OS 39.89602638 -38.578155
OS 39.88585622 -38.56983396
OS 39.87291238 -38.56151292
OS 39.85811942 -38.55411644
OS 39.84147734 -38.54949364
OS 39.83223174 -38.54856908
OS 39.82298614 -38.54764452
OE
OB 35.73550638 -38.39601668 H
OS 35.5524435 -38.39601668
OS 35.5524435 -38.624383
OS 35.72441166 -38.624383
OS 35.73088358 -38.62345844
OS 35.7373555 -38.62345844
OS 35.74475198 -38.62253388
OS 35.76231862 -38.62068476
OS 35.78173438 -38.61698652
OS 35.80115014 -38.61143916
OS 35.81871678 -38.60404268
OS 35.82703782 -38.59941988
OS 35.83350974 -38.59387252
OS 35.83535886 -38.5920234
OS 35.8390571 -38.58832516
OS 35.84460446 -38.58092868
OS 35.85107638 -38.57168308
OS 35.8575483 -38.5596638
OS 35.86309566 -38.54487084
OS 35.8667939 -38.52822876
OS 35.86864302 -38.508813
OS 35.86864302 -38.50788844
OS 35.86864302 -38.50696388
OS 35.86864302 -38.50234108
OS 35.86771846 -38.49402004
OS 35.86586934 -38.48477444
OS 35.86402022 -38.47460428
OS 35.86032198 -38.462585
OS 35.85477462 -38.45149028
OS 35.8483027 -38.44039556
OS 35.84737814 -38.439471
OS 35.84460446 -38.43577276
OS 35.83998166 -38.43114996
OS 35.8344343 -38.42467804
OS 35.82611326 -38.41820612
OS 35.81686766 -38.41265876
OS 35.8066975 -38.4071114
OS 35.79467822 -38.4024886
OS 35.79375366 -38.4024886
OS 35.79005542 -38.40156404
OS 35.78450806 -38.40063948
OS 35.77711158 -38.39879036
OS 35.76601686 -38.3978658
OS 35.75214846 -38.39694124
OS 35.73550638 -38.39601668
OE
OB 43.44263854 -38.5504182 H
OS 43.43709118 -38.5504182
OS 43.43339294 -38.55134276
OS 43.42322278 -38.55226732
OS 43.4112035 -38.555041
OS 43.39641054 -38.5596638
OS 43.38069302 -38.56613572
OS 43.36590006 -38.57538132
OS 43.3511071 -38.5874006
OS 43.34925798 -38.58924972
OS 43.34555974 -38.59387252
OS 43.33908782 -38.60219356
OS 43.3326159 -38.61328828
OS 43.32521942 -38.62623212
OS 43.3187475 -38.6428742
OS 43.31320014 -38.66228996
OS 43.31042646 -38.68355484
OS 43.57022782 -38.68355484
OS 43.57022782 -38.68263028
OS 43.57022782 -38.68078116
OS 43.56930326 -38.67800748
OS 43.56930326 -38.67430924
OS 43.56745414 -38.66321452
OS 43.56468046 -38.65119524
OS 43.56005766 -38.63640228
OS 43.55543486 -38.62253388
OS 43.54803838 -38.60866548
OS 43.53971734 -38.5966462
OS 43.53971734 -38.59572164
OS 43.53786822 -38.59479708
OS 43.53324542 -38.58924972
OS 43.52492438 -38.58185324
OS 43.51382966 -38.5735322
OS 43.49996126 -38.56521116
OS 43.48331918 -38.55781468
OS 43.46390342 -38.55226732
OS 43.45373326 -38.55134276
OS 43.44263854 -38.5504182
OE
OB 34.35791198 -38.39601668 H
OS 34.20628414 -38.39601668
OS 34.20628414 -38.58832516
OS 34.36345934 -38.58832516
OS 34.37547862 -38.5874006
OS 34.38842246 -38.58647604
OS 34.4013663 -38.58555148
OS 34.41431014 -38.58370236
OS 34.4244803 -38.58185324
OS 34.42632942 -38.58092868
OS 34.43002766 -38.58000412
OS 34.43557502 -38.57723044
OS 34.4429715 -38.5735322
OS 34.45036798 -38.56983396
OS 34.45868902 -38.5642866
OS 34.46701006 -38.55689012
OS 34.47348198 -38.54949364
OS 34.47440654 -38.54856908
OS 34.47625566 -38.5457954
OS 34.47902934 -38.54024804
OS 34.48180302 -38.53377612
OS 34.4845767 -38.52637964
OS 34.48735038 -38.51713404
OS 34.4891995 -38.50603932
OS 34.49012406 -38.49402004
OS 34.49012406 -38.49217092
OS 34.49012406 -38.48847268
OS 34.4891995 -38.48292532
OS 34.48827494 -38.47552884
OS 34.48642582 -38.46628324
OS 34.48365214 -38.45703764
OS 34.4799539 -38.44779204
OS 34.47440654 -38.43854644
OS 34.47348198 -38.43762188
OS 34.47163286 -38.4348482
OS 34.46793462 -38.4302254
OS 34.46331182 -38.4256026
OS 34.4568399 -38.42005524
OS 34.44944342 -38.41450788
OS 34.44019782 -38.40896052
OS 34.43002766 -38.40526228
OS 34.4291031 -38.40526228
OS 34.4244803 -38.40341316
OS 34.41800838 -38.4024886
OS 34.40783822 -38.40063948
OS 34.39396982 -38.39879036
OS 34.3782523 -38.3978658
OS 34.35791198 -38.39601668
OE
OB 40.89732486 -38.39601668 H
OS 40.71426198 -38.39601668
OS 40.71426198 -38.624383
OS 40.88623014 -38.624383
OS 40.89270206 -38.62345844
OS 40.89917398 -38.62345844
OS 40.90657046 -38.62253388
OS 40.9241371 -38.62068476
OS 40.94355286 -38.61698652
OS 40.96296862 -38.61143916
OS 40.98053526 -38.60404268
OS 40.9888563 -38.59941988
OS 40.99532822 -38.59387252
OS 40.99717734 -38.5920234
OS 41.00087558 -38.58832516
OS 41.00642294 -38.58092868
OS 41.01289486 -38.57168308
OS 41.01936678 -38.5596638
OS 41.02491414 -38.54487084
OS 41.02861238 -38.52822876
OS 41.0304615 -38.508813
OS 41.0304615 -38.50788844
OS 41.0304615 -38.50696388
OS 41.0304615 -38.50234108
OS 41.02953694 -38.49402004
OS 41.02768782 -38.48477444
OS 41.0258387 -38.47460428
OS 41.02214046 -38.462585
OS 41.0165931 -38.45149028
OS 41.01012118 -38.44039556
OS 41.00919662 -38.439471
OS 41.00642294 -38.43577276
OS 41.00180014 -38.43114996
OS 40.99625278 -38.42467804
OS 40.98793174 -38.41820612
OS 40.97868614 -38.41265876
OS 40.96851598 -38.4071114
OS 40.9564967 -38.4024886
OS 40.95557214 -38.4024886
OS 40.9518739 -38.40156404
OS 40.94632654 -38.40063948
OS 40.93893006 -38.39879036
OS 40.92783534 -38.3978658
OS 40.91396694 -38.39694124
OS 40.89732486 -38.39601668
OE
OB 33.15136118 -38.39601668 H
OS 32.9682983 -38.39601668
OS 32.9682983 -38.624383
OS 33.14026646 -38.624383
OS 33.14673838 -38.62345844
OS 33.1532103 -38.62345844
OS 33.16060678 -38.62253388
OS 33.17817342 -38.62068476
OS 33.19758918 -38.61698652
OS 33.21700494 -38.61143916
OS 33.23457158 -38.60404268
OS 33.24289262 -38.59941988
OS 33.24936454 -38.59387252
OS 33.25121366 -38.5920234
OS 33.2549119 -38.58832516
OS 33.26045926 -38.58092868
OS 33.26693118 -38.57168308
OS 33.2734031 -38.5596638
OS 33.27895046 -38.54487084
OS 33.2826487 -38.52822876
OS 33.28449782 -38.508813
OS 33.28449782 -38.50788844
OS 33.28449782 -38.50696388
OS 33.28449782 -38.50234108
OS 33.28357326 -38.49402004
OS 33.28172414 -38.48477444
OS 33.27987502 -38.47460428
OS 33.27617678 -38.462585
OS 33.27062942 -38.45149028
OS 33.2641575 -38.44039556
OS 33.26323294 -38.439471
OS 33.26045926 -38.43577276
OS 33.25583646 -38.43114996
OS 33.2502891 -38.42467804
OS 33.24196806 -38.41820612
OS 33.23272246 -38.41265876
OS 33.2225523 -38.4071114
OS 33.21053302 -38.4024886
OS 33.20960846 -38.4024886
OS 33.20591022 -38.40156404
OS 33.20036286 -38.40063948
OS 33.19296638 -38.39879036
OS 33.18187166 -38.3978658
OS 33.16800326 -38.39694124
OS 33.15136118 -38.39601668
OE
OB 34.37455406 -38.66413908 H
OS 34.20628414 -38.66413908
OS 34.20628414 -38.88418436
OS 34.38842246 -38.88418436
OS 34.40783822 -38.8832598
OS 34.41615926 -38.88233524
OS 34.42355574 -38.88141068
OS 34.4244803 -38.88141068
OS 34.42817854 -38.88048612
OS 34.4337259 -38.87956156
OS 34.44019782 -38.87771244
OS 34.45591534 -38.87216508
OS 34.47163286 -38.8647686
OS 34.47255742 -38.86384404
OS 34.4753311 -38.86199492
OS 34.47902934 -38.85922124
OS 34.48365214 -38.855523
OS 34.48827494 -38.84997564
OS 34.49474686 -38.84442828
OS 34.49936966 -38.8370318
OS 34.50491702 -38.82871076
OS 34.50584158 -38.8277862
OS 34.50676614 -38.82501252
OS 34.50861526 -38.81946516
OS 34.51138894 -38.81299324
OS 34.51416262 -38.80559676
OS 34.51601174 -38.79635116
OS 34.5169363 -38.78525644
OS 34.51786086 -38.77416172
OS 34.51786086 -38.7723126
OS 34.51786086 -38.76861436
OS 34.5169363 -38.76121788
OS 34.51508718 -38.75289684
OS 34.51323806 -38.74365124
OS 34.50953982 -38.73348108
OS 34.50491702 -38.72331092
OS 34.4984451 -38.71314076
OS 34.49752054 -38.7122162
OS 34.49474686 -38.70851796
OS 34.49104862 -38.70389516
OS 34.48550126 -38.6983478
OS 34.47810478 -38.69187588
OS 34.46885918 -38.68540396
OS 34.45868902 -38.6798566
OS 34.44666974 -38.6752338
OS 34.44482062 -38.67430924
OS 34.44112238 -38.67338468
OS 34.43280134 -38.67153556
OS 34.42263118 -38.66968644
OS 34.40968734 -38.66783732
OS 34.39396982 -38.6659882
OS 34.37455406 -38.66413908
OE
SE
S P 0
OB 48.49040086 -36.61402634 I
OS 48.17420134 -36.61402634
OS 48.17420134 -37.45999874
OS 48.04661206 -37.45999874
OS 48.04661206 -36.61402634
OS 47.73041254 -36.61402634
OS 47.73041254 -36.50030546
OS 48.49040086 -36.50030546
OS 48.49040086 -36.61402634
OE
OB 47.69990206 -37.45999874 I
OS 47.5556707 -37.45999874
OS 47.44333666 -37.16876234
OS 47.04115306 -37.16876234
OS 46.93714006 -37.45999874
OS 46.80261658 -37.45999874
OS 47.16874234 -36.50030546
OS 47.30742634 -36.50030546
OS 47.69990206 -37.45999874
OE
OB 49.31834434 -36.61402634 I
OS 48.75112678 -36.61402634
OS 48.75112678 -36.90664958
OS 49.2822865 -36.90664958
OS 49.2822865 -37.02037046
OS 48.75112678 -37.02037046
OS 48.75112678 -37.34627786
OS 49.34053378 -37.34627786
OS 49.34053378 -37.45999874
OS 48.6235375 -37.45999874
OS 48.6235375 -36.50030546
OS 49.31834434 -36.50030546
OS 49.31834434 -36.61402634
OE
OB 46.33386466 -36.5016923 I
OS 46.36160146 -36.50307914
OS 46.38933826 -36.50585282
OS 46.41707506 -36.51001334
OS 46.44065134 -36.51417386
OS 46.44203818 -36.51417386
OS 46.44481186 -36.5155607
OS 46.44897238 -36.5155607
OS 46.45451974 -36.51833438
OS 46.46977498 -36.5224949
OS 46.48919074 -36.5294291
OS 46.51138018 -36.53913698
OS 46.53495646 -36.55161854
OS 46.55853274 -36.56548694
OS 46.58072218 -36.58351586
OS 46.58210902 -36.5849027
OS 46.58349586 -36.58628954
OS 46.58765638 -36.59045006
OS 46.59320374 -36.59461058
OS 46.60707214 -36.60847898
OS 46.62371422 -36.62789474
OS 46.64174314 -36.65147102
OS 46.6611589 -36.67920782
OS 46.67918782 -36.71110514
OS 46.69444306 -36.74716298
OS 46.69444306 -36.74854982
OS 46.6958299 -36.7513235
OS 46.69860358 -36.75687086
OS 46.69999042 -36.7651919
OS 46.70415094 -36.77489978
OS 46.70692462 -36.7859945
OS 46.7096983 -36.79847606
OS 46.71385882 -36.8137313
OS 46.71801934 -36.82898654
OS 46.72079302 -36.84701546
OS 46.72772722 -36.88584698
OS 46.73188774 -36.92883902
OS 46.73327458 -36.97599158
OS 46.73327458 -36.97737842
OS 46.73327458 -36.9801521
OS 46.73327458 -36.9870863
OS 46.73327458 -36.9940205
OS 46.73188774 -37.00372838
OS 46.73188774 -37.0148231
OS 46.7305009 -37.04117306
OS 46.72634038 -37.07168354
OS 46.72217986 -37.10358086
OS 46.71524566 -37.13686502
OS 46.70692462 -37.17014918
OS 46.70692462 -37.17153602
OS 46.70553778 -37.1743097
OS 46.70415094 -37.17847022
OS 46.7027641 -37.18401758
OS 46.69721674 -37.19927282
OS 46.6888957 -37.21868858
OS 46.68057466 -37.24087802
OS 46.66947994 -37.26306746
OS 46.65561154 -37.28664374
OS 46.64174314 -37.30883318
OS 46.6403563 -37.31160686
OS 46.63480894 -37.31854106
OS 46.6264879 -37.32824894
OS 46.61539318 -37.3407305
OS 46.60291162 -37.3545989
OS 46.58765638 -37.3684673
OS 46.57240114 -37.38372254
OS 46.55437222 -37.3962041
OS 46.55159854 -37.39759094
OS 46.54605118 -37.40175146
OS 46.5363433 -37.40729882
OS 46.5224749 -37.41423302
OS 46.50583282 -37.42255406
OS 46.48641706 -37.42948826
OS 46.46422762 -37.4378093
OS 46.4392645 -37.4447435
OS 46.43649082 -37.4447435
OS 46.4323303 -37.44613034
OS 46.42816978 -37.44751718
OS 46.41430138 -37.44890402
OS 46.39488562 -37.4516777
OS 46.37269618 -37.45445138
OS 46.34634622 -37.45722506
OS 46.31722258 -37.4586119
OS 46.28532526 -37.45999874
OS 45.9400021 -37.45999874
OS 45.9400021 -36.50030546
OS 46.30890154 -36.50030546
OS 46.33386466 -36.5016923
OE
OB 46.28948578 -36.61402634 H
OS 46.06759138 -36.61402634
OS 46.06759138 -37.34627786
OS 46.29503314 -37.34627786
OS 46.30474102 -37.34489102
OS 46.32554362 -37.34350418
OS 46.3491199 -37.34211734
OS 46.37408302 -37.33934366
OS 46.39904614 -37.33518314
OS 46.41984874 -37.32963578
OS 46.42262242 -37.32824894
OS 46.42955662 -37.3268621
OS 46.4392645 -37.32270158
OS 46.45174606 -37.31715422
OS 46.46561446 -37.30883318
OS 46.47948286 -37.30051214
OS 46.49335126 -37.29080426
OS 46.50721966 -37.27970954
OS 46.5086065 -37.27693586
OS 46.51415386 -37.2713885
OS 46.5224749 -37.26168062
OS 46.53218278 -37.24781222
OS 46.5432775 -37.2297833
OS 46.55575906 -37.2089807
OS 46.56685378 -37.18540442
OS 46.57656166 -37.15905446
OS 46.57656166 -37.15766762
OS 46.5779485 -37.15489394
OS 46.57933534 -37.15073342
OS 46.58072218 -37.14518606
OS 46.58210902 -37.13825186
OS 46.5848827 -37.12854398
OS 46.58765638 -37.1188361
OS 46.59043006 -37.10774138
OS 46.59459058 -37.08000458
OS 46.5987511 -37.04810726
OS 46.60152478 -37.01204942
OS 46.60291162 -36.9732179
OS 46.60291162 -36.97183106
OS 46.60291162 -36.9662837
OS 46.60291162 -36.9593495
OS 46.60152478 -36.94825478
OS 46.60152478 -36.93577322
OS 46.60013794 -36.92190482
OS 46.5987511 -36.90526274
OS 46.59736426 -36.88862066
OS 46.59043006 -36.85117598
OS 46.58210902 -36.81234446
OS 46.56962746 -36.77628662
OS 46.56130642 -36.7582577
OS 46.55298538 -36.74300246
OS 46.55298538 -36.74161562
OS 46.5502117 -36.73884194
OS 46.54743802 -36.73468142
OS 46.54466434 -36.72913406
OS 46.53356962 -36.71526566
OS 46.51970122 -36.69862358
OS 46.5016723 -36.68059466
OS 46.4808697 -36.66256574
OS 46.45729342 -36.6473105
OS 46.4323303 -36.63482894
OS 46.42955662 -36.6334421
OS 46.42262242 -36.63205526
OS 46.41014086 -36.62789474
OS 46.39211194 -36.62373422
OS 46.3699225 -36.62096054
OS 46.3421857 -36.61680002
OS 46.32554362 -36.61541318
OS 46.3075147 -36.61541318
OS 46.28948578 -36.61402634
OE
OB 47.23531066 -36.60015794 H
OS 47.23531066 -36.60154478
OS 47.23392382 -36.60431846
OS 47.23392382 -36.60986582
OS 47.23115014 -36.61541318
OS 47.2297633 -36.62512106
OS 47.22698962 -36.63482894
OS 47.22144226 -36.65840522
OS 47.21450806 -36.68614202
OS 47.20480018 -36.7166525
OS 47.1950923 -36.74993666
OS 47.18261074 -36.78460766
OS 47.07859774 -37.06474934
OS 47.4031183 -37.06474934
OS 47.30326582 -36.80124974
OS 47.30326582 -36.7998629
OS 47.30187898 -36.79570238
OS 47.2991053 -36.78876818
OS 47.29633162 -36.78044714
OS 47.2921711 -36.77073926
OS 47.28801058 -36.7582577
OS 47.28385006 -36.7443893
OS 47.2783027 -36.7305209
OS 47.26720798 -36.69862358
OS 47.25611326 -36.66533942
OS 47.24501854 -36.63205526
OS 47.23531066 -36.60015794
OE
SE
S P 0
OB 53.57408132 -38.30725892 I
OS 53.5861006 -38.30910804
OS 53.60089356 -38.31188172
OS 53.61753564 -38.31650452
OS 53.63417772 -38.32205188
OS 53.6508198 -38.32944836
OS 53.65174436 -38.32944836
OS 53.65266892 -38.33037292
OS 53.65821628 -38.3331466
OS 53.66653732 -38.33869396
OS 53.67578292 -38.34516588
OS 53.68687764 -38.35441148
OS 53.69797236 -38.36458164
OS 53.70906708 -38.37660092
OS 53.71831268 -38.39046932
OS 53.71923724 -38.39231844
OS 53.72201092 -38.39694124
OS 53.72570916 -38.40526228
OS 53.73033196 -38.41543244
OS 53.73495476 -38.42745172
OS 53.738653 -38.44132012
OS 53.74142668 -38.45703764
OS 53.74235124 -38.47275516
OS 53.74235124 -38.47460428
OS 53.74235124 -38.48015164
OS 53.74142668 -38.48754812
OS 53.73957756 -38.49771828
OS 53.73680388 -38.50973756
OS 53.73218108 -38.5226814
OS 53.72663372 -38.53562524
OS 53.71923724 -38.54856908
OS 53.71831268 -38.5504182
OS 53.715539 -38.55411644
OS 53.70999164 -38.56058836
OS 53.70259516 -38.56798484
OS 53.69334956 -38.57630588
OS 53.68225484 -38.58555148
OS 53.669311 -38.59387252
OS 53.65359348 -38.60219356
OS 53.65451804 -38.60219356
OS 53.65636716 -38.60311812
OS 53.65914084 -38.60404268
OS 53.66283908 -38.60496724
OS 53.67300924 -38.60866548
OS 53.68595308 -38.61421284
OS 53.70074604 -38.62160932
OS 53.715539 -38.63085492
OS 53.7294074 -38.6428742
OS 53.74235124 -38.6567426
OS 53.7432758 -38.65859172
OS 53.74697404 -38.66413908
OS 53.7525214 -38.67338468
OS 53.75806876 -38.68540396
OS 53.76361612 -38.70019692
OS 53.76916348 -38.71776356
OS 53.77286172 -38.73810388
OS 53.77378628 -38.76029332
OS 53.77378628 -38.76121788
OS 53.77378628 -38.76399156
OS 53.77378628 -38.76861436
OS 53.77286172 -38.77416172
OS 53.77193716 -38.7815582
OS 53.77008804 -38.78987924
OS 53.76823892 -38.79912484
OS 53.7663898 -38.809295
OS 53.75899332 -38.83148444
OS 53.75344596 -38.84350372
OS 53.7478986 -38.85459844
OS 53.74050212 -38.86661772
OS 53.73218108 -38.878637
OS 53.72293548 -38.89065628
OS 53.71184076 -38.901751
OS 53.7109162 -38.90267556
OS 53.70906708 -38.90452468
OS 53.70536884 -38.90729836
OS 53.70074604 -38.9109966
OS 53.69519868 -38.9156194
OS 53.6878022 -38.9202422
OS 53.67948116 -38.92578956
OS 53.669311 -38.93041236
OS 53.65914084 -38.93595972
OS 53.64712156 -38.94150708
OS 53.63510228 -38.94612988
OS 53.62123388 -38.95075268
OS 53.60644092 -38.95445092
OS 53.5907234 -38.9572246
OS 53.57500588 -38.95907372
OS 53.55743924 -38.95999828
OS 53.5491182 -38.95999828
OS 53.54357084 -38.95907372
OS 53.53617436 -38.95814916
OS 53.52785332 -38.9572246
OS 53.51860772 -38.95537548
OS 53.50843756 -38.95352636
OS 53.48624812 -38.947979
OS 53.46313412 -38.9387334
OS 53.45111484 -38.93318604
OS 53.44002012 -38.92671412
OS 53.4289254 -38.91839308
OS 53.41783068 -38.91007204
OS 53.41690612 -38.90914748
OS 53.415057 -38.90729836
OS 53.41228332 -38.90452468
OS 53.40950964 -38.90082644
OS 53.40488684 -38.89620364
OS 53.40026404 -38.88973172
OS 53.39471668 -38.8832598
OS 53.38916932 -38.87493876
OS 53.38362196 -38.86569316
OS 53.3780746 -38.85644756
OS 53.36790444 -38.83425812
OS 53.3595834 -38.80837044
OS 53.35680972 -38.79450204
OS 53.3549606 -38.77970908
OS 53.4335482 -38.76953892
OS 53.4335482 -38.77046348
OS 53.43447276 -38.7723126
OS 53.43539732 -38.77601084
OS 53.43632188 -38.78063364
OS 53.43724644 -38.786181
OS 53.43909556 -38.79265292
OS 53.44371836 -38.80652132
OS 53.45019028 -38.8231634
OS 53.45851132 -38.83888092
OS 53.46775692 -38.85367388
OS 53.47885164 -38.86661772
OS 53.48070076 -38.86754228
OS 53.484399 -38.87124052
OS 53.49179548 -38.87586332
OS 53.50104108 -38.88048612
OS 53.5121358 -38.88603348
OS 53.5260042 -38.89065628
OS 53.54172172 -38.89435452
OS 53.5583638 -38.89527908
OS 53.56391116 -38.89527908
OS 53.5676094 -38.89435452
OS 53.57777956 -38.89342996
OS 53.5907234 -38.89065628
OS 53.60551636 -38.88603348
OS 53.62123388 -38.87956156
OS 53.6369514 -38.87031596
OS 53.65174436 -38.85737212
OS 53.65359348 -38.855523
OS 53.65821628 -38.84997564
OS 53.66376364 -38.8416546
OS 53.67116012 -38.83055988
OS 53.6785566 -38.81669148
OS 53.68410396 -38.80097396
OS 53.68872676 -38.78248276
OS 53.69057588 -38.76214244
OS 53.69057588 -38.76121788
OS 53.69057588 -38.75936876
OS 53.69057588 -38.75659508
OS 53.68965132 -38.75289684
OS 53.68872676 -38.74272668
OS 53.68595308 -38.7307074
OS 53.68225484 -38.71591444
OS 53.67578292 -38.70112148
OS 53.66653732 -38.68632852
OS 53.65451804 -38.67246012
OS 53.65266892 -38.670611
OS 53.64804612 -38.66691276
OS 53.64064964 -38.6613654
OS 53.63047948 -38.65489348
OS 53.61753564 -38.64842156
OS 53.60181812 -38.6428742
OS 53.58425148 -38.63917596
OS 53.56483572 -38.63732684
OS 53.55651468 -38.63732684
OS 53.55004276 -38.6382514
OS 53.54172172 -38.63917596
OS 53.53247612 -38.64102508
OS 53.5213814 -38.6428742
OS 53.50936212 -38.64564788
OS 53.51860772 -38.57630588
OS 53.52323052 -38.57630588
OS 53.52692876 -38.57723044
OS 53.53894804 -38.57723044
OS 53.5491182 -38.57538132
OS 53.56113748 -38.5735322
OS 53.57500588 -38.57075852
OS 53.5907234 -38.56613572
OS 53.60551636 -38.5596638
OS 53.62123388 -38.55134276
OS 53.62215844 -38.55134276
OS 53.623083 -38.5504182
OS 53.6277058 -38.54671996
OS 53.63417772 -38.54024804
OS 53.6415742 -38.531927
OS 53.64897068 -38.51990772
OS 53.6554426 -38.50603932
OS 53.6600654 -38.4903218
OS 53.66191452 -38.4810762
OS 53.66191452 -38.47090604
OS 53.66191452 -38.46998148
OS 53.66191452 -38.46905692
OS 53.66191452 -38.46350956
OS 53.6600654 -38.45611308
OS 53.65821628 -38.44594292
OS 53.65451804 -38.4348482
OS 53.64989524 -38.42282892
OS 53.64249876 -38.41080964
OS 53.6323286 -38.39971492
OS 53.63140404 -38.39879036
OS 53.62678124 -38.39509212
OS 53.62030932 -38.39046932
OS 53.61198828 -38.38492196
OS 53.60089356 -38.38029916
OS 53.58794972 -38.37567636
OS 53.57315676 -38.37197812
OS 53.55651468 -38.37105356
OS 53.5491182 -38.37105356
OS 53.54079716 -38.37290268
OS 53.52970244 -38.3747518
OS 53.51768316 -38.37845004
OS 53.50566388 -38.38307284
OS 53.49272004 -38.39046932
OS 53.48070076 -38.39971492
OS 53.4797762 -38.40063948
OS 53.47607796 -38.40526228
OS 53.4705306 -38.4117342
OS 53.46405868 -38.4209798
OS 53.45758676 -38.43299908
OS 53.45111484 -38.44779204
OS 53.44556748 -38.46535868
OS 53.44186924 -38.485699
OS 53.36328164 -38.4718306
OS 53.36328164 -38.47090604
OS 53.3642062 -38.46813236
OS 53.36513076 -38.46443412
OS 53.36605532 -38.45888676
OS 53.36790444 -38.45241484
OS 53.37067812 -38.44501836
OS 53.37622548 -38.42745172
OS 53.38547108 -38.4071114
OS 53.3965658 -38.38677108
OS 53.4104342 -38.36735532
OS 53.42800084 -38.34978868
OS 53.4289254 -38.34886412
OS 53.43077452 -38.34793956
OS 53.4335482 -38.34609044
OS 53.43724644 -38.34331676
OS 53.44186924 -38.33961852
OS 53.44834116 -38.33592028
OS 53.45481308 -38.33222204
OS 53.46313412 -38.32759924
OS 53.48162532 -38.32020276
OS 53.5028902 -38.31280628
OS 53.52785332 -38.30818348
OS 53.54079716 -38.30633436
OS 53.56391116 -38.30633436
OS 53.57408132 -38.30725892
OE
OB 54.07889108 -38.30725892 I
OS 54.09091036 -38.30910804
OS 54.10477876 -38.31188172
OS 54.11957172 -38.31557996
OS 54.13528924 -38.32020276
OS 54.1500822 -38.32759924
OS 54.15100676 -38.32759924
OS 54.15193132 -38.3285238
OS 54.15655412 -38.33129748
OS 54.1639506 -38.33592028
OS 54.1731962 -38.3423922
OS 54.18336636 -38.3516378
OS 54.19446108 -38.36180796
OS 54.20463124 -38.37382724
OS 54.2148014 -38.38769564
OS 54.21572596 -38.38954476
OS 54.2194242 -38.39416756
OS 54.22312244 -38.4024886
OS 54.22959436 -38.41450788
OS 54.23514172 -38.42837628
OS 54.2425382 -38.4440938
OS 54.24901012 -38.462585
OS 54.25455748 -38.48292532
OS 54.25455748 -38.48384988
OS 54.25548204 -38.485699
OS 54.2564066 -38.48847268
OS 54.25733116 -38.49309548
OS 54.25825572 -38.49864284
OS 54.25918028 -38.50511476
OS 54.2610294 -38.5134358
OS 54.26195396 -38.5226814
OS 54.26380308 -38.53285156
OS 54.26472764 -38.54394628
OS 54.2656522 -38.55689012
OS 54.26750132 -38.56983396
OS 54.26842588 -38.58462692
OS 54.26842588 -38.59941988
OS 54.26935044 -38.61606196
OS 54.26935044 -38.6336286
OS 54.26935044 -38.63455316
OS 54.26935044 -38.6382514
OS 54.26935044 -38.64472332
OS 54.26935044 -38.6521198
OS 54.26842588 -38.66228996
OS 54.26842588 -38.67338468
OS 54.26750132 -38.68540396
OS 54.26657676 -38.6983478
OS 54.26380308 -38.72793372
OS 54.25918028 -38.7584442
OS 54.25363292 -38.78803012
OS 54.24993468 -38.80189852
OS 54.24531188 -38.81576692
OS 54.24531188 -38.81669148
OS 54.24438732 -38.8185406
OS 54.2425382 -38.82223884
OS 54.24068908 -38.82686164
OS 54.23883996 -38.83333356
OS 54.23514172 -38.83980548
OS 54.22774524 -38.855523
OS 54.21849964 -38.87216508
OS 54.20648036 -38.89065628
OS 54.19261196 -38.90729836
OS 54.17596988 -38.92301588
OS 54.17504532 -38.92301588
OS 54.17412076 -38.924865
OS 54.17134708 -38.92671412
OS 54.16764884 -38.92856324
OS 54.16302604 -38.93133692
OS 54.15840324 -38.93503516
OS 54.14453484 -38.94150708
OS 54.12789276 -38.947979
OS 54.108477 -38.95445092
OS 54.085363 -38.95814916
OS 54.06039988 -38.95999828
OS 54.05115428 -38.95999828
OS 54.04468236 -38.95907372
OS 54.03728588 -38.95814916
OS 54.02804028 -38.95630004
OS 54.01787012 -38.95445092
OS 54.0067754 -38.95167724
OS 53.99568068 -38.947979
OS 53.9836614 -38.94428076
OS 53.97164212 -38.9387334
OS 53.95962284 -38.93226148
OS 53.94760356 -38.924865
OS 53.93558428 -38.9156194
OS 53.92448956 -38.90544924
OS 53.9143194 -38.89435452
OS 53.91339484 -38.89342996
OS 53.91154572 -38.89065628
OS 53.90877204 -38.88603348
OS 53.90414924 -38.878637
OS 53.89952644 -38.87031596
OS 53.89490364 -38.85922124
OS 53.88843172 -38.8462774
OS 53.88288436 -38.83148444
OS 53.877337 -38.81484236
OS 53.87178964 -38.7954266
OS 53.86624228 -38.77416172
OS 53.86161948 -38.75012316
OS 53.85699668 -38.72423548
OS 53.854223 -38.69649868
OS 53.85237388 -38.6659882
OS 53.85144932 -38.6336286
OS 53.85144932 -38.63270404
OS 53.85144932 -38.6290058
OS 53.85144932 -38.62253388
OS 53.85144932 -38.6151374
OS 53.85237388 -38.60496724
OS 53.85237388 -38.59387252
OS 53.85329844 -38.58185324
OS 53.854223 -38.56798484
OS 53.85699668 -38.53932348
OS 53.86161948 -38.508813
OS 53.86716684 -38.47830252
OS 53.87086508 -38.46443412
OS 53.87456332 -38.45056572
OS 53.87456332 -38.44964116
OS 53.87548788 -38.44779204
OS 53.877337 -38.4440938
OS 53.87918612 -38.439471
OS 53.88103524 -38.43299908
OS 53.88473348 -38.42652716
OS 53.89212996 -38.41080964
OS 53.90137556 -38.39416756
OS 53.91339484 -38.37660092
OS 53.92726324 -38.35903428
OS 53.94390532 -38.34424132
OS 53.94482988 -38.34424132
OS 53.94575444 -38.3423922
OS 53.94852812 -38.34054308
OS 53.95222636 -38.33869396
OS 53.95684916 -38.33499572
OS 53.96239652 -38.33222204
OS 53.97626492 -38.32482556
OS 53.992907 -38.31835364
OS 54.01232276 -38.31188172
OS 54.03543676 -38.30818348
OS 54.06039988 -38.30633436
OS 54.06872092 -38.30633436
OS 54.07889108 -38.30725892
OE
OB 53.23846604 -38.94890356 I
OS 53.14878372 -38.94890356
OS 53.14878372 -38.85922124
OS 53.23846604 -38.85922124
OS 53.23846604 -38.94890356
OE
OB 53.00177868 -38.39231844 I
OS 52.74567556 -38.39231844
OS 52.71146684 -38.56521116
OS 52.7123914 -38.5642866
OS 52.71424052 -38.56336204
OS 52.7170142 -38.56151292
OS 52.721637 -38.55873924
OS 52.72718436 -38.55596556
OS 52.73365628 -38.55226732
OS 52.74844924 -38.54487084
OS 52.76694044 -38.53747436
OS 52.78728076 -38.53100244
OS 52.8094702 -38.52637964
OS 52.82056492 -38.52453052
OS 52.84090524 -38.52453052
OS 52.8464526 -38.52545508
OS 52.85384908 -38.52637964
OS 52.86217012 -38.5273042
OS 52.87141572 -38.52915332
OS 52.88158588 -38.531927
OS 52.90377532 -38.53839892
OS 52.9157946 -38.54302172
OS 52.92781388 -38.54949364
OS 52.93983316 -38.55596556
OS 52.95185244 -38.56336204
OS 52.96294716 -38.57260764
OS 52.97404188 -38.5827778
OS 52.97496644 -38.58370236
OS 52.97681556 -38.58555148
OS 52.97958924 -38.58832516
OS 52.98328748 -38.59294796
OS 52.98791028 -38.59941988
OS 52.99253308 -38.6058918
OS 52.99808044 -38.61421284
OS 53.0036278 -38.62345844
OS 53.0082506 -38.6336286
OS 53.01379796 -38.64472332
OS 53.01842076 -38.65766716
OS 53.02304356 -38.670611
OS 53.0267418 -38.6844794
OS 53.02951548 -38.70019692
OS 53.0313646 -38.71591444
OS 53.03228916 -38.73255652
OS 53.03228916 -38.73348108
OS 53.03228916 -38.73625476
OS 53.03228916 -38.74087756
OS 53.0313646 -38.74734948
OS 53.03044004 -38.75474596
OS 53.02951548 -38.763067
OS 53.02766636 -38.77323716
OS 53.02581724 -38.78340732
OS 53.02026988 -38.80744588
OS 53.01102428 -38.832409
OS 53.00547692 -38.84535284
OS 52.99808044 -38.85737212
OS 52.99068396 -38.87031596
OS 52.98143836 -38.88233524
OS 52.9805138 -38.8832598
OS 52.97866468 -38.88603348
OS 52.97496644 -38.88973172
OS 52.97034364 -38.89435452
OS 52.96387172 -38.89990188
OS 52.95647524 -38.90729836
OS 52.94722964 -38.91377028
OS 52.93705948 -38.92116676
OS 52.92596476 -38.92856324
OS 52.91302092 -38.93503516
OS 52.89915252 -38.94150708
OS 52.88435956 -38.947979
OS 52.86864204 -38.9526018
OS 52.8510754 -38.95630004
OS 52.8325842 -38.95907372
OS 52.81316844 -38.95999828
OS 52.8048474 -38.95999828
OS 52.79837548 -38.95907372
OS 52.790979 -38.95814916
OS 52.78265796 -38.9572246
OS 52.7724878 -38.95630004
OS 52.76231764 -38.95352636
OS 52.73920364 -38.947979
OS 52.71608964 -38.93965796
OS 52.70407036 -38.9341106
OS 52.69205108 -38.92763868
OS 52.68095636 -38.9202422
OS 52.66986164 -38.91192116
OS 52.66893708 -38.9109966
OS 52.66708796 -38.91007204
OS 52.66523884 -38.9063738
OS 52.6615406 -38.90267556
OS 52.6569178 -38.89805276
OS 52.652295 -38.8925054
OS 52.64674764 -38.88510892
OS 52.64212484 -38.87678788
OS 52.63657748 -38.86846684
OS 52.63103012 -38.85829668
OS 52.62085996 -38.83610724
OS 52.61253892 -38.81021956
OS 52.60976524 -38.79635116
OS 52.60791612 -38.7815582
OS 52.69020196 -38.77508628
OS 52.69020196 -38.77601084
OS 52.69020196 -38.77785996
OS 52.69112652 -38.78063364
OS 52.69205108 -38.78525644
OS 52.69482476 -38.7954266
OS 52.698523 -38.809295
OS 52.70407036 -38.8231634
OS 52.71146684 -38.83888092
OS 52.72071244 -38.85274932
OS 52.73180716 -38.86569316
OS 52.73365628 -38.86661772
OS 52.73735452 -38.87031596
OS 52.744751 -38.87493876
OS 52.75492116 -38.88048612
OS 52.76601588 -38.88603348
OS 52.77988428 -38.89065628
OS 52.7956018 -38.89435452
OS 52.81316844 -38.89527908
OS 52.8187158 -38.89527908
OS 52.82241404 -38.89435452
OS 52.83350876 -38.89342996
OS 52.8464526 -38.88973172
OS 52.86217012 -38.88510892
OS 52.87788764 -38.87771244
OS 52.89452972 -38.86661772
OS 52.9019262 -38.8601458
OS 52.90932268 -38.85274932
OS 52.91024724 -38.85182476
OS 52.9111718 -38.8509002
OS 52.91302092 -38.84812652
OS 52.9157946 -38.84535284
OS 52.92226652 -38.83518268
OS 52.929663 -38.82223884
OS 52.93613492 -38.80652132
OS 52.94260684 -38.78710556
OS 52.94722964 -38.76399156
OS 52.94907876 -38.75197228
OS 52.94907876 -38.73902844
OS 52.94907876 -38.73810388
OS 52.94907876 -38.73625476
OS 52.94907876 -38.73255652
OS 52.9481542 -38.72793372
OS 52.9481542 -38.72238636
OS 52.94722964 -38.71591444
OS 52.94445596 -38.70112148
OS 52.93983316 -38.68355484
OS 52.93336124 -38.6659882
OS 52.92411564 -38.64934612
OS 52.9111718 -38.6336286
OS 52.9111718 -38.63270404
OS 52.90932268 -38.63177948
OS 52.90469988 -38.62715668
OS 52.89637884 -38.62068476
OS 52.88528412 -38.61328828
OS 52.87049116 -38.60681636
OS 52.85384908 -38.60034444
OS 52.83443332 -38.59572164
OS 52.8233386 -38.59387252
OS 52.80577196 -38.59387252
OS 52.79837548 -38.59479708
OS 52.78912988 -38.59572164
OS 52.77803516 -38.59849532
OS 52.76694044 -38.601269
OS 52.75492116 -38.6058918
OS 52.74290188 -38.61143916
OS 52.74197732 -38.61236372
OS 52.73827908 -38.61421284
OS 52.73273172 -38.61883564
OS 52.72533524 -38.62345844
OS 52.71793876 -38.62993036
OS 52.71054228 -38.6382514
OS 52.70222124 -38.64657244
OS 52.69574932 -38.6567426
OS 52.62178452 -38.64657244
OS 52.68373004 -38.31742908
OS 53.00177868 -38.31742908
OS 53.00177868 -38.39231844
OE
OB 53.23846604 -38.57445676 I
OS 53.14878372 -38.57445676
OS 53.14878372 -38.48477444
OS 53.23846604 -38.48477444
OS 53.23846604 -38.57445676
OE
OB 54.48199924 -38.57445676 I
OS 54.39231692 -38.57445676
OS 54.39231692 -38.48477444
OS 54.48199924 -38.48477444
OS 54.48199924 -38.57445676
OE
OB 56.14990548 -38.3100326 I
OS 56.165623 -38.31095716
OS 56.18226508 -38.31188172
OS 56.1979826 -38.31373084
OS 56.211851 -38.31557996
OS 56.21370012 -38.31557996
OS 56.22017204 -38.31742908
OS 56.22849308 -38.3192782
OS 56.2395878 -38.32205188
OS 56.25160708 -38.32667468
OS 56.26455092 -38.33222204
OS 56.27841932 -38.33869396
OS 56.2904386 -38.34609044
OS 56.29228772 -38.347015
OS 56.29598596 -38.34978868
OS 56.30153332 -38.35533604
OS 56.3089298 -38.36180796
OS 56.31725084 -38.370129
OS 56.32557188 -38.38122372
OS 56.33481748 -38.393243
OS 56.34221396 -38.4071114
OS 56.34313852 -38.40896052
OS 56.34498764 -38.41358332
OS 56.34868588 -38.42190436
OS 56.35238412 -38.43299908
OS 56.3551578 -38.44594292
OS 56.35885604 -38.46073588
OS 56.36070516 -38.47737796
OS 56.36162972 -38.4949446
OS 56.36162972 -38.49586916
OS 56.36162972 -38.49864284
OS 56.36162972 -38.50234108
OS 56.36070516 -38.508813
OS 56.3597806 -38.51528492
OS 56.35885604 -38.52360596
OS 56.35700692 -38.53285156
OS 56.3551578 -38.54302172
OS 56.34868588 -38.5642866
OS 56.34498764 -38.57538132
OS 56.33944028 -38.5874006
OS 56.33296836 -38.59941988
OS 56.32649644 -38.6105146
OS 56.3181754 -38.62160932
OS 56.3089298 -38.63270404
OS 56.30800524 -38.6336286
OS 56.30615612 -38.63547772
OS 56.30338244 -38.6382514
OS 56.29875964 -38.64102508
OS 56.29321228 -38.64564788
OS 56.2858158 -38.65027068
OS 56.2765702 -38.65581804
OS 56.26640004 -38.66044084
OS 56.25438076 -38.6659882
OS 56.24051236 -38.67153556
OS 56.2257194 -38.67615836
OS 56.20815276 -38.6798566
OS 56.18966156 -38.68355484
OS 56.16932124 -38.68632852
OS 56.14620724 -38.68817764
OS 56.12216868 -38.6891022
OS 55.95852156 -38.6891022
OS 55.95852156 -38.94890356
OS 55.87346204 -38.94890356
OS 55.87346204 -38.30910804
OS 56.13603708 -38.30910804
OS 56.14990548 -38.3100326
OE
OB 57.07723916 -38.94890356 I
OS 56.99587788 -38.94890356
OS 56.99587788 -38.41358332
OS 56.80911676 -38.94890356
OS 56.73330284 -38.94890356
OS 56.54839084 -38.40433772
OS 56.54839084 -38.94890356
OS 56.46702956 -38.94890356
OS 56.46702956 -38.30910804
OS 56.59369428 -38.30910804
OS 56.74532212 -38.763067
OS 56.74532212 -38.76399156
OS 56.74624668 -38.76584068
OS 56.74717124 -38.76861436
OS 56.74902036 -38.77323716
OS 56.7527186 -38.78433188
OS 56.7573414 -38.79820028
OS 56.7619642 -38.8139178
OS 56.76751156 -38.82963532
OS 56.77213436 -38.84442828
OS 56.7758326 -38.85737212
OS 56.77675716 -38.855523
OS 56.77768172 -38.8509002
OS 56.7804554 -38.84257916
OS 56.78415364 -38.83148444
OS 56.78877644 -38.81669148
OS 56.79524836 -38.79912484
OS 56.80172028 -38.77878452
OS 56.81004132 -38.75474596
OS 56.96351828 -38.30910804
OS 57.07723916 -38.30910804
OS 57.07723916 -38.94890356
OE
OB 55.3150278 -38.30725892 I
OS 55.32704708 -38.30910804
OS 55.34184004 -38.31188172
OS 55.35848212 -38.31650452
OS 55.3751242 -38.32205188
OS 55.39176628 -38.32944836
OS 55.39269084 -38.32944836
OS 55.3936154 -38.33037292
OS 55.39916276 -38.3331466
OS 55.4074838 -38.33869396
OS 55.4167294 -38.34516588
OS 55.42782412 -38.35441148
OS 55.43891884 -38.36458164
OS 55.45001356 -38.37660092
OS 55.45925916 -38.39046932
OS 55.46018372 -38.39231844
OS 55.4629574 -38.39694124
OS 55.46665564 -38.40526228
OS 55.47127844 -38.41543244
OS 55.47590124 -38.42745172
OS 55.47959948 -38.44132012
OS 55.48237316 -38.45703764
OS 55.48329772 -38.47275516
OS 55.48329772 -38.47460428
OS 55.48329772 -38.48015164
OS 55.48237316 -38.48754812
OS 55.48052404 -38.49771828
OS 55.47775036 -38.50973756
OS 55.47312756 -38.5226814
OS 55.4675802 -38.53562524
OS 55.46018372 -38.54856908
OS 55.45925916 -38.5504182
OS 55.45648548 -38.55411644
OS 55.45093812 -38.56058836
OS 55.44354164 -38.56798484
OS 55.43429604 -38.57630588
OS 55.42320132 -38.58555148
OS 55.41025748 -38.59387252
OS 55.39453996 -38.60219356
OS 55.39546452 -38.60219356
OS 55.39731364 -38.60311812
OS 55.40008732 -38.60404268
OS 55.40378556 -38.60496724
OS 55.41395572 -38.60866548
OS 55.42689956 -38.61421284
OS 55.44169252 -38.62160932
OS 55.45648548 -38.63085492
OS 55.47035388 -38.6428742
OS 55.48329772 -38.6567426
OS 55.48422228 -38.65859172
OS 55.48792052 -38.66413908
OS 55.49346788 -38.67338468
OS 55.49901524 -38.68540396
OS 55.5045626 -38.70019692
OS 55.51010996 -38.71776356
OS 55.5138082 -38.73810388
OS 55.51473276 -38.76029332
OS 55.51473276 -38.76121788
OS 55.51473276 -38.76399156
OS 55.51473276 -38.76861436
OS 55.5138082 -38.77416172
OS 55.51288364 -38.7815582
OS 55.51103452 -38.78987924
OS 55.5091854 -38.79912484
OS 55.50733628 -38.809295
OS 55.4999398 -38.83148444
OS 55.49439244 -38.84350372
OS 55.48884508 -38.85459844
OS 55.4814486 -38.86661772
OS 55.47312756 -38.878637
OS 55.46388196 -38.89065628
OS 55.45278724 -38.901751
OS 55.45186268 -38.90267556
OS 55.45001356 -38.90452468
OS 55.44631532 -38.90729836
OS 55.44169252 -38.9109966
OS 55.43614516 -38.9156194
OS 55.42874868 -38.9202422
OS 55.42042764 -38.92578956
OS 55.41025748 -38.93041236
OS 55.40008732 -38.93595972
OS 55.38806804 -38.94150708
OS 55.37604876 -38.94612988
OS 55.36218036 -38.95075268
OS 55.3473874 -38.95445092
OS 55.33166988 -38.9572246
OS 55.31595236 -38.95907372
OS 55.29838572 -38.95999828
OS 55.29006468 -38.95999828
OS 55.28451732 -38.95907372
OS 55.27712084 -38.95814916
OS 55.2687998 -38.9572246
OS 55.2595542 -38.95537548
OS 55.24938404 -38.95352636
OS 55.2271946 -38.947979
OS 55.2040806 -38.9387334
OS 55.19206132 -38.93318604
OS 55.1809666 -38.92671412
OS 55.16987188 -38.91839308
OS 55.15877716 -38.91007204
OS 55.1578526 -38.90914748
OS 55.15600348 -38.90729836
OS 55.1532298 -38.90452468
OS 55.15045612 -38.90082644
OS 55.14583332 -38.89620364
OS 55.14121052 -38.88973172
OS 55.13566316 -38.8832598
OS 55.1301158 -38.87493876
OS 55.12456844 -38.86569316
OS 55.11902108 -38.85644756
OS 55.10885092 -38.83425812
OS 55.10052988 -38.80837044
OS 55.0977562 -38.79450204
OS 55.09590708 -38.77970908
OS 55.17449468 -38.76953892
OS 55.17449468 -38.77046348
OS 55.17541924 -38.7723126
OS 55.1763438 -38.77601084
OS 55.17726836 -38.78063364
OS 55.17819292 -38.786181
OS 55.18004204 -38.79265292
OS 55.18466484 -38.80652132
OS 55.19113676 -38.8231634
OS 55.1994578 -38.83888092
OS 55.2087034 -38.85367388
OS 55.21979812 -38.86661772
OS 55.22164724 -38.86754228
OS 55.22534548 -38.87124052
OS 55.23274196 -38.87586332
OS 55.24198756 -38.88048612
OS 55.25308228 -38.88603348
OS 55.26695068 -38.89065628
OS 55.2826682 -38.89435452
OS 55.29931028 -38.89527908
OS 55.30485764 -38.89527908
OS 55.30855588 -38.89435452
OS 55.31872604 -38.89342996
OS 55.33166988 -38.89065628
OS 55.34646284 -38.88603348
OS 55.36218036 -38.87956156
OS 55.37789788 -38.87031596
OS 55.39269084 -38.85737212
OS 55.39453996 -38.855523
OS 55.39916276 -38.84997564
OS 55.40471012 -38.8416546
OS 55.4121066 -38.83055988
OS 55.41950308 -38.81669148
OS 55.42505044 -38.80097396
OS 55.42967324 -38.78248276
OS 55.43152236 -38.76214244
OS 55.43152236 -38.76121788
OS 55.43152236 -38.75936876
OS 55.43152236 -38.75659508
OS 55.4305978 -38.75289684
OS 55.42967324 -38.74272668
OS 55.42689956 -38.7307074
OS 55.42320132 -38.71591444
OS 55.4167294 -38.70112148
OS 55.4074838 -38.68632852
OS 55.39546452 -38.67246012
OS 55.3936154 -38.670611
OS 55.3889926 -38.66691276
OS 55.38159612 -38.6613654
OS 55.37142596 -38.65489348
OS 55.35848212 -38.64842156
OS 55.3427646 -38.6428742
OS 55.32519796 -38.63917596
OS 55.3057822 -38.63732684
OS 55.29746116 -38.63732684
OS 55.29098924 -38.6382514
OS 55.2826682 -38.63917596
OS 55.2734226 -38.64102508
OS 55.26232788 -38.6428742
OS 55.2503086 -38.64564788
OS 55.2595542 -38.57630588
OS 55.264177 -38.57630588
OS 55.26787524 -38.57723044
OS 55.27989452 -38.57723044
OS 55.29006468 -38.57538132
OS 55.30208396 -38.5735322
OS 55.31595236 -38.57075852
OS 55.33166988 -38.56613572
OS 55.34646284 -38.5596638
OS 55.36218036 -38.55134276
OS 55.36310492 -38.55134276
OS 55.36402948 -38.5504182
OS 55.36865228 -38.54671996
OS 55.3751242 -38.54024804
OS 55.38252068 -38.531927
OS 55.38991716 -38.51990772
OS 55.39638908 -38.50603932
OS 55.40101188 -38.4903218
OS 55.402861 -38.4810762
OS 55.402861 -38.47090604
OS 55.402861 -38.46998148
OS 55.402861 -38.46905692
OS 55.402861 -38.46350956
OS 55.40101188 -38.45611308
OS 55.39916276 -38.44594292
OS 55.39546452 -38.4348482
OS 55.39084172 -38.42282892
OS 55.38344524 -38.41080964
OS 55.37327508 -38.39971492
OS 55.37235052 -38.39879036
OS 55.36772772 -38.39509212
OS 55.3612558 -38.39046932
OS 55.35293476 -38.38492196
OS 55.34184004 -38.38029916
OS 55.3288962 -38.37567636
OS 55.31410324 -38.37197812
OS 55.29746116 -38.37105356
OS 55.29006468 -38.37105356
OS 55.28174364 -38.37290268
OS 55.27064892 -38.3747518
OS 55.25862964 -38.37845004
OS 55.24661036 -38.38307284
OS 55.23366652 -38.39046932
OS 55.22164724 -38.39971492
OS 55.22072268 -38.40063948
OS 55.21702444 -38.40526228
OS 55.21147708 -38.4117342
OS 55.20500516 -38.4209798
OS 55.19853324 -38.43299908
OS 55.19206132 -38.44779204
OS 55.18651396 -38.46535868
OS 55.18281572 -38.485699
OS 55.10422812 -38.4718306
OS 55.10422812 -38.47090604
OS 55.10515268 -38.46813236
OS 55.10607724 -38.46443412
OS 55.1070018 -38.45888676
OS 55.10885092 -38.45241484
OS 55.1116246 -38.44501836
OS 55.11717196 -38.42745172
OS 55.12641756 -38.4071114
OS 55.13751228 -38.38677108
OS 55.15138068 -38.36735532
OS 55.16894732 -38.34978868
OS 55.16987188 -38.34886412
OS 55.171721 -38.34793956
OS 55.17449468 -38.34609044
OS 55.17819292 -38.34331676
OS 55.18281572 -38.33961852
OS 55.18928764 -38.33592028
OS 55.19575956 -38.33222204
OS 55.2040806 -38.32759924
OS 55.2225718 -38.32020276
OS 55.24383668 -38.31280628
OS 55.2687998 -38.30818348
OS 55.28174364 -38.30633436
OS 55.30485764 -38.30633436
OS 55.3150278 -38.30725892
OE
OB 54.48199924 -38.94890356 I
OS 54.39231692 -38.94890356
OS 54.39231692 -38.85922124
OS 54.48199924 -38.85922124
OS 54.48199924 -38.94890356
OE
OB 54.9914318 -38.39231844 I
OS 54.73532868 -38.39231844
OS 54.70111996 -38.56521116
OS 54.70204452 -38.5642866
OS 54.70389364 -38.56336204
OS 54.70666732 -38.56151292
OS 54.71129012 -38.55873924
OS 54.71683748 -38.55596556
OS 54.7233094 -38.55226732
OS 54.73810236 -38.54487084
OS 54.75659356 -38.53747436
OS 54.77693388 -38.53100244
OS 54.79912332 -38.52637964
OS 54.81021804 -38.52453052
OS 54.83055836 -38.52453052
OS 54.83610572 -38.52545508
OS 54.8435022 -38.52637964
OS 54.85182324 -38.5273042
OS 54.86106884 -38.52915332
OS 54.871239 -38.531927
OS 54.89342844 -38.53839892
OS 54.90544772 -38.54302172
OS 54.917467 -38.54949364
OS 54.92948628 -38.55596556
OS 54.94150556 -38.56336204
OS 54.95260028 -38.57260764
OS 54.963695 -38.5827778
OS 54.96461956 -38.58370236
OS 54.96646868 -38.58555148
OS 54.96924236 -38.58832516
OS 54.9729406 -38.59294796
OS 54.9775634 -38.59941988
OS 54.9821862 -38.6058918
OS 54.98773356 -38.61421284
OS 54.99328092 -38.62345844
OS 54.99790372 -38.6336286
OS 55.00345108 -38.64472332
OS 55.00807388 -38.65766716
OS 55.01269668 -38.670611
OS 55.01639492 -38.6844794
OS 55.0191686 -38.70019692
OS 55.02101772 -38.71591444
OS 55.02194228 -38.73255652
OS 55.02194228 -38.73348108
OS 55.02194228 -38.73625476
OS 55.02194228 -38.74087756
OS 55.02101772 -38.74734948
OS 55.02009316 -38.75474596
OS 55.0191686 -38.763067
OS 55.01731948 -38.77323716
OS 55.01547036 -38.78340732
OS 55.009923 -38.80744588
OS 55.0006774 -38.832409
OS 54.99513004 -38.84535284
OS 54.98773356 -38.85737212
OS 54.98033708 -38.87031596
OS 54.97109148 -38.88233524
OS 54.97016692 -38.8832598
OS 54.9683178 -38.88603348
OS 54.96461956 -38.88973172
OS 54.95999676 -38.89435452
OS 54.95352484 -38.89990188
OS 54.94612836 -38.90729836
OS 54.93688276 -38.91377028
OS 54.9267126 -38.92116676
OS 54.91561788 -38.92856324
OS 54.90267404 -38.93503516
OS 54.88880564 -38.94150708
OS 54.87401268 -38.947979
OS 54.85829516 -38.9526018
OS 54.84072852 -38.95630004
OS 54.82223732 -38.95907372
OS 54.80282156 -38.95999828
OS 54.79450052 -38.95999828
OS 54.7880286 -38.95907372
OS 54.78063212 -38.95814916
OS 54.77231108 -38.9572246
OS 54.76214092 -38.95630004
OS 54.75197076 -38.95352636
OS 54.72885676 -38.947979
OS 54.70574276 -38.93965796
OS 54.69372348 -38.9341106
OS 54.6817042 -38.92763868
OS 54.67060948 -38.9202422
OS 54.65951476 -38.91192116
OS 54.6585902 -38.9109966
OS 54.65674108 -38.91007204
OS 54.65489196 -38.9063738
OS 54.65119372 -38.90267556
OS 54.64657092 -38.89805276
OS 54.64194812 -38.8925054
OS 54.63640076 -38.88510892
OS 54.63177796 -38.87678788
OS 54.6262306 -38.86846684
OS 54.62068324 -38.85829668
OS 54.61051308 -38.83610724
OS 54.60219204 -38.81021956
OS 54.59941836 -38.79635116
OS 54.59756924 -38.7815582
OS 54.67985508 -38.77508628
OS 54.67985508 -38.77601084
OS 54.67985508 -38.77785996
OS 54.68077964 -38.78063364
OS 54.6817042 -38.78525644
OS 54.68447788 -38.7954266
OS 54.68817612 -38.809295
OS 54.69372348 -38.8231634
OS 54.70111996 -38.83888092
OS 54.71036556 -38.85274932
OS 54.72146028 -38.86569316
OS 54.7233094 -38.86661772
OS 54.72700764 -38.87031596
OS 54.73440412 -38.87493876
OS 54.74457428 -38.88048612
OS 54.755669 -38.88603348
OS 54.7695374 -38.89065628
OS 54.78525492 -38.89435452
OS 54.80282156 -38.89527908
OS 54.80836892 -38.89527908
OS 54.81206716 -38.89435452
OS 54.82316188 -38.89342996
OS 54.83610572 -38.88973172
OS 54.85182324 -38.88510892
OS 54.86754076 -38.87771244
OS 54.88418284 -38.86661772
OS 54.89157932 -38.8601458
OS 54.8989758 -38.85274932
OS 54.89990036 -38.85182476
OS 54.90082492 -38.8509002
OS 54.90267404 -38.84812652
OS 54.90544772 -38.84535284
OS 54.91191964 -38.83518268
OS 54.91931612 -38.82223884
OS 54.92578804 -38.80652132
OS 54.93225996 -38.78710556
OS 54.93688276 -38.76399156
OS 54.93873188 -38.75197228
OS 54.93873188 -38.73902844
OS 54.93873188 -38.73810388
OS 54.93873188 -38.73625476
OS 54.93873188 -38.73255652
OS 54.93780732 -38.72793372
OS 54.93780732 -38.72238636
OS 54.93688276 -38.71591444
OS 54.93410908 -38.70112148
OS 54.92948628 -38.68355484
OS 54.92301436 -38.6659882
OS 54.91376876 -38.64934612
OS 54.90082492 -38.6336286
OS 54.90082492 -38.63270404
OS 54.8989758 -38.63177948
OS 54.894353 -38.62715668
OS 54.88603196 -38.62068476
OS 54.87493724 -38.61328828
OS 54.86014428 -38.60681636
OS 54.8435022 -38.60034444
OS 54.82408644 -38.59572164
OS 54.81299172 -38.59387252
OS 54.79542508 -38.59387252
OS 54.7880286 -38.59479708
OS 54.778783 -38.59572164
OS 54.76768828 -38.59849532
OS 54.75659356 -38.601269
OS 54.74457428 -38.6058918
OS 54.732555 -38.61143916
OS 54.73163044 -38.61236372
OS 54.7279322 -38.61421284
OS 54.72238484 -38.61883564
OS 54.71498836 -38.62345844
OS 54.70759188 -38.62993036
OS 54.7001954 -38.6382514
OS 54.69187436 -38.64657244
OS 54.68540244 -38.6567426
OS 54.61143764 -38.64657244
OS 54.67338316 -38.31742908
OS 54.9914318 -38.31742908
OS 54.9914318 -38.39231844
OE
OB 49.95350436 -38.72331092 I
OS 50.040413 -38.72331092
OS 50.040413 -38.7954266
OS 49.95350436 -38.7954266
OS 49.95350436 -38.94890356
OS 49.87491676 -38.94890356
OS 49.87491676 -38.7954266
OS 49.5966242 -38.7954266
OS 49.5966242 -38.72331092
OS 49.88970972 -38.30910804
OS 49.95350436 -38.30910804
OS 49.95350436 -38.72331092
OE
OB 50.1467374 -38.95999828 I
OS 50.08386732 -38.95999828
OS 50.26970388 -38.29801332
OS 50.33257396 -38.29801332
OS 50.1467374 -38.95999828
OE
OB 49.35346492 -38.30725892 I
OS 49.3608614 -38.30818348
OS 49.370107 -38.30910804
OS 49.38027716 -38.31095716
OS 49.39044732 -38.31280628
OS 49.41448588 -38.3192782
OS 49.43852444 -38.3285238
OS 49.45054372 -38.33407116
OS 49.462563 -38.34054308
OS 49.47365772 -38.34886412
OS 49.48382788 -38.35810972
OS 49.48475244 -38.35903428
OS 49.48660156 -38.35995884
OS 49.48845068 -38.36365708
OS 49.49214892 -38.36735532
OS 49.49677172 -38.37197812
OS 49.50139452 -38.37845004
OS 49.50601732 -38.38492196
OS 49.51156468 -38.393243
OS 49.52081028 -38.41080964
OS 49.53005588 -38.43299908
OS 49.53375412 -38.4440938
OS 49.53560324 -38.45703764
OS 49.53745236 -38.46998148
OS 49.53837692 -38.48384988
OS 49.53837692 -38.485699
OS 49.53837692 -38.4903218
OS 49.53745236 -38.49771828
OS 49.5365278 -38.50788844
OS 49.53467868 -38.51898316
OS 49.53098044 -38.531927
OS 49.5272822 -38.5457954
OS 49.52173484 -38.5596638
OS 49.52081028 -38.56151292
OS 49.51896116 -38.56613572
OS 49.51526292 -38.5735322
OS 49.50971556 -38.58370236
OS 49.50231908 -38.59479708
OS 49.49307348 -38.60866548
OS 49.48197876 -38.62253388
OS 49.46903492 -38.6382514
OS 49.4671858 -38.64010052
OS 49.462563 -38.64564788
OS 49.4579402 -38.65027068
OS 49.4533174 -38.65489348
OS 49.44777004 -38.66044084
OS 49.44037356 -38.66783732
OS 49.43297708 -38.6752338
OS 49.42373148 -38.68355484
OS 49.41448588 -38.69280044
OS 49.40339116 -38.7029706
OS 49.39137188 -38.71314076
OS 49.37842804 -38.72516004
OS 49.36363508 -38.73717932
OS 49.34884212 -38.75012316
OS 49.34791756 -38.75104772
OS 49.34606844 -38.75289684
OS 49.3423702 -38.75567052
OS 49.3377474 -38.75936876
OS 49.33220004 -38.76491612
OS 49.32572812 -38.77046348
OS 49.31093516 -38.78248276
OS 49.29521764 -38.79635116
OS 49.28042468 -38.81021956
OS 49.26748084 -38.82223884
OS 49.26193348 -38.82686164
OS 49.25731068 -38.83148444
OS 49.25638612 -38.832409
OS 49.25361244 -38.83518268
OS 49.2499142 -38.83888092
OS 49.2452914 -38.84442828
OS 49.2406686 -38.8509002
OS 49.23512124 -38.85737212
OS 49.22402652 -38.87308964
OS 49.53930148 -38.87308964
OS 49.53930148 -38.94890356
OS 49.11492844 -38.94890356
OS 49.11492844 -38.947979
OS 49.11492844 -38.94428076
OS 49.11492844 -38.9387334
OS 49.115853 -38.93133692
OS 49.11677756 -38.92301588
OS 49.11862668 -38.91377028
OS 49.1204758 -38.90452468
OS 49.12417404 -38.89435452
OS 49.12417404 -38.89342996
OS 49.1250986 -38.8925054
OS 49.12694772 -38.88695804
OS 49.13064596 -38.878637
OS 49.13619332 -38.86754228
OS 49.1435898 -38.85459844
OS 49.1528354 -38.83980548
OS 49.16300556 -38.82501252
OS 49.1759494 -38.809295
OS 49.1759494 -38.80837044
OS 49.17779852 -38.80744588
OS 49.18242132 -38.80189852
OS 49.19074236 -38.79357748
OS 49.20276164 -38.7815582
OS 49.21663004 -38.7676898
OS 49.23419668 -38.75104772
OS 49.25546156 -38.73255652
OS 49.27857556 -38.71314076
OS 49.27950012 -38.7122162
OS 49.28319836 -38.70944252
OS 49.28874572 -38.70481972
OS 49.29521764 -38.69927236
OS 49.30353868 -38.69187588
OS 49.31370884 -38.68355484
OS 49.323879 -38.67430924
OS 49.33589828 -38.66413908
OS 49.35901228 -38.64194964
OS 49.38212628 -38.6197602
OS 49.393221 -38.60866548
OS 49.40339116 -38.59757076
OS 49.41263676 -38.5874006
OS 49.42003324 -38.57723044
OS 49.42003324 -38.57630588
OS 49.42188236 -38.57538132
OS 49.42373148 -38.57260764
OS 49.4255806 -38.5689094
OS 49.43205252 -38.55873924
OS 49.439449 -38.54671996
OS 49.44592092 -38.531927
OS 49.45239284 -38.51620948
OS 49.45609108 -38.49864284
OS 49.4579402 -38.48200076
OS 49.4579402 -38.4810762
OS 49.4579402 -38.48015164
OS 49.45701564 -38.47460428
OS 49.45609108 -38.46535868
OS 49.4533174 -38.45518852
OS 49.44961916 -38.44224468
OS 49.44314724 -38.42930084
OS 49.4348262 -38.416357
OS 49.42373148 -38.40341316
OS 49.42188236 -38.40156404
OS 49.41725956 -38.3978658
OS 49.41078764 -38.393243
OS 49.40061748 -38.38677108
OS 49.38767364 -38.38122372
OS 49.37288068 -38.37567636
OS 49.35531404 -38.37197812
OS 49.33589828 -38.37105356
OS 49.33035092 -38.37105356
OS 49.32665268 -38.37197812
OS 49.31555796 -38.37290268
OS 49.30261412 -38.37567636
OS 49.28874572 -38.3793746
OS 49.2730282 -38.38584652
OS 49.25823524 -38.39416756
OS 49.24436684 -38.40526228
OS 49.24251772 -38.4071114
OS 49.23881948 -38.4117342
OS 49.23327212 -38.41913068
OS 49.22772476 -38.4302254
OS 49.22125284 -38.44316924
OS 49.21570548 -38.45981132
OS 49.21200724 -38.47830252
OS 49.21015812 -38.4995674
OS 49.1297214 -38.49124636
OS 49.1297214 -38.4903218
OS 49.13064596 -38.48754812
OS 49.13064596 -38.48292532
OS 49.13157052 -38.4764534
OS 49.13341964 -38.46905692
OS 49.13526876 -38.46073588
OS 49.13804244 -38.45056572
OS 49.14081612 -38.44039556
OS 49.1482126 -38.41820612
OS 49.15930732 -38.39601668
OS 49.16577924 -38.38492196
OS 49.17410028 -38.37382724
OS 49.18242132 -38.36365708
OS 49.19166692 -38.35441148
OS 49.19259148 -38.35348692
OS 49.1944406 -38.35256236
OS 49.19721428 -38.34978868
OS 49.20183708 -38.347015
OS 49.20738444 -38.34331676
OS 49.21385636 -38.33961852
OS 49.22125284 -38.33499572
OS 49.23049844 -38.33037292
OS 49.2406686 -38.32575012
OS 49.25176332 -38.32112732
OS 49.2637826 -38.31742908
OS 49.27672644 -38.31373084
OS 49.29059484 -38.31095716
OS 49.3053878 -38.30818348
OS 49.32110532 -38.30725892
OS 49.3377474 -38.30633436
OS 49.346993 -38.30633436
OS 49.35346492 -38.30725892
OE
OB 48.67576244 -38.94890356 I
OS 48.59717484 -38.94890356
OS 48.59717484 -38.4487166
OS 48.59625028 -38.44964116
OS 48.59162748 -38.4533394
OS 48.58608012 -38.45888676
OS 48.57683452 -38.46535868
OS 48.56666436 -38.47367972
OS 48.55372052 -38.48292532
OS 48.53892756 -38.49309548
OS 48.52228548 -38.50326564
OS 48.52136092 -38.50326564
OS 48.52043636 -38.5041902
OS 48.514889 -38.50788844
OS 48.5056434 -38.51251124
OS 48.49454868 -38.5180586
OS 48.48160484 -38.52453052
OS 48.46773644 -38.53100244
OS 48.45386804 -38.53747436
OS 48.43999964 -38.54302172
OS 48.43999964 -38.4672078
OS 48.4409242 -38.4672078
OS 48.44277332 -38.46535868
OS 48.44647156 -38.46443412
OS 48.45109436 -38.46166044
OS 48.45664172 -38.45888676
OS 48.46311364 -38.45518852
OS 48.47883116 -38.44594292
OS 48.49732236 -38.43577276
OS 48.51581356 -38.42282892
OS 48.53522932 -38.40803596
OS 48.55464508 -38.39231844
OS 48.55556964 -38.39139388
OS 48.5564942 -38.39046932
OS 48.55926788 -38.38769564
OS 48.56296612 -38.38492196
OS 48.57128716 -38.37567636
OS 48.58238188 -38.36458164
OS 48.5934766 -38.3516378
OS 48.60549588 -38.33684484
OS 48.61566604 -38.32205188
OS 48.62491164 -38.30633436
OS 48.67576244 -38.30633436
OS 48.67576244 -38.94890356
OE
OB 48.9032042 -38.95999828 I
OS 48.84033412 -38.95999828
OS 49.02617068 -38.29801332
OS 49.08904076 -38.29801332
OS 48.9032042 -38.95999828
OE
OB 50.59699812 -38.30725892 I
OS 50.6043946 -38.30818348
OS 50.6136402 -38.30910804
OS 50.62381036 -38.31095716
OS 50.63398052 -38.31280628
OS 50.65801908 -38.3192782
OS 50.68205764 -38.3285238
OS 50.69407692 -38.33407116
OS 50.7060962 -38.34054308
OS 50.71719092 -38.34886412
OS 50.72736108 -38.35810972
OS 50.72828564 -38.35903428
OS 50.73013476 -38.35995884
OS 50.73198388 -38.36365708
OS 50.73568212 -38.36735532
OS 50.74030492 -38.37197812
OS 50.74492772 -38.37845004
OS 50.74955052 -38.38492196
OS 50.75509788 -38.393243
OS 50.76434348 -38.41080964
OS 50.77358908 -38.43299908
OS 50.77728732 -38.4440938
OS 50.77913644 -38.45703764
OS 50.78098556 -38.46998148
OS 50.78191012 -38.48384988
OS 50.78191012 -38.485699
OS 50.78191012 -38.4903218
OS 50.78098556 -38.49771828
OS 50.780061 -38.50788844
OS 50.77821188 -38.51898316
OS 50.77451364 -38.531927
OS 50.7708154 -38.5457954
OS 50.76526804 -38.5596638
OS 50.76434348 -38.56151292
OS 50.76249436 -38.56613572
OS 50.75879612 -38.5735322
OS 50.75324876 -38.58370236
OS 50.74585228 -38.59479708
OS 50.73660668 -38.60866548
OS 50.72551196 -38.62253388
OS 50.71256812 -38.6382514
OS 50.710719 -38.64010052
OS 50.7060962 -38.64564788
OS 50.7014734 -38.65027068
OS 50.6968506 -38.65489348
OS 50.69130324 -38.66044084
OS 50.68390676 -38.66783732
OS 50.67651028 -38.6752338
OS 50.66726468 -38.68355484
OS 50.65801908 -38.69280044
OS 50.64692436 -38.7029706
OS 50.63490508 -38.71314076
OS 50.62196124 -38.72516004
OS 50.60716828 -38.73717932
OS 50.59237532 -38.75012316
OS 50.59145076 -38.75104772
OS 50.58960164 -38.75289684
OS 50.5859034 -38.75567052
OS 50.5812806 -38.75936876
OS 50.57573324 -38.76491612
OS 50.56926132 -38.77046348
OS 50.55446836 -38.78248276
OS 50.53875084 -38.79635116
OS 50.52395788 -38.81021956
OS 50.51101404 -38.82223884
OS 50.50546668 -38.82686164
OS 50.50084388 -38.83148444
OS 50.49991932 -38.832409
OS 50.49714564 -38.83518268
OS 50.4934474 -38.83888092
OS 50.4888246 -38.84442828
OS 50.4842018 -38.8509002
OS 50.47865444 -38.85737212
OS 50.46755972 -38.87308964
OS 50.78283468 -38.87308964
OS 50.78283468 -38.94890356
OS 50.35846164 -38.94890356
OS 50.35846164 -38.947979
OS 50.35846164 -38.94428076
OS 50.35846164 -38.9387334
OS 50.3593862 -38.93133692
OS 50.36031076 -38.92301588
OS 50.36215988 -38.91377028
OS 50.364009 -38.90452468
OS 50.36770724 -38.89435452
OS 50.36770724 -38.89342996
OS 50.3686318 -38.8925054
OS 50.37048092 -38.88695804
OS 50.37417916 -38.878637
OS 50.37972652 -38.86754228
OS 50.387123 -38.85459844
OS 50.3963686 -38.83980548
OS 50.40653876 -38.82501252
OS 50.4194826 -38.809295
OS 50.4194826 -38.80837044
OS 50.42133172 -38.80744588
OS 50.42595452 -38.80189852
OS 50.43427556 -38.79357748
OS 50.44629484 -38.7815582
OS 50.46016324 -38.7676898
OS 50.47772988 -38.75104772
OS 50.49899476 -38.73255652
OS 50.52210876 -38.71314076
OS 50.52303332 -38.7122162
OS 50.52673156 -38.70944252
OS 50.53227892 -38.70481972
OS 50.53875084 -38.69927236
OS 50.54707188 -38.69187588
OS 50.55724204 -38.68355484
OS 50.5674122 -38.67430924
OS 50.57943148 -38.66413908
OS 50.60254548 -38.64194964
OS 50.62565948 -38.6197602
OS 50.6367542 -38.60866548
OS 50.64692436 -38.59757076
OS 50.65616996 -38.5874006
OS 50.66356644 -38.57723044
OS 50.66356644 -38.57630588
OS 50.66541556 -38.57538132
OS 50.66726468 -38.57260764
OS 50.6691138 -38.5689094
OS 50.67558572 -38.55873924
OS 50.6829822 -38.54671996
OS 50.68945412 -38.531927
OS 50.69592604 -38.51620948
OS 50.69962428 -38.49864284
OS 50.7014734 -38.48200076
OS 50.7014734 -38.4810762
OS 50.7014734 -38.48015164
OS 50.70054884 -38.47460428
OS 50.69962428 -38.46535868
OS 50.6968506 -38.45518852
OS 50.69315236 -38.44224468
OS 50.68668044 -38.42930084
OS 50.6783594 -38.416357
OS 50.66726468 -38.40341316
OS 50.66541556 -38.40156404
OS 50.66079276 -38.3978658
OS 50.65432084 -38.393243
OS 50.64415068 -38.38677108
OS 50.63120684 -38.38122372
OS 50.61641388 -38.37567636
OS 50.59884724 -38.37197812
OS 50.57943148 -38.37105356
OS 50.57388412 -38.37105356
OS 50.57018588 -38.37197812
OS 50.55909116 -38.37290268
OS 50.54614732 -38.37567636
OS 50.53227892 -38.3793746
OS 50.5165614 -38.38584652
OS 50.50176844 -38.39416756
OS 50.48790004 -38.40526228
OS 50.48605092 -38.4071114
OS 50.48235268 -38.4117342
OS 50.47680532 -38.41913068
OS 50.47125796 -38.4302254
OS 50.46478604 -38.44316924
OS 50.45923868 -38.45981132
OS 50.45554044 -38.47830252
OS 50.45369132 -38.4995674
OS 50.3732546 -38.49124636
OS 50.3732546 -38.4903218
OS 50.37417916 -38.48754812
OS 50.37417916 -38.48292532
OS 50.37510372 -38.4764534
OS 50.37695284 -38.46905692
OS 50.37880196 -38.46073588
OS 50.38157564 -38.45056572
OS 50.38434932 -38.44039556
OS 50.3917458 -38.41820612
OS 50.40284052 -38.39601668
OS 50.40931244 -38.38492196
OS 50.41763348 -38.37382724
OS 50.42595452 -38.36365708
OS 50.43520012 -38.35441148
OS 50.43612468 -38.35348692
OS 50.4379738 -38.35256236
OS 50.44074748 -38.34978868
OS 50.44537028 -38.347015
OS 50.45091764 -38.34331676
OS 50.45738956 -38.33961852
OS 50.46478604 -38.33499572
OS 50.47403164 -38.33037292
OS 50.4842018 -38.32575012
OS 50.49529652 -38.32112732
OS 50.5073158 -38.31742908
OS 50.52025964 -38.31373084
OS 50.53412804 -38.31095716
OS 50.548921 -38.30818348
OS 50.56463852 -38.30725892
OS 50.5812806 -38.30633436
OS 50.5905262 -38.30633436
OS 50.59699812 -38.30725892
OE
OB 51.0944114 -38.30725892 I
OS 51.10643068 -38.30910804
OS 51.12029908 -38.31188172
OS 51.13509204 -38.31557996
OS 51.15080956 -38.32020276
OS 51.16560252 -38.32759924
OS 51.16652708 -38.32759924
OS 51.16745164 -38.3285238
OS 51.17207444 -38.33129748
OS 51.17947092 -38.33592028
OS 51.18871652 -38.3423922
OS 51.19888668 -38.3516378
OS 51.2099814 -38.36180796
OS 51.22015156 -38.37382724
OS 51.23032172 -38.38769564
OS 51.23124628 -38.38954476
OS 51.23494452 -38.39416756
OS 51.23864276 -38.4024886
OS 51.24511468 -38.41450788
OS 51.25066204 -38.42837628
OS 51.25805852 -38.4440938
OS 51.26453044 -38.462585
OS 51.2700778 -38.48292532
OS 51.2700778 -38.48384988
OS 51.27100236 -38.485699
OS 51.27192692 -38.48847268
OS 51.27285148 -38.49309548
OS 51.27377604 -38.49864284
OS 51.2747006 -38.50511476
OS 51.27654972 -38.5134358
OS 51.27747428 -38.5226814
OS 51.2793234 -38.53285156
OS 51.28024796 -38.54394628
OS 51.28117252 -38.55689012
OS 51.28302164 -38.56983396
OS 51.2839462 -38.58462692
OS 51.2839462 -38.59941988
OS 51.28487076 -38.61606196
OS 51.28487076 -38.6336286
OS 51.28487076 -38.63455316
OS 51.28487076 -38.6382514
OS 51.28487076 -38.64472332
OS 51.28487076 -38.6521198
OS 51.2839462 -38.66228996
OS 51.2839462 -38.67338468
OS 51.28302164 -38.68540396
OS 51.28209708 -38.6983478
OS 51.2793234 -38.72793372
OS 51.2747006 -38.7584442
OS 51.26915324 -38.78803012
OS 51.265455 -38.80189852
OS 51.2608322 -38.81576692
OS 51.2608322 -38.81669148
OS 51.25990764 -38.8185406
OS 51.25805852 -38.82223884
OS 51.2562094 -38.82686164
OS 51.25436028 -38.83333356
OS 51.25066204 -38.83980548
OS 51.24326556 -38.855523
OS 51.23401996 -38.87216508
OS 51.22200068 -38.89065628
OS 51.20813228 -38.90729836
OS 51.1914902 -38.92301588
OS 51.19056564 -38.92301588
OS 51.18964108 -38.924865
OS 51.1868674 -38.92671412
OS 51.18316916 -38.92856324
OS 51.17854636 -38.93133692
OS 51.17392356 -38.93503516
OS 51.16005516 -38.94150708
OS 51.14341308 -38.947979
OS 51.12399732 -38.95445092
OS 51.10088332 -38.95814916
OS 51.0759202 -38.95999828
OS 51.0666746 -38.95999828
OS 51.06020268 -38.95907372
OS 51.0528062 -38.95814916
OS 51.0435606 -38.95630004
OS 51.03339044 -38.95445092
OS 51.02229572 -38.95167724
OS 51.011201 -38.947979
OS 50.99918172 -38.94428076
OS 50.98716244 -38.9387334
OS 50.97514316 -38.93226148
OS 50.96312388 -38.924865
OS 50.9511046 -38.9156194
OS 50.94000988 -38.90544924
OS 50.92983972 -38.89435452
OS 50.92891516 -38.89342996
OS 50.92706604 -38.89065628
OS 50.92429236 -38.88603348
OS 50.91966956 -38.878637
OS 50.91504676 -38.87031596
OS 50.91042396 -38.85922124
OS 50.90395204 -38.8462774
OS 50.89840468 -38.83148444
OS 50.89285732 -38.81484236
OS 50.88730996 -38.7954266
OS 50.8817626 -38.77416172
OS 50.8771398 -38.75012316
OS 50.872517 -38.72423548
OS 50.86974332 -38.69649868
OS 50.8678942 -38.6659882
OS 50.86696964 -38.6336286
OS 50.86696964 -38.63270404
OS 50.86696964 -38.6290058
OS 50.86696964 -38.62253388
OS 50.86696964 -38.6151374
OS 50.8678942 -38.60496724
OS 50.8678942 -38.59387252
OS 50.86881876 -38.58185324
OS 50.86974332 -38.56798484
OS 50.872517 -38.53932348
OS 50.8771398 -38.508813
OS 50.88268716 -38.47830252
OS 50.8863854 -38.46443412
OS 50.89008364 -38.45056572
OS 50.89008364 -38.44964116
OS 50.8910082 -38.44779204
OS 50.89285732 -38.4440938
OS 50.89470644 -38.439471
OS 50.89655556 -38.43299908
OS 50.9002538 -38.42652716
OS 50.90765028 -38.41080964
OS 50.91689588 -38.39416756
OS 50.92891516 -38.37660092
OS 50.94278356 -38.35903428
OS 50.95942564 -38.34424132
OS 50.9603502 -38.34424132
OS 50.96127476 -38.3423922
OS 50.96404844 -38.34054308
OS 50.96774668 -38.33869396
OS 50.97236948 -38.33499572
OS 50.97791684 -38.33222204
OS 50.99178524 -38.32482556
OS 51.00842732 -38.31835364
OS 51.02784308 -38.31188172
OS 51.05095708 -38.30818348
OS 51.0759202 -38.30633436
OS 51.08424124 -38.30633436
OS 51.0944114 -38.30725892
OE
OB 51.59182468 -38.30725892 I
OS 51.59922116 -38.30818348
OS 51.60846676 -38.30910804
OS 51.61863692 -38.31095716
OS 51.62880708 -38.31280628
OS 51.65284564 -38.3192782
OS 51.6768842 -38.3285238
OS 51.68890348 -38.33407116
OS 51.70092276 -38.34054308
OS 51.71201748 -38.34886412
OS 51.72218764 -38.35810972
OS 51.7231122 -38.35903428
OS 51.72496132 -38.35995884
OS 51.72681044 -38.36365708
OS 51.73050868 -38.36735532
OS 51.73513148 -38.37197812
OS 51.73975428 -38.37845004
OS 51.74437708 -38.38492196
OS 51.74992444 -38.393243
OS 51.75917004 -38.41080964
OS 51.76841564 -38.43299908
OS 51.77211388 -38.4440938
OS 51.773963 -38.45703764
OS 51.77581212 -38.46998148
OS 51.77673668 -38.48384988
OS 51.77673668 -38.485699
OS 51.77673668 -38.4903218
OS 51.77581212 -38.49771828
OS 51.77488756 -38.50788844
OS 51.77303844 -38.51898316
OS 51.7693402 -38.531927
OS 51.76564196 -38.5457954
OS 51.7600946 -38.5596638
OS 51.75917004 -38.56151292
OS 51.75732092 -38.56613572
OS 51.75362268 -38.5735322
OS 51.74807532 -38.58370236
OS 51.74067884 -38.59479708
OS 51.73143324 -38.60866548
OS 51.72033852 -38.62253388
OS 51.70739468 -38.6382514
OS 51.70554556 -38.64010052
OS 51.70092276 -38.64564788
OS 51.69629996 -38.65027068
OS 51.69167716 -38.65489348
OS 51.6861298 -38.66044084
OS 51.67873332 -38.66783732
OS 51.67133684 -38.6752338
OS 51.66209124 -38.68355484
OS 51.65284564 -38.69280044
OS 51.64175092 -38.7029706
OS 51.62973164 -38.71314076
OS 51.6167878 -38.72516004
OS 51.60199484 -38.73717932
OS 51.58720188 -38.75012316
OS 51.58627732 -38.75104772
OS 51.5844282 -38.75289684
OS 51.58072996 -38.75567052
OS 51.57610716 -38.75936876
OS 51.5705598 -38.76491612
OS 51.56408788 -38.77046348
OS 51.54929492 -38.78248276
OS 51.5335774 -38.79635116
OS 51.51878444 -38.81021956
OS 51.5058406 -38.82223884
OS 51.50029324 -38.82686164
OS 51.49567044 -38.83148444
OS 51.49474588 -38.832409
OS 51.4919722 -38.83518268
OS 51.48827396 -38.83888092
OS 51.48365116 -38.84442828
OS 51.47902836 -38.8509002
OS 51.473481 -38.85737212
OS 51.46238628 -38.87308964
OS 51.77766124 -38.87308964
OS 51.77766124 -38.94890356
OS 51.3532882 -38.94890356
OS 51.3532882 -38.947979
OS 51.3532882 -38.94428076
OS 51.3532882 -38.9387334
OS 51.35421276 -38.93133692
OS 51.35513732 -38.92301588
OS 51.35698644 -38.91377028
OS 51.35883556 -38.90452468
OS 51.3625338 -38.89435452
OS 51.3625338 -38.89342996
OS 51.36345836 -38.8925054
OS 51.36530748 -38.88695804
OS 51.36900572 -38.878637
OS 51.37455308 -38.86754228
OS 51.38194956 -38.85459844
OS 51.39119516 -38.83980548
OS 51.40136532 -38.82501252
OS 51.41430916 -38.809295
OS 51.41430916 -38.80837044
OS 51.41615828 -38.80744588
OS 51.42078108 -38.80189852
OS 51.42910212 -38.79357748
OS 51.4411214 -38.7815582
OS 51.4549898 -38.7676898
OS 51.47255644 -38.75104772
OS 51.49382132 -38.73255652
OS 51.51693532 -38.71314076
OS 51.51785988 -38.7122162
OS 51.52155812 -38.70944252
OS 51.52710548 -38.70481972
OS 51.5335774 -38.69927236
OS 51.54189844 -38.69187588
OS 51.5520686 -38.68355484
OS 51.56223876 -38.67430924
OS 51.57425804 -38.66413908
OS 51.59737204 -38.64194964
OS 51.62048604 -38.6197602
OS 51.63158076 -38.60866548
OS 51.64175092 -38.59757076
OS 51.65099652 -38.5874006
OS 51.658393 -38.57723044
OS 51.658393 -38.57630588
OS 51.66024212 -38.57538132
OS 51.66209124 -38.57260764
OS 51.66394036 -38.5689094
OS 51.67041228 -38.55873924
OS 51.67780876 -38.54671996
OS 51.68428068 -38.531927
OS 51.6907526 -38.51620948
OS 51.69445084 -38.49864284
OS 51.69629996 -38.48200076
OS 51.69629996 -38.4810762
OS 51.69629996 -38.48015164
OS 51.6953754 -38.47460428
OS 51.69445084 -38.46535868
OS 51.69167716 -38.45518852
OS 51.68797892 -38.44224468
OS 51.681507 -38.42930084
OS 51.67318596 -38.416357
OS 51.66209124 -38.40341316
OS 51.66024212 -38.40156404
OS 51.65561932 -38.3978658
OS 51.6491474 -38.393243
OS 51.63897724 -38.38677108
OS 51.6260334 -38.38122372
OS 51.61124044 -38.37567636
OS 51.5936738 -38.37197812
OS 51.57425804 -38.37105356
OS 51.56871068 -38.37105356
OS 51.56501244 -38.37197812
OS 51.55391772 -38.37290268
OS 51.54097388 -38.37567636
OS 51.52710548 -38.3793746
OS 51.51138796 -38.38584652
OS 51.496595 -38.39416756
OS 51.4827266 -38.40526228
OS 51.48087748 -38.4071114
OS 51.47717924 -38.4117342
OS 51.47163188 -38.41913068
OS 51.46608452 -38.4302254
OS 51.4596126 -38.44316924
OS 51.45406524 -38.45981132
OS 51.450367 -38.47830252
OS 51.44851788 -38.4995674
OS 51.36808116 -38.49124636
OS 51.36808116 -38.4903218
OS 51.36900572 -38.48754812
OS 51.36900572 -38.48292532
OS 51.36993028 -38.4764534
OS 51.3717794 -38.46905692
OS 51.37362852 -38.46073588
OS 51.3764022 -38.45056572
OS 51.37917588 -38.44039556
OS 51.38657236 -38.41820612
OS 51.39766708 -38.39601668
OS 51.404139 -38.38492196
OS 51.41246004 -38.37382724
OS 51.42078108 -38.36365708
OS 51.43002668 -38.35441148
OS 51.43095124 -38.35348692
OS 51.43280036 -38.35256236
OS 51.43557404 -38.34978868
OS 51.44019684 -38.347015
OS 51.4457442 -38.34331676
OS 51.45221612 -38.33961852
OS 51.4596126 -38.33499572
OS 51.4688582 -38.33037292
OS 51.47902836 -38.32575012
OS 51.49012308 -38.32112732
OS 51.50214236 -38.31742908
OS 51.5150862 -38.31373084
OS 51.5289546 -38.31095716
OS 51.54374756 -38.30818348
OS 51.55946508 -38.30725892
OS 51.57610716 -38.30633436
OS 51.58535276 -38.30633436
OS 51.59182468 -38.30725892
OE
OB 52.08184148 -38.30725892 I
OS 52.09386076 -38.30910804
OS 52.10865372 -38.31188172
OS 52.1252958 -38.31650452
OS 52.14193788 -38.32205188
OS 52.15857996 -38.32944836
OS 52.15950452 -38.32944836
OS 52.16042908 -38.33037292
OS 52.16597644 -38.3331466
OS 52.17429748 -38.33869396
OS 52.18354308 -38.34516588
OS 52.1946378 -38.35441148
OS 52.20573252 -38.36458164
OS 52.21682724 -38.37660092
OS 52.22607284 -38.39046932
OS 52.2269974 -38.39231844
OS 52.22977108 -38.39694124
OS 52.23346932 -38.40526228
OS 52.23809212 -38.41543244
OS 52.24271492 -38.42745172
OS 52.24641316 -38.44132012
OS 52.24918684 -38.45703764
OS 52.2501114 -38.47275516
OS 52.2501114 -38.47460428
OS 52.2501114 -38.48015164
OS 52.24918684 -38.48754812
OS 52.24733772 -38.49771828
OS 52.24456404 -38.50973756
OS 52.23994124 -38.5226814
OS 52.23439388 -38.53562524
OS 52.2269974 -38.54856908
OS 52.22607284 -38.5504182
OS 52.22329916 -38.55411644
OS 52.2177518 -38.56058836
OS 52.21035532 -38.56798484
OS 52.20110972 -38.57630588
OS 52.190015 -38.58555148
OS 52.17707116 -38.59387252
OS 52.16135364 -38.60219356
OS 52.1622782 -38.60219356
OS 52.16412732 -38.60311812
OS 52.166901 -38.60404268
OS 52.17059924 -38.60496724
OS 52.1807694 -38.60866548
OS 52.19371324 -38.61421284
OS 52.2085062 -38.62160932
OS 52.22329916 -38.63085492
OS 52.23716756 -38.6428742
OS 52.2501114 -38.6567426
OS 52.25103596 -38.65859172
OS 52.2547342 -38.66413908
OS 52.26028156 -38.67338468
OS 52.26582892 -38.68540396
OS 52.27137628 -38.70019692
OS 52.27692364 -38.71776356
OS 52.28062188 -38.73810388
OS 52.28154644 -38.76029332
OS 52.28154644 -38.76121788
OS 52.28154644 -38.76399156
OS 52.28154644 -38.76861436
OS 52.28062188 -38.77416172
OS 52.27969732 -38.7815582
OS 52.2778482 -38.78987924
OS 52.27599908 -38.79912484
OS 52.27414996 -38.809295
OS 52.26675348 -38.83148444
OS 52.26120612 -38.84350372
OS 52.25565876 -38.85459844
OS 52.24826228 -38.86661772
OS 52.23994124 -38.878637
OS 52.23069564 -38.89065628
OS 52.21960092 -38.901751
OS 52.21867636 -38.90267556
OS 52.21682724 -38.90452468
OS 52.213129 -38.90729836
OS 52.2085062 -38.9109966
OS 52.20295884 -38.9156194
OS 52.19556236 -38.9202422
OS 52.18724132 -38.92578956
OS 52.17707116 -38.93041236
OS 52.166901 -38.93595972
OS 52.15488172 -38.94150708
OS 52.14286244 -38.94612988
OS 52.12899404 -38.95075268
OS 52.11420108 -38.95445092
OS 52.09848356 -38.9572246
OS 52.08276604 -38.95907372
OS 52.0651994 -38.95999828
OS 52.05687836 -38.95999828
OS 52.051331 -38.95907372
OS 52.04393452 -38.95814916
OS 52.03561348 -38.9572246
OS 52.02636788 -38.95537548
OS 52.01619772 -38.95352636
OS 51.99400828 -38.947979
OS 51.97089428 -38.9387334
OS 51.958875 -38.93318604
OS 51.94778028 -38.92671412
OS 51.93668556 -38.91839308
OS 51.92559084 -38.91007204
OS 51.92466628 -38.90914748
OS 51.92281716 -38.90729836
OS 51.92004348 -38.90452468
OS 51.9172698 -38.90082644
OS 51.912647 -38.89620364
OS 51.9080242 -38.88973172
OS 51.90247684 -38.8832598
OS 51.89692948 -38.87493876
OS 51.89138212 -38.86569316
OS 51.88583476 -38.85644756
OS 51.8756646 -38.83425812
OS 51.86734356 -38.80837044
OS 51.86456988 -38.79450204
OS 51.86272076 -38.77970908
OS 51.94130836 -38.76953892
OS 51.94130836 -38.77046348
OS 51.94223292 -38.7723126
OS 51.94315748 -38.77601084
OS 51.94408204 -38.78063364
OS 51.9450066 -38.786181
OS 51.94685572 -38.79265292
OS 51.95147852 -38.80652132
OS 51.95795044 -38.8231634
OS 51.96627148 -38.83888092
OS 51.97551708 -38.85367388
OS 51.9866118 -38.86661772
OS 51.98846092 -38.86754228
OS 51.99215916 -38.87124052
OS 51.99955564 -38.87586332
OS 52.00880124 -38.88048612
OS 52.01989596 -38.88603348
OS 52.03376436 -38.89065628
OS 52.04948188 -38.89435452
OS 52.06612396 -38.89527908
OS 52.07167132 -38.89527908
OS 52.07536956 -38.89435452
OS 52.08553972 -38.89342996
OS 52.09848356 -38.89065628
OS 52.11327652 -38.88603348
OS 52.12899404 -38.87956156
OS 52.14471156 -38.87031596
OS 52.15950452 -38.85737212
OS 52.16135364 -38.855523
OS 52.16597644 -38.84997564
OS 52.1715238 -38.8416546
OS 52.17892028 -38.83055988
OS 52.18631676 -38.81669148
OS 52.19186412 -38.80097396
OS 52.19648692 -38.78248276
OS 52.19833604 -38.76214244
OS 52.19833604 -38.76121788
OS 52.19833604 -38.75936876
OS 52.19833604 -38.75659508
OS 52.19741148 -38.75289684
OS 52.19648692 -38.74272668
OS 52.19371324 -38.7307074
OS 52.190015 -38.71591444
OS 52.18354308 -38.70112148
OS 52.17429748 -38.68632852
OS 52.1622782 -38.67246012
OS 52.16042908 -38.670611
OS 52.15580628 -38.66691276
OS 52.1484098 -38.6613654
OS 52.13823964 -38.65489348
OS 52.1252958 -38.64842156
OS 52.10957828 -38.6428742
OS 52.09201164 -38.63917596
OS 52.07259588 -38.63732684
OS 52.06427484 -38.63732684
OS 52.05780292 -38.6382514
OS 52.04948188 -38.63917596
OS 52.04023628 -38.64102508
OS 52.02914156 -38.6428742
OS 52.01712228 -38.64564788
OS 52.02636788 -38.57630588
OS 52.03099068 -38.57630588
OS 52.03468892 -38.57723044
OS 52.0467082 -38.57723044
OS 52.05687836 -38.57538132
OS 52.06889764 -38.5735322
OS 52.08276604 -38.57075852
OS 52.09848356 -38.56613572
OS 52.11327652 -38.5596638
OS 52.12899404 -38.55134276
OS 52.1299186 -38.55134276
OS 52.13084316 -38.5504182
OS 52.13546596 -38.54671996
OS 52.14193788 -38.54024804
OS 52.14933436 -38.531927
OS 52.15673084 -38.51990772
OS 52.16320276 -38.50603932
OS 52.16782556 -38.4903218
OS 52.16967468 -38.4810762
OS 52.16967468 -38.47090604
OS 52.16967468 -38.46998148
OS 52.16967468 -38.46905692
OS 52.16967468 -38.46350956
OS 52.16782556 -38.45611308
OS 52.16597644 -38.44594292
OS 52.1622782 -38.4348482
OS 52.1576554 -38.42282892
OS 52.15025892 -38.41080964
OS 52.14008876 -38.39971492
OS 52.1391642 -38.39879036
OS 52.1345414 -38.39509212
OS 52.12806948 -38.39046932
OS 52.11974844 -38.38492196
OS 52.10865372 -38.38029916
OS 52.09570988 -38.37567636
OS 52.08091692 -38.37197812
OS 52.06427484 -38.37105356
OS 52.05687836 -38.37105356
OS 52.04855732 -38.37290268
OS 52.0374626 -38.3747518
OS 52.02544332 -38.37845004
OS 52.01342404 -38.38307284
OS 52.0004802 -38.39046932
OS 51.98846092 -38.39971492
OS 51.98753636 -38.40063948
OS 51.98383812 -38.40526228
OS 51.97829076 -38.4117342
OS 51.97181884 -38.4209798
OS 51.96534692 -38.43299908
OS 51.958875 -38.44779204
OS 51.95332764 -38.46535868
OS 51.9496294 -38.485699
OS 51.8710418 -38.4718306
OS 51.8710418 -38.47090604
OS 51.87196636 -38.46813236
OS 51.87289092 -38.46443412
OS 51.87381548 -38.45888676
OS 51.8756646 -38.45241484
OS 51.87843828 -38.44501836
OS 51.88398564 -38.42745172
OS 51.89323124 -38.4071114
OS 51.90432596 -38.38677108
OS 51.91819436 -38.36735532
OS 51.935761 -38.34978868
OS 51.93668556 -38.34886412
OS 51.93853468 -38.34793956
OS 51.94130836 -38.34609044
OS 51.9450066 -38.34331676
OS 51.9496294 -38.33961852
OS 51.95610132 -38.33592028
OS 51.96257324 -38.33222204
OS 51.97089428 -38.32759924
OS 51.98938548 -38.32020276
OS 52.01065036 -38.31280628
OS 52.03561348 -38.30818348
OS 52.04855732 -38.30633436
OS 52.07167132 -38.30633436
OS 52.08184148 -38.30725892
OE
OB 51.07499564 -38.37105356 H
OS 51.06944828 -38.37105356
OS 51.06575004 -38.37197812
OS 51.05557988 -38.37382724
OS 51.0435606 -38.37660092
OS 51.0296922 -38.38214828
OS 51.01489924 -38.39046932
OS 51.00750276 -38.39601668
OS 51.00010628 -38.40156404
OS 50.99363436 -38.40896052
OS 50.98716244 -38.41728156
OS 50.98716244 -38.41820612
OS 50.98531332 -38.42005524
OS 50.9834642 -38.42375348
OS 50.98069052 -38.42837628
OS 50.97791684 -38.43577276
OS 50.9742186 -38.4440938
OS 50.97144492 -38.45426396
OS 50.96774668 -38.46628324
OS 50.96404844 -38.48015164
OS 50.9603502 -38.49586916
OS 50.95665196 -38.5134358
OS 50.95387828 -38.53285156
OS 50.9511046 -38.555041
OS 50.94925548 -38.57907956
OS 50.94833092 -38.60496724
OS 50.94740636 -38.6336286
OS 50.94740636 -38.63547772
OS 50.94740636 -38.64010052
OS 50.94740636 -38.64842156
OS 50.94833092 -38.65951628
OS 50.94833092 -38.67153556
OS 50.94925548 -38.68632852
OS 50.95018004 -38.70204604
OS 50.95202916 -38.71868812
OS 50.95665196 -38.75474596
OS 50.95942564 -38.7723126
OS 50.96312388 -38.78895468
OS 50.96682212 -38.8046722
OS 50.97236948 -38.81946516
OS 50.97791684 -38.832409
OS 50.98438876 -38.84350372
OS 50.98438876 -38.84442828
OS 50.98623788 -38.84535284
OS 50.99086068 -38.85182476
OS 50.99918172 -38.8601458
OS 51.00935188 -38.8693914
OS 51.02322028 -38.878637
OS 51.0389378 -38.88695804
OS 51.05650444 -38.89342996
OS 51.06575004 -38.89435452
OS 51.0759202 -38.89527908
OS 51.08146756 -38.89527908
OS 51.0851658 -38.89435452
OS 51.0944114 -38.8925054
OS 51.10735524 -38.88880716
OS 51.12122364 -38.88233524
OS 51.13694116 -38.87308964
OS 51.14433764 -38.86754228
OS 51.15173412 -38.8601458
OS 51.1591306 -38.85274932
OS 51.16652708 -38.84350372
OS 51.16652708 -38.84257916
OS 51.1683762 -38.84073004
OS 51.17022532 -38.83795636
OS 51.17207444 -38.83333356
OS 51.17577268 -38.82686164
OS 51.17854636 -38.8185406
OS 51.1822446 -38.809295
OS 51.18594284 -38.79820028
OS 51.18871652 -38.78433188
OS 51.19241476 -38.76953892
OS 51.196113 -38.75197228
OS 51.19888668 -38.73348108
OS 51.2007358 -38.71129164
OS 51.20258492 -38.68817764
OS 51.20443404 -38.66228996
OS 51.20443404 -38.6336286
OS 51.20443404 -38.63270404
OS 51.20443404 -38.63177948
OS 51.20443404 -38.62715668
OS 51.20443404 -38.61883564
OS 51.20350948 -38.60774092
OS 51.20350948 -38.59572164
OS 51.20258492 -38.58092868
OS 51.20166036 -38.56521116
OS 51.19981124 -38.54764452
OS 51.19518844 -38.51251124
OS 51.19241476 -38.4949446
OS 51.18871652 -38.47830252
OS 51.18501828 -38.462585
OS 51.17947092 -38.44779204
OS 51.17392356 -38.4348482
OS 51.16745164 -38.42375348
OS 51.16745164 -38.42282892
OS 51.16560252 -38.42190436
OS 51.1637534 -38.41913068
OS 51.16097972 -38.41543244
OS 51.15265868 -38.4071114
OS 51.14248852 -38.39694124
OS 51.12862012 -38.38769564
OS 51.1129026 -38.3793746
OS 51.10458156 -38.37567636
OS 51.09533596 -38.37290268
OS 51.0851658 -38.37197812
OS 51.07499564 -38.37105356
OE
OB 54.05947532 -38.37105356 H
OS 54.05392796 -38.37105356
OS 54.05022972 -38.37197812
OS 54.04005956 -38.37382724
OS 54.02804028 -38.37660092
OS 54.01417188 -38.38214828
OS 53.99937892 -38.39046932
OS 53.99198244 -38.39601668
OS 53.98458596 -38.40156404
OS 53.97811404 -38.40896052
OS 53.97164212 -38.41728156
OS 53.97164212 -38.41820612
OS 53.969793 -38.42005524
OS 53.96794388 -38.42375348
OS 53.9651702 -38.42837628
OS 53.96239652 -38.43577276
OS 53.95869828 -38.4440938
OS 53.9559246 -38.45426396
OS 53.95222636 -38.46628324
OS 53.94852812 -38.48015164
OS 53.94482988 -38.49586916
OS 53.94113164 -38.5134358
OS 53.93835796 -38.53285156
OS 53.93558428 -38.555041
OS 53.93373516 -38.57907956
OS 53.9328106 -38.60496724
OS 53.93188604 -38.6336286
OS 53.93188604 -38.63547772
OS 53.93188604 -38.64010052
OS 53.93188604 -38.64842156
OS 53.9328106 -38.65951628
OS 53.9328106 -38.67153556
OS 53.93373516 -38.68632852
OS 53.93465972 -38.70204604
OS 53.93650884 -38.71868812
OS 53.94113164 -38.75474596
OS 53.94390532 -38.7723126
OS 53.94760356 -38.78895468
OS 53.9513018 -38.8046722
OS 53.95684916 -38.81946516
OS 53.96239652 -38.832409
OS 53.96886844 -38.84350372
OS 53.96886844 -38.84442828
OS 53.97071756 -38.84535284
OS 53.97534036 -38.85182476
OS 53.9836614 -38.8601458
OS 53.99383156 -38.8693914
OS 54.00769996 -38.878637
OS 54.02341748 -38.88695804
OS 54.04098412 -38.89342996
OS 54.05022972 -38.89435452
OS 54.06039988 -38.89527908
OS 54.06594724 -38.89527908
OS 54.06964548 -38.89435452
OS 54.07889108 -38.8925054
OS 54.09183492 -38.88880716
OS 54.10570332 -38.88233524
OS 54.12142084 -38.87308964
OS 54.12881732 -38.86754228
OS 54.1362138 -38.8601458
OS 54.14361028 -38.85274932
OS 54.15100676 -38.84350372
OS 54.15100676 -38.84257916
OS 54.15285588 -38.84073004
OS 54.154705 -38.83795636
OS 54.15655412 -38.83333356
OS 54.16025236 -38.82686164
OS 54.16302604 -38.8185406
OS 54.16672428 -38.809295
OS 54.17042252 -38.79820028
OS 54.1731962 -38.78433188
OS 54.17689444 -38.76953892
OS 54.18059268 -38.75197228
OS 54.18336636 -38.73348108
OS 54.18521548 -38.71129164
OS 54.1870646 -38.68817764
OS 54.18891372 -38.66228996
OS 54.18891372 -38.6336286
OS 54.18891372 -38.63270404
OS 54.18891372 -38.63177948
OS 54.18891372 -38.62715668
OS 54.18891372 -38.61883564
OS 54.18798916 -38.60774092
OS 54.18798916 -38.59572164
OS 54.1870646 -38.58092868
OS 54.18614004 -38.56521116
OS 54.18429092 -38.54764452
OS 54.17966812 -38.51251124
OS 54.17689444 -38.4949446
OS 54.1731962 -38.47830252
OS 54.16949796 -38.462585
OS 54.1639506 -38.44779204
OS 54.15840324 -38.4348482
OS 54.15193132 -38.42375348
OS 54.15193132 -38.42282892
OS 54.1500822 -38.42190436
OS 54.14823308 -38.41913068
OS 54.1454594 -38.41543244
OS 54.13713836 -38.4071114
OS 54.1269682 -38.39694124
OS 54.1130998 -38.38769564
OS 54.09738228 -38.3793746
OS 54.08906124 -38.37567636
OS 54.07981564 -38.37290268
OS 54.06964548 -38.37197812
OS 54.05947532 -38.37105356
OE
OB 49.87491676 -38.43669732 H
OS 49.67336268 -38.72331092
OS 49.87491676 -38.72331092
OS 49.87491676 -38.43669732
OE
OB 56.14158444 -38.38492196 H
OS 55.95852156 -38.38492196
OS 55.95852156 -38.61328828
OS 56.13048972 -38.61328828
OS 56.13696164 -38.61236372
OS 56.14343356 -38.61236372
OS 56.15083004 -38.61143916
OS 56.16839668 -38.60959004
OS 56.18781244 -38.6058918
OS 56.2072282 -38.60034444
OS 56.22479484 -38.59294796
OS 56.23311588 -38.58832516
OS 56.2395878 -38.5827778
OS 56.24143692 -38.58092868
OS 56.24513516 -38.57723044
OS 56.25068252 -38.56983396
OS 56.25715444 -38.56058836
OS 56.26362636 -38.54856908
OS 56.26917372 -38.53377612
OS 56.27287196 -38.51713404
OS 56.27472108 -38.49771828
OS 56.27472108 -38.49679372
OS 56.27472108 -38.49586916
OS 56.27472108 -38.49124636
OS 56.27379652 -38.48292532
OS 56.2719474 -38.47367972
OS 56.27009828 -38.46350956
OS 56.26640004 -38.45149028
OS 56.26085268 -38.44039556
OS 56.25438076 -38.42930084
OS 56.2534562 -38.42837628
OS 56.25068252 -38.42467804
OS 56.24605972 -38.42005524
OS 56.24051236 -38.41358332
OS 56.23219132 -38.4071114
OS 56.22294572 -38.40156404
OS 56.21277556 -38.39601668
OS 56.20075628 -38.39139388
OS 56.19983172 -38.39139388
OS 56.19613348 -38.39046932
OS 56.19058612 -38.38954476
OS 56.18318964 -38.38769564
OS 56.17209492 -38.38677108
OS 56.15822652 -38.38584652
OS 56.14158444 -38.38492196
OE
SE

### steps/pcb/layers/top_paste/features
UNITS=MM
#Layer_Color=8421504
#
#Feature symbol names
#
$0 r99.9998

#
#Feature attribute names
#
@0 .nomenclature
@1 .string
@2 .string_angle
@3 .geometry
@4 .pad_usage

#
#Feature attribute text strings
#

#
#Layer features
#
L -9.5600012 -24.45999934 40.4400004 -24.45999934 0 P 0
L -9.5600012 -35.9599992 -9.5600012 -24.45999934 0 P 0
L -9.5600012 -35.9599992 28.439999 -35.9599992 0 P 0
L -9.5600012 -39.45999982 -9.5600012 -35.9599992 0 P 0
L -9.5600012 -39.45999982 28.439999 -39.45999982 0 P 0
L -9.5600012 -42.96000044 -9.5600012 -39.45999982 0 P 0
L -9.5600012 -42.96000044 28.439999 -42.96000044 0 P 0
L -10.0600002 -23.96000034 62.93999858 -23.96000034 0 P 0
L -10.0600002 -43.45999944 -10.0600002 -23.96000034 0 P 0
L -10.0600002 -43.45999944 62.93999858 -43.45999944 0 P 0
L 28.439999 -35.96000174 45.44000056 -35.9599992 0 P 0
L 28.439999 -39.45999982 28.439999 -35.9599992 0 P 0
L 28.439999 -39.46000236 45.44000056 -39.45999982 0 P 0
L 28.439999 -42.96000044 28.439999 -39.45999982 0 P 0
L 28.439999 -42.96000298 45.44000056 -42.96000044 0 P 0
L 40.4400004 -24.45999934 62.43999958 -24.45999934 0 P 0
L 40.4400004 -35.9599992 40.4400004 -24.45999934 0 P 0
L 45.44000056 -35.9599992 62.43999958 -35.9599992 0 P 0
L 45.44000056 -39.45999982 62.43999958 -39.45999982 0 P 0
L 45.44000056 -42.96000044 45.44000056 -35.9599992 0 P 0
L 45.44000056 -42.96000044 62.43999958 -42.96000044 0 P 0
L 62.43999958 -35.9599992 62.43999958 -24.45999934 0 P 0
L 62.43999958 -42.96000044 62.43999958 -35.9599992 0 P 0
L 62.93999858 -43.45999944 62.93999858 -23.96000034 0 P 0
S P 0
OB -2.96272458 -38.48662356 I
OS -2.94885618 -38.48754812
OS -2.93406322 -38.48939724
OS -2.9183457 -38.49309548
OS -2.90170362 -38.49679372
OS -2.8859861 -38.50234108
OS -2.88506154 -38.50234108
OS -2.88413698 -38.50326564
OS -2.87951418 -38.50511476
OS -2.8721177 -38.508813
OS -2.8628721 -38.5134358
OS -2.85270194 -38.51990772
OS -2.84253178 -38.5273042
OS -2.83328618 -38.53562524
OS -2.82496514 -38.54487084
OS -2.82404058 -38.5457954
OS -2.82219146 -38.54949364
OS -2.81849322 -38.55596556
OS -2.81387042 -38.56336204
OS -2.80924762 -38.57445676
OS -2.80462482 -38.58647604
OS -2.80092658 -38.60034444
OS -2.79722834 -38.61606196
OS -2.87396682 -38.62623212
OS -2.87396682 -38.624383
OS -2.87489138 -38.62068476
OS -2.8767405 -38.61421284
OS -2.87951418 -38.6058918
OS -2.88413698 -38.59757076
OS -2.88968434 -38.58832516
OS -2.89615626 -38.57907956
OS -2.90540186 -38.57075852
OS -2.90632642 -38.56983396
OS -2.91002466 -38.56798484
OS -2.91557202 -38.5642866
OS -2.92389306 -38.56058836
OS -2.93313866 -38.55689012
OS -2.94515794 -38.55319188
OS -2.9599509 -38.55134276
OS -2.97566842 -38.5504182
OS -2.98491402 -38.5504182
OS -2.99415962 -38.55134276
OS -3.0061789 -38.55226732
OS -3.01819818 -38.555041
OS -3.03114202 -38.55781468
OS -3.0431613 -38.56243748
OS -3.05333146 -38.5689094
OS -3.05425602 -38.56983396
OS -3.0570297 -38.57168308
OS -3.06072794 -38.57538132
OS -3.06442618 -38.58092868
OS -3.06904898 -38.58647604
OS -3.07274722 -38.59387252
OS -3.0755209 -38.60219356
OS -3.07644546 -38.6105146
OS -3.07644546 -38.61143916
OS -3.07644546 -38.61328828
OS -3.0755209 -38.61606196
OS -3.0755209 -38.6197602
OS -3.07274722 -38.6290058
OS -3.06719986 -38.6382514
OS -3.0662753 -38.63917596
OS -3.06535074 -38.64010052
OS -3.06350162 -38.6428742
OS -3.05980338 -38.64564788
OS -3.05610514 -38.64842156
OS -3.05055778 -38.6521198
OS -3.04408586 -38.65489348
OS -3.03668938 -38.65859172
OS -3.03576482 -38.65859172
OS -3.0339157 -38.65951628
OS -3.03021746 -38.66044084
OS -3.02374554 -38.66321452
OS -3.01449994 -38.6659882
OS -3.00248066 -38.66876188
OS -2.99508418 -38.67153556
OS -2.98676314 -38.67338468
OS -2.97751754 -38.67615836
OS -2.96734738 -38.67893204
OS -2.96642282 -38.67893204
OS -2.96364914 -38.6798566
OS -2.95902634 -38.68078116
OS -2.95347898 -38.68263028
OS -2.94700706 -38.6844794
OS -2.93868602 -38.68632852
OS -2.92111938 -38.69187588
OS -2.90170362 -38.69742324
OS -2.88228786 -38.70389516
OS -2.86472122 -38.71036708
OS -2.85732474 -38.71314076
OS -2.85085282 -38.71591444
OS -2.8490037 -38.716839
OS -2.84530546 -38.71868812
OS -2.8397581 -38.7214618
OS -2.83143706 -38.7260846
OS -2.82311602 -38.73163196
OS -2.81479498 -38.73902844
OS -2.80647394 -38.74734948
OS -2.79907746 -38.75659508
OS -2.7981529 -38.75751964
OS -2.79630378 -38.76121788
OS -2.79260554 -38.76676524
OS -2.7889073 -38.77508628
OS -2.78613362 -38.78525644
OS -2.78243538 -38.79635116
OS -2.78058626 -38.809295
OS -2.7796617 -38.82408796
OS -2.7796617 -38.82593708
OS -2.7796617 -38.83055988
OS -2.78058626 -38.83795636
OS -2.78243538 -38.84812652
OS -2.78520906 -38.85922124
OS -2.78983186 -38.87124052
OS -2.79537922 -38.88510892
OS -2.8027757 -38.89805276
OS -2.80370026 -38.89990188
OS -2.8073985 -38.90360012
OS -2.8120213 -38.91007204
OS -2.81941778 -38.91746852
OS -2.82958794 -38.92578956
OS -2.84068266 -38.93503516
OS -2.8536265 -38.9433562
OS -2.86934402 -38.95167724
OS -2.87026858 -38.95167724
OS -2.87119314 -38.9526018
OS -2.8767405 -38.95445092
OS -2.8859861 -38.9572246
OS -2.89800538 -38.96092284
OS -2.91279834 -38.96462108
OS -2.92944042 -38.96739476
OS -2.94700706 -38.96924388
OS -2.96734738 -38.97016844
OS -2.97566842 -38.97016844
OS -2.98214034 -38.96924388
OS -2.98953682 -38.96924388
OS -2.99878242 -38.96831932
OS -3.00802802 -38.96739476
OS -3.01819818 -38.96554564
OS -3.04038762 -38.96092284
OS -3.06350162 -38.95445092
OS -3.08569106 -38.94520532
OS -3.09586122 -38.93965796
OS -3.10510682 -38.93318604
OS -3.10603138 -38.93226148
OS -3.10695594 -38.93133692
OS -3.1125033 -38.92578956
OS -3.12082434 -38.91746852
OS -3.13006994 -38.90452468
OS -3.1402401 -38.88880716
OS -3.15041026 -38.87031596
OS -3.1587313 -38.84720196
OS -3.16520322 -38.82131428
OS -3.08754018 -38.809295
OS -3.08754018 -38.81021956
OS -3.08754018 -38.81114412
OS -3.08569106 -38.81669148
OS -3.08384194 -38.82593708
OS -3.0801437 -38.83610724
OS -3.0755209 -38.84720196
OS -3.06997354 -38.85922124
OS -3.0616525 -38.87124052
OS -3.05148234 -38.88141068
OS -3.04963322 -38.88233524
OS -3.04593498 -38.88510892
OS -3.0385385 -38.88880716
OS -3.0292929 -38.89342996
OS -3.01727362 -38.89805276
OS -3.00340522 -38.901751
OS -2.98676314 -38.90452468
OS -2.96734738 -38.90544924
OS -2.95810178 -38.90544924
OS -2.94885618 -38.90452468
OS -2.9368369 -38.90267556
OS -2.92389306 -38.89990188
OS -2.91002466 -38.89620364
OS -2.89800538 -38.89158084
OS -2.88691066 -38.88418436
OS -2.8859861 -38.8832598
OS -2.88228786 -38.88048612
OS -2.87858962 -38.87586332
OS -2.87304226 -38.8693914
OS -2.86841946 -38.86199492
OS -2.86379666 -38.85274932
OS -2.86102298 -38.84350372
OS -2.86009842 -38.832409
OS -2.86009842 -38.83148444
OS -2.86009842 -38.8277862
OS -2.86102298 -38.8231634
OS -2.8628721 -38.81669148
OS -2.86564578 -38.81021956
OS -2.87026858 -38.80374764
OS -2.87581594 -38.79635116
OS -2.88413698 -38.7908038
OS -2.88506154 -38.78987924
OS -2.88783522 -38.78895468
OS -2.89245802 -38.786181
OS -2.8998545 -38.78340732
OS -2.91094922 -38.77970908
OS -2.91742114 -38.7769354
OS -2.92481762 -38.77508628
OS -2.93313866 -38.7723126
OS -2.94238426 -38.76953892
OS -2.95255442 -38.76676524
OS -2.9645737 -38.76399156
OS -2.96549826 -38.76399156
OS -2.96827194 -38.763067
OS -2.97289474 -38.76214244
OS -2.9784421 -38.76029332
OS -2.98583858 -38.7584442
OS -2.99415962 -38.75567052
OS -3.01172626 -38.75104772
OS -3.03206658 -38.7445758
OS -3.05148234 -38.73902844
OS -3.06997354 -38.73255652
OS -3.07829458 -38.72885828
OS -3.0847665 -38.7260846
OS -3.08661562 -38.72516004
OS -3.09031386 -38.72331092
OS -3.09586122 -38.71961268
OS -3.1032577 -38.71498988
OS -3.11157874 -38.70851796
OS -3.11989978 -38.70112148
OS -3.12822082 -38.69280044
OS -3.1356173 -38.68263028
OS -3.13654186 -38.68170572
OS -3.13839098 -38.67800748
OS -3.14116466 -38.67153556
OS -3.14393834 -38.66413908
OS -3.14671202 -38.65489348
OS -3.1494857 -38.64379876
OS -3.15133482 -38.63270404
OS -3.15225938 -38.6197602
OS -3.15225938 -38.61791108
OS -3.15225938 -38.61421284
OS -3.15133482 -38.60866548
OS -3.15041026 -38.60034444
OS -3.14856114 -38.5920234
OS -3.14671202 -38.58185324
OS -3.14301378 -38.57260764
OS -3.13839098 -38.56243748
OS -3.13746642 -38.56151292
OS -3.1356173 -38.55781468
OS -3.13284362 -38.55319188
OS -3.12822082 -38.54671996
OS -3.12267346 -38.54024804
OS -3.11620154 -38.531927
OS -3.10880506 -38.52453052
OS -3.09955946 -38.5180586
OS -3.0986349 -38.51713404
OS -3.09586122 -38.51620948
OS -3.09216298 -38.5134358
OS -3.08661562 -38.51066212
OS -3.07921914 -38.50696388
OS -3.0708981 -38.50326564
OS -3.06072794 -38.4995674
OS -3.04963322 -38.49586916
OS -3.0477841 -38.4949446
OS -3.04408586 -38.49402004
OS -3.03761394 -38.49217092
OS -3.0292929 -38.4903218
OS -3.01912274 -38.48847268
OS -3.00802802 -38.48754812
OS -2.99508418 -38.485699
OS -2.97289474 -38.485699
OS -2.96272458 -38.48662356
OE
OB -3.41483442 -38.48662356 I
OS -3.40096602 -38.48754812
OS -3.3852485 -38.48939724
OS -3.36953098 -38.49217092
OS -3.35381346 -38.49586916
OS -3.3390205 -38.50049196
OS -3.33717138 -38.50141652
OS -3.33254858 -38.50326564
OS -3.32607666 -38.50603932
OS -3.31775562 -38.50973756
OS -3.30851002 -38.51528492
OS -3.29926442 -38.52083228
OS -3.29094338 -38.52822876
OS -3.2835469 -38.53562524
OS -3.28262234 -38.5365498
OS -3.28077322 -38.53932348
OS -3.27799954 -38.54394628
OS -3.2743013 -38.54949364
OS -3.2696785 -38.55781468
OS -3.26598026 -38.56613572
OS -3.26228202 -38.57630588
OS -3.25950834 -38.58832516
OS -3.25950834 -38.58924972
OS -3.25858378 -38.5920234
OS -3.25765922 -38.59757076
OS -3.25673466 -38.60496724
OS -3.25673466 -38.6151374
OS -3.2558101 -38.62715668
OS -3.25488554 -38.6428742
OS -3.25488554 -38.66044084
OS -3.25488554 -38.76584068
OS -3.25488554 -38.76676524
OS -3.25488554 -38.77046348
OS -3.25488554 -38.77601084
OS -3.25488554 -38.78340732
OS -3.25488554 -38.79172836
OS -3.25488554 -38.80189852
OS -3.25396098 -38.82408796
OS -3.25396098 -38.84720196
OS -3.25303642 -38.87031596
OS -3.25211186 -38.88048612
OS -3.25211186 -38.88973172
OS -3.2511873 -38.89805276
OS -3.25026274 -38.90452468
OS -3.25026274 -38.90544924
OS -3.24933818 -38.90914748
OS -3.24841362 -38.91469484
OS -3.24563994 -38.92209132
OS -3.24379082 -38.93041236
OS -3.24009258 -38.93965796
OS -3.23546978 -38.94982812
OS -3.23084698 -38.95999828
OS -3.31313282 -38.95999828
OS -3.31405738 -38.95907372
OS -3.31498194 -38.95537548
OS -3.31683106 -38.95075268
OS -3.31960474 -38.9433562
OS -3.32237842 -38.93503516
OS -3.32422754 -38.924865
OS -3.32607666 -38.91377028
OS -3.32792578 -38.901751
OS -3.32885034 -38.901751
OS -3.3297749 -38.90360012
OS -3.33532226 -38.90822292
OS -3.3436433 -38.91469484
OS -3.35473802 -38.92301588
OS -3.36860642 -38.93133692
OS -3.38247482 -38.94058252
OS -3.39726778 -38.94890356
OS -3.4129853 -38.95537548
OS -3.41483442 -38.95630004
OS -3.42038178 -38.9572246
OS -3.42870282 -38.95999828
OS -3.43887298 -38.96277196
OS -3.45181682 -38.96554564
OS -3.46660978 -38.96739476
OS -3.48325186 -38.96924388
OS -3.49989394 -38.97016844
OS -3.50729042 -38.97016844
OS -3.51283778 -38.96924388
OS -3.5193097 -38.96924388
OS -3.52670618 -38.96831932
OS -3.54334826 -38.96554564
OS -3.56183946 -38.96092284
OS -3.58217978 -38.95445092
OS -3.60067098 -38.94520532
OS -3.61731306 -38.93318604
OS -3.61916218 -38.93133692
OS -3.62378498 -38.92671412
OS -3.6302569 -38.91839308
OS -3.63765338 -38.90729836
OS -3.64504986 -38.89342996
OS -3.65152178 -38.87771244
OS -3.65614458 -38.85829668
OS -3.65706914 -38.84905108
OS -3.6579937 -38.83795636
OS -3.6579937 -38.83610724
OS -3.6579937 -38.832409
OS -3.65706914 -38.82593708
OS -3.65614458 -38.81761604
OS -3.65429546 -38.80744588
OS -3.65152178 -38.79727572
OS -3.64782354 -38.786181
OS -3.64320074 -38.77601084
OS -3.64227618 -38.77508628
OS -3.64042706 -38.77138804
OS -3.63672882 -38.76584068
OS -3.63210602 -38.75936876
OS -3.62655866 -38.75197228
OS -3.61916218 -38.7445758
OS -3.6117657 -38.73717932
OS -3.6025201 -38.7307074
OS -3.60159554 -38.72978284
OS -3.5978973 -38.72793372
OS -3.5932745 -38.72423548
OS -3.58587802 -38.72053724
OS -3.57755698 -38.716839
OS -3.56738682 -38.7122162
OS -3.55721666 -38.70851796
OS -3.54519738 -38.70481972
OS -3.54427282 -38.70481972
OS -3.54057458 -38.70389516
OS -3.53502722 -38.70204604
OS -3.52763074 -38.70112148
OS -3.51838514 -38.69927236
OS -3.50636586 -38.69742324
OS -3.49249746 -38.69464956
OS -3.47585538 -38.69280044
OS -3.47493082 -38.69280044
OS -3.47123258 -38.69187588
OS -3.46660978 -38.69187588
OS -3.46013786 -38.69095132
OS -3.45274138 -38.69002676
OS -3.44349578 -38.68817764
OS -3.43332562 -38.68725308
OS -3.4222309 -38.68540396
OS -3.40004146 -38.68078116
OS -3.3760029 -38.67615836
OS -3.35473802 -38.670611
OS -3.34456786 -38.66783732
OS -3.33532226 -38.66506364
OS -3.33532226 -38.66413908
OS -3.33532226 -38.66228996
OS -3.3343977 -38.6567426
OS -3.3343977 -38.65027068
OS -3.3343977 -38.64657244
OS -3.3343977 -38.64472332
OS -3.3343977 -38.64379876
OS -3.3343977 -38.6428742
OS -3.3343977 -38.63732684
OS -3.33532226 -38.62808124
OS -3.33717138 -38.61791108
OS -3.33994506 -38.60681636
OS -3.34456786 -38.59572164
OS -3.35011522 -38.58555148
OS -3.3575117 -38.57723044
OS -3.35843626 -38.57630588
OS -3.36305906 -38.57260764
OS -3.37045554 -38.5689094
OS -3.37970114 -38.56336204
OS -3.39264498 -38.55873924
OS -3.40743794 -38.55411644
OS -3.42592914 -38.55134276
OS -3.44719402 -38.5504182
OS -3.45643962 -38.5504182
OS -3.46568522 -38.55134276
OS -3.47862906 -38.55319188
OS -3.4915729 -38.555041
OS -3.5054413 -38.55873924
OS -3.51838514 -38.56336204
OS -3.52947986 -38.56983396
OS -3.53040442 -38.57075852
OS -3.53410266 -38.5735322
OS -3.53872546 -38.578155
OS -3.54427282 -38.58555148
OS -3.54982018 -38.59479708
OS -3.5562921 -38.60681636
OS -3.56183946 -38.62160932
OS -3.56738682 -38.6382514
OS -3.6441253 -38.62808124
OS -3.6441253 -38.62715668
OS -3.64320074 -38.62623212
OS -3.64320074 -38.62345844
OS -3.64227618 -38.6197602
OS -3.6395025 -38.61143916
OS -3.63580426 -38.59941988
OS -3.63118146 -38.5874006
OS -3.6256341 -38.57445676
OS -3.61823762 -38.56151292
OS -3.60991658 -38.54949364
OS -3.60899202 -38.54856908
OS -3.60529378 -38.54487084
OS -3.59974642 -38.53932348
OS -3.59234994 -38.531927
OS -3.58217978 -38.52453052
OS -3.5701605 -38.51713404
OS -3.5562921 -38.508813
OS -3.54057458 -38.50234108
OS -3.53965002 -38.50234108
OS -3.53872546 -38.50141652
OS -3.53595178 -38.50049196
OS -3.53225354 -38.4995674
OS -3.52300794 -38.49679372
OS -3.5100641 -38.49402004
OS -3.49527114 -38.49124636
OS -3.47677994 -38.48847268
OS -3.45736418 -38.48662356
OS -3.43517474 -38.485699
OS -3.42500458 -38.485699
OS -3.41483442 -38.48662356
OE
OB -3.90854946 -38.48662356 I
OS -3.90207754 -38.48754812
OS -3.88820914 -38.48939724
OS -3.87156706 -38.49309548
OS -3.85400042 -38.49864284
OS -3.83643378 -38.50696388
OS -3.81886714 -38.51713404
OS -3.81794258 -38.51713404
OS -3.81701802 -38.51898316
OS -3.81147066 -38.5226814
OS -3.80314962 -38.53007788
OS -3.79297946 -38.53932348
OS -3.78188474 -38.55134276
OS -3.77079002 -38.56613572
OS -3.7596953 -38.58370236
OS -3.7504497 -38.60311812
OS -3.7504497 -38.60404268
OS -3.74952514 -38.6058918
OS -3.74860058 -38.60866548
OS -3.74675146 -38.61236372
OS -3.74490234 -38.61791108
OS -3.74305322 -38.624383
OS -3.73843042 -38.63917596
OS -3.73380762 -38.65766716
OS -3.73010938 -38.67800748
OS -3.7273357 -38.70112148
OS -3.72641114 -38.72516004
OS -3.72641114 -38.7260846
OS -3.72641114 -38.72793372
OS -3.72641114 -38.73163196
OS -3.72641114 -38.73717932
OS -3.7273357 -38.74365124
OS -3.7273357 -38.75104772
OS -3.72918482 -38.7676898
OS -3.73288306 -38.78803012
OS -3.73750586 -38.809295
OS -3.74397778 -38.83148444
OS -3.75229882 -38.85367388
OS -3.75229882 -38.85459844
OS -3.75322338 -38.85644756
OS -3.7550725 -38.85922124
OS -3.75692162 -38.86291948
OS -3.76339354 -38.87308964
OS -3.77171458 -38.88603348
OS -3.78188474 -38.89990188
OS -3.79482858 -38.91377028
OS -3.80962154 -38.92763868
OS -3.82718818 -38.94058252
OS -3.82811274 -38.94058252
OS -3.8290373 -38.94150708
OS -3.83181098 -38.9433562
OS -3.83550922 -38.94520532
OS -3.84475482 -38.94982812
OS -3.85769866 -38.95537548
OS -3.87341618 -38.96092284
OS -3.89005826 -38.96554564
OS -3.90947402 -38.96924388
OS -3.92888978 -38.97016844
OS -3.9353617 -38.97016844
OS -3.94275818 -38.96924388
OS -3.95200378 -38.96831932
OS -3.9630985 -38.9664702
OS -3.97511778 -38.96369652
OS -3.98713706 -38.95999828
OS -3.99915634 -38.95445092
OS -4.0000809 -38.95352636
OS -4.0047037 -38.95167724
OS -4.01025106 -38.947979
OS -4.01764754 -38.94243164
OS -4.02504402 -38.93688428
OS -4.03428962 -38.9294878
OS -4.04261066 -38.92116676
OS -4.05000714 -38.91192116
OS -4.05000714 -39.1375138
OS -4.12859474 -39.1375138
OS -4.12859474 -38.49586916
OS -4.05740362 -38.49586916
OS -4.05740362 -38.55689012
OS -4.05647906 -38.555041
OS -4.05278082 -38.55134276
OS -4.04815802 -38.54487084
OS -4.04076154 -38.53747436
OS -4.0324405 -38.52822876
OS -4.0231949 -38.51990772
OS -4.01210018 -38.51158668
OS -4.00100546 -38.5041902
OS -3.99915634 -38.50326564
OS -3.9954581 -38.50141652
OS -3.98806162 -38.49864284
OS -3.97881602 -38.4949446
OS -3.9677213 -38.49124636
OS -3.95477746 -38.48847268
OS -3.9399845 -38.48662356
OS -3.92334242 -38.485699
OS -3.91317226 -38.485699
OS -3.90854946 -38.48662356
OE
OB -1.86989466 -38.42745172 I
OS -1.89115954 -38.54671996
OS -1.94016122 -38.54671996
OS -1.95957698 -38.42745172
OS -1.95957698 -38.32020276
OS -1.86989466 -38.32020276
OS -1.86989466 -38.42745172
OE
OB -2.23232218 -38.48662356 I
OS -2.2249257 -38.48754812
OS -2.2156801 -38.48939724
OS -2.20550994 -38.49124636
OS -2.19349066 -38.49402004
OS -2.18239594 -38.49679372
OS -2.1694521 -38.50141652
OS -2.15743282 -38.50603932
OS -2.14448898 -38.51251124
OS -2.13154514 -38.51990772
OS -2.1186013 -38.52822876
OS -2.10658202 -38.53839892
OS -2.0954873 -38.54949364
OS -2.09456274 -38.5504182
OS -2.09271362 -38.55226732
OS -2.08993994 -38.55596556
OS -2.0862417 -38.56151292
OS -2.0816189 -38.56798484
OS -2.0769961 -38.57538132
OS -2.07144874 -38.58462692
OS -2.06590138 -38.59572164
OS -2.06035402 -38.60774092
OS -2.05480666 -38.62068476
OS -2.05018386 -38.63547772
OS -2.04556106 -38.65119524
OS -2.04186282 -38.66876188
OS -2.03908914 -38.68725308
OS -2.03724002 -38.70666884
OS -2.03631546 -38.72793372
OS -2.03631546 -38.72885828
OS -2.03631546 -38.73255652
OS -2.03631546 -38.73902844
OS -2.03724002 -38.74827404
OS -2.38395002 -38.74827404
OS -2.38395002 -38.7491986
OS -2.38395002 -38.75197228
OS -2.38302546 -38.75567052
OS -2.38302546 -38.76121788
OS -2.3821009 -38.7676898
OS -2.38025178 -38.77508628
OS -2.3774781 -38.79172836
OS -2.37193074 -38.81021956
OS -2.36453426 -38.83055988
OS -2.3543641 -38.84905108
OS -2.34142026 -38.86569316
OS -2.3404957 -38.86569316
OS -2.33957114 -38.86754228
OS -2.33402378 -38.87216508
OS -2.32570274 -38.878637
OS -2.31460802 -38.88510892
OS -2.29981506 -38.8925054
OS -2.28317298 -38.89897732
OS -2.26468178 -38.90360012
OS -2.25451162 -38.90452468
OS -2.2434169 -38.90544924
OS -2.23602042 -38.90544924
OS -2.22769938 -38.90452468
OS -2.21752922 -38.90267556
OS -2.2064345 -38.89990188
OS -2.19349066 -38.89620364
OS -2.18147138 -38.89065628
OS -2.1694521 -38.8832598
OS -2.16852754 -38.88233524
OS -2.16390474 -38.878637
OS -2.15835738 -38.87308964
OS -2.15188546 -38.86569316
OS -2.14448898 -38.855523
OS -2.13616794 -38.84257916
OS -2.1278469 -38.8277862
OS -2.12045042 -38.81021956
OS -2.03908914 -38.82038972
OS -2.03908914 -38.82131428
OS -2.0400137 -38.8231634
OS -2.04093826 -38.82686164
OS -2.04278738 -38.832409
OS -2.04556106 -38.83795636
OS -2.04833474 -38.84535284
OS -2.05573122 -38.86107036
OS -2.06497682 -38.878637
OS -2.07792066 -38.8971282
OS -2.09271362 -38.91469484
OS -2.11120482 -38.93133692
OS -2.11212938 -38.93133692
OS -2.1139785 -38.93318604
OS -2.11675218 -38.93503516
OS -2.12045042 -38.93780884
OS -2.12599778 -38.94058252
OS -2.13154514 -38.9433562
OS -2.13894162 -38.94705444
OS -2.14726266 -38.95075268
OS -2.15650826 -38.95445092
OS -2.16575386 -38.95814916
OS -2.18886786 -38.96369652
OS -2.21475554 -38.96831932
OS -2.2434169 -38.97016844
OS -2.25358706 -38.97016844
OS -2.26005898 -38.96924388
OS -2.26838002 -38.96831932
OS -2.27855018 -38.9664702
OS -2.2896449 -38.96462108
OS -2.30166418 -38.96277196
OS -2.32755186 -38.95537548
OS -2.34142026 -38.94982812
OS -2.3543641 -38.94428076
OS -2.3682325 -38.93688428
OS -2.38117634 -38.92856324
OS -2.39319562 -38.91931764
OS -2.4052149 -38.90822292
OS -2.40613946 -38.90729836
OS -2.40798858 -38.90544924
OS -2.41076226 -38.901751
OS -2.4144605 -38.89620364
OS -2.4190833 -38.88973172
OS -2.4237061 -38.88233524
OS -2.42925346 -38.87308964
OS -2.43480082 -38.86291948
OS -2.44034818 -38.8509002
OS -2.44589554 -38.83795636
OS -2.45051834 -38.8231634
OS -2.45514114 -38.80744588
OS -2.45883938 -38.7908038
OS -2.46161306 -38.7723126
OS -2.46346218 -38.75289684
OS -2.46438674 -38.73255652
OS -2.46438674 -38.73163196
OS -2.46438674 -38.72700916
OS -2.46438674 -38.7214618
OS -2.46346218 -38.71314076
OS -2.46253762 -38.7029706
OS -2.46161306 -38.69187588
OS -2.45976394 -38.67893204
OS -2.45699026 -38.6659882
OS -2.44959378 -38.63640228
OS -2.44497098 -38.62160932
OS -2.43942362 -38.6058918
OS -2.43202714 -38.59109884
OS -2.4237061 -38.57723044
OS -2.4144605 -38.56336204
OS -2.40429034 -38.5504182
OS -2.40336578 -38.54949364
OS -2.40151666 -38.54764452
OS -2.39781842 -38.54487084
OS -2.39319562 -38.54024804
OS -2.38764826 -38.53562524
OS -2.38025178 -38.53007788
OS -2.37193074 -38.52360596
OS -2.36176058 -38.5180586
OS -2.35159042 -38.51158668
OS -2.33957114 -38.50603932
OS -2.3266273 -38.50049196
OS -2.3127589 -38.49586916
OS -2.29796594 -38.49124636
OS -2.28224842 -38.48847268
OS -2.26560634 -38.48662356
OS -2.2480397 -38.485699
OS -2.2387941 -38.485699
OS -2.23232218 -38.48662356
OE
OB -2.5947497 -38.49586916 I
OS -2.51523754 -38.49586916
OS -2.51523754 -38.55689012
OS -2.5947497 -38.55689012
OS -2.5947497 -38.82963532
OS -2.5947497 -38.83148444
OS -2.5947497 -38.83518268
OS -2.5947497 -38.84073004
OS -2.59382514 -38.84720196
OS -2.59290058 -38.86199492
OS -2.59197602 -38.86846684
OS -2.59105146 -38.87308964
OS -2.5901269 -38.87493876
OS -2.58735322 -38.878637
OS -2.58365498 -38.8832598
OS -2.57718306 -38.8878826
OS -2.57533394 -38.88880716
OS -2.57071114 -38.89065628
OS -2.5623901 -38.8925054
OS -2.55037082 -38.89342996
OS -2.54112522 -38.89342996
OS -2.53650242 -38.8925054
OS -2.5300305 -38.8925054
OS -2.52263402 -38.89158084
OS -2.51523754 -38.89065628
OS -2.50506738 -38.95999828
OS -2.5069165 -38.95999828
OS -2.51061474 -38.96092284
OS -2.51708666 -38.9618474
OS -2.5254077 -38.96277196
OS -2.5346533 -38.96462108
OS -2.54482346 -38.96554564
OS -2.56516378 -38.9664702
OS -2.57256026 -38.9664702
OS -2.57995674 -38.96554564
OS -2.58920234 -38.96462108
OS -2.60029706 -38.96369652
OS -2.61139178 -38.96092284
OS -2.62156194 -38.95814916
OS -2.6317321 -38.95352636
OS -2.63265666 -38.9526018
OS -2.63543034 -38.95075268
OS -2.63912858 -38.947979
OS -2.64467594 -38.9433562
OS -2.64929874 -38.9387334
OS -2.6548461 -38.93226148
OS -2.66039346 -38.92578956
OS -2.6640917 -38.91746852
OS -2.6640917 -38.91654396
OS -2.66594082 -38.91284572
OS -2.66686538 -38.9063738
OS -2.6687145 -38.8971282
OS -2.67056362 -38.88510892
OS -2.67148818 -38.87771244
OS -2.67148818 -38.8693914
OS -2.67241274 -38.85922124
OS -2.6733373 -38.84905108
OS -2.6733373 -38.83795636
OS -2.6733373 -38.82501252
OS -2.6733373 -38.55689012
OS -2.73158458 -38.55689012
OS -2.73158458 -38.49586916
OS -2.6733373 -38.49586916
OS -2.6733373 -38.38122372
OS -2.5947497 -38.33407116
OS -2.5947497 -38.49586916
OE
OB -4.17852098 -39.1375138 I
OS -4.69904826 -39.1375138
OS -4.69904826 -39.08111564
OS -4.17852098 -39.08111564
OS -4.17852098 -39.1375138
OE
OB -5.41743138 -38.48662356 I
OS -5.40911034 -38.48754812
OS -5.39986474 -38.48939724
OS -5.38969458 -38.49124636
OS -5.3776753 -38.49309548
OS -5.35271218 -38.50141652
OS -5.33976834 -38.50603932
OS -5.3268245 -38.51251124
OS -5.31388066 -38.51898316
OS -5.30093682 -38.52822876
OS -5.28891754 -38.53747436
OS -5.27689826 -38.54856908
OS -5.2759737 -38.54949364
OS -5.27412458 -38.55134276
OS -5.2713509 -38.555041
OS -5.26765266 -38.5596638
OS -5.26302986 -38.56613572
OS -5.2574825 -38.57445676
OS -5.25193514 -38.58370236
OS -5.24638778 -38.59387252
OS -5.24084042 -38.60496724
OS -5.23529306 -38.61883564
OS -5.2297457 -38.63270404
OS -5.2251229 -38.64842156
OS -5.22142466 -38.66506364
OS -5.21865098 -38.68263028
OS -5.21680186 -38.70112148
OS -5.2158773 -38.7214618
OS -5.2158773 -38.72238636
OS -5.2158773 -38.72516004
OS -5.2158773 -38.72978284
OS -5.2158773 -38.73625476
OS -5.21680186 -38.74365124
OS -5.21772642 -38.75289684
OS -5.21772642 -38.76214244
OS -5.21957554 -38.7723126
OS -5.22234922 -38.7954266
OS -5.22789658 -38.8185406
OS -5.2343685 -38.8416546
OS -5.2436141 -38.86291948
OS -5.2436141 -38.86384404
OS -5.24453866 -38.8647686
OS -5.24638778 -38.86754228
OS -5.2482369 -38.87124052
OS -5.25470882 -38.88048612
OS -5.26302986 -38.89158084
OS -5.27412458 -38.90452468
OS -5.28799298 -38.91746852
OS -5.3037105 -38.93041236
OS -5.3222017 -38.94243164
OS -5.32312626 -38.94243164
OS -5.32405082 -38.9433562
OS -5.3268245 -38.94520532
OS -5.3314473 -38.94705444
OS -5.3360701 -38.94890356
OS -5.34161746 -38.95075268
OS -5.35548586 -38.95630004
OS -5.37120338 -38.96092284
OS -5.39061914 -38.96554564
OS -5.41095946 -38.96924388
OS -5.4331489 -38.97016844
OS -5.4423945 -38.97016844
OS -5.44979098 -38.96924388
OS -5.45811202 -38.96831932
OS -5.46735762 -38.9664702
OS -5.47845234 -38.96462108
OS -5.48954706 -38.96277196
OS -5.51451018 -38.95537548
OS -5.52837858 -38.94982812
OS -5.54132242 -38.94428076
OS -5.55426626 -38.93688428
OS -5.5672101 -38.92856324
OS -5.57922938 -38.91931764
OS -5.59124866 -38.90822292
OS -5.59217322 -38.90729836
OS -5.59402234 -38.90544924
OS -5.59679602 -38.901751
OS -5.60049426 -38.89620364
OS -5.60511706 -38.88973172
OS -5.60973986 -38.88233524
OS -5.61528722 -38.87308964
OS -5.62083458 -38.86199492
OS -5.62638194 -38.84997564
OS -5.6319293 -38.83610724
OS -5.6365521 -38.82131428
OS -5.6411749 -38.80559676
OS -5.64487314 -38.78803012
OS -5.64764682 -38.76953892
OS -5.64949594 -38.7491986
OS -5.6504205 -38.72793372
OS -5.6504205 -38.7260846
OS -5.6504205 -38.72238636
OS -5.64949594 -38.71591444
OS -5.64949594 -38.70666884
OS -5.64857138 -38.69649868
OS -5.64672226 -38.68355484
OS -5.64487314 -38.670611
OS -5.6411749 -38.65581804
OS -5.63747666 -38.64102508
OS -5.63285386 -38.62530756
OS -5.6273065 -38.60866548
OS -5.61991002 -38.59294796
OS -5.61251354 -38.578155
OS -5.60234338 -38.56336204
OS -5.59217322 -38.54949364
OS -5.57922938 -38.53747436
OS -5.57830482 -38.5365498
OS -5.5764557 -38.53562524
OS -5.57275746 -38.53285156
OS -5.56813466 -38.52915332
OS -5.5625873 -38.52545508
OS -5.55519082 -38.52083228
OS -5.54779434 -38.51620948
OS -5.53854874 -38.51158668
OS -5.52837858 -38.50696388
OS -5.51728386 -38.50234108
OS -5.49232074 -38.49402004
OS -5.46365938 -38.48754812
OS -5.44886642 -38.48662356
OS -5.4331489 -38.485699
OS -5.4239033 -38.485699
OS -5.41743138 -38.48662356
OE
OB -5.97031826 -38.42745172 I
OS -5.99158314 -38.54671996
OS -6.04058482 -38.54671996
OS -6.06000058 -38.42745172
OS -6.06000058 -38.32020276
OS -5.97031826 -38.32020276
OS -5.97031826 -38.42745172
OE
OB -5.77800978 -38.49586916 I
OS -5.69849762 -38.49586916
OS -5.69849762 -38.55689012
OS -5.77800978 -38.55689012
OS -5.77800978 -38.82963532
OS -5.77800978 -38.83148444
OS -5.77800978 -38.83518268
OS -5.77800978 -38.84073004
OS -5.77708522 -38.84720196
OS -5.77616066 -38.86199492
OS -5.7752361 -38.86846684
OS -5.77431154 -38.87308964
OS -5.77338698 -38.87493876
OS -5.7706133 -38.878637
OS -5.76691506 -38.8832598
OS -5.76044314 -38.8878826
OS -5.75859402 -38.88880716
OS -5.75397122 -38.89065628
OS -5.74565018 -38.8925054
OS -5.7336309 -38.89342996
OS -5.7243853 -38.89342996
OS -5.7197625 -38.8925054
OS -5.71329058 -38.8925054
OS -5.7058941 -38.89158084
OS -5.69849762 -38.89065628
OS -5.68832746 -38.95999828
OS -5.69017658 -38.95999828
OS -5.69387482 -38.96092284
OS -5.70034674 -38.9618474
OS -5.70866778 -38.96277196
OS -5.71791338 -38.96462108
OS -5.72808354 -38.96554564
OS -5.74842386 -38.9664702
OS -5.75582034 -38.9664702
OS -5.76321682 -38.96554564
OS -5.77246242 -38.96462108
OS -5.78355714 -38.96369652
OS -5.79465186 -38.96092284
OS -5.80482202 -38.95814916
OS -5.81499218 -38.95352636
OS -5.81591674 -38.9526018
OS -5.81869042 -38.95075268
OS -5.82238866 -38.947979
OS -5.82793602 -38.9433562
OS -5.83255882 -38.9387334
OS -5.83810618 -38.93226148
OS -5.84365354 -38.92578956
OS -5.84735178 -38.91746852
OS -5.84735178 -38.91654396
OS -5.8492009 -38.91284572
OS -5.85012546 -38.9063738
OS -5.85197458 -38.8971282
OS -5.8538237 -38.88510892
OS -5.85474826 -38.87771244
OS -5.85474826 -38.8693914
OS -5.85567282 -38.85922124
OS -5.85659738 -38.84905108
OS -5.85659738 -38.83795636
OS -5.85659738 -38.82501252
OS -5.85659738 -38.55689012
OS -5.91484466 -38.55689012
OS -5.91484466 -38.49586916
OS -5.85659738 -38.49586916
OS -5.85659738 -38.38122372
OS -5.77800978 -38.33407116
OS -5.77800978 -38.49586916
OE
OB -4.90337602 -38.48662356 I
OS -4.8969041 -38.48754812
OS -4.8830357 -38.48939724
OS -4.86639362 -38.49309548
OS -4.84882698 -38.49864284
OS -4.83126034 -38.50696388
OS -4.8136937 -38.51713404
OS -4.81276914 -38.51713404
OS -4.81184458 -38.51898316
OS -4.80629722 -38.5226814
OS -4.79797618 -38.53007788
OS -4.78780602 -38.53932348
OS -4.7767113 -38.55134276
OS -4.76561658 -38.56613572
OS -4.75452186 -38.58370236
OS -4.74527626 -38.60311812
OS -4.74527626 -38.60404268
OS -4.7443517 -38.6058918
OS -4.74342714 -38.60866548
OS -4.74157802 -38.61236372
OS -4.7397289 -38.61791108
OS -4.73787978 -38.624383
OS -4.73325698 -38.63917596
OS -4.72863418 -38.65766716
OS -4.72493594 -38.67800748
OS -4.72216226 -38.70112148
OS -4.7212377 -38.72516004
OS -4.7212377 -38.7260846
OS -4.7212377 -38.72793372
OS -4.7212377 -38.73163196
OS -4.7212377 -38.73717932
OS -4.72216226 -38.74365124
OS -4.72216226 -38.75104772
OS -4.72401138 -38.7676898
OS -4.72770962 -38.78803012
OS -4.73233242 -38.809295
OS -4.73880434 -38.83148444
OS -4.74712538 -38.85367388
OS -4.74712538 -38.85459844
OS -4.74804994 -38.85644756
OS -4.74989906 -38.85922124
OS -4.75174818 -38.86291948
OS -4.7582201 -38.87308964
OS -4.76654114 -38.88603348
OS -4.7767113 -38.89990188
OS -4.78965514 -38.91377028
OS -4.8044481 -38.92763868
OS -4.82201474 -38.94058252
OS -4.8229393 -38.94058252
OS -4.82386386 -38.94150708
OS -4.82663754 -38.9433562
OS -4.83033578 -38.94520532
OS -4.83958138 -38.94982812
OS -4.85252522 -38.95537548
OS -4.86824274 -38.96092284
OS -4.88488482 -38.96554564
OS -4.90430058 -38.96924388
OS -4.92371634 -38.97016844
OS -4.93018826 -38.97016844
OS -4.93758474 -38.96924388
OS -4.94683034 -38.96831932
OS -4.95792506 -38.9664702
OS -4.96994434 -38.96369652
OS -4.98196362 -38.95999828
OS -4.9939829 -38.95445092
OS -4.99490746 -38.95352636
OS -4.99953026 -38.95167724
OS -5.00507762 -38.947979
OS -5.0124741 -38.94243164
OS -5.01987058 -38.93688428
OS -5.02911618 -38.9294878
OS -5.03743722 -38.92116676
OS -5.0448337 -38.91192116
OS -5.0448337 -39.1375138
OS -5.1234213 -39.1375138
OS -5.1234213 -38.49586916
OS -5.05223018 -38.49586916
OS -5.05223018 -38.55689012
OS -5.05130562 -38.555041
OS -5.04760738 -38.55134276
OS -5.04298458 -38.54487084
OS -5.0355881 -38.53747436
OS -5.02726706 -38.52822876
OS -5.01802146 -38.51990772
OS -5.00692674 -38.51158668
OS -4.99583202 -38.5041902
OS -4.9939829 -38.50326564
OS -4.99028466 -38.50141652
OS -4.98288818 -38.49864284
OS -4.97364258 -38.4949446
OS -4.96254786 -38.49124636
OS -4.94960402 -38.48847268
OS -4.93481106 -38.48662356
OS -4.91816898 -38.485699
OS -4.90799882 -38.485699
OS -4.90337602 -38.48662356
OE
OB -3.9307389 -38.54764452 H
OS -3.9353617 -38.54764452
OS -3.93905994 -38.54856908
OS -3.94830554 -38.5504182
OS -3.96032482 -38.55319188
OS -3.97419322 -38.55873924
OS -3.98898618 -38.56706028
OS -3.99730722 -38.57260764
OS -4.0047037 -38.57907956
OS -4.01210018 -38.58647604
OS -4.01949666 -38.59479708
OS -4.01949666 -38.59572164
OS -4.02134578 -38.5966462
OS -4.0231949 -38.59941988
OS -4.02504402 -38.60311812
OS -4.0278177 -38.60866548
OS -4.03151594 -38.61421284
OS -4.03521418 -38.62160932
OS -4.03798786 -38.6290058
OS -4.0416861 -38.6382514
OS -4.04538434 -38.64842156
OS -4.04815802 -38.65951628
OS -4.05185626 -38.67153556
OS -4.05370538 -38.68540396
OS -4.0555545 -38.69927236
OS -4.05740362 -38.71406532
OS -4.05740362 -38.7307074
OS -4.05740362 -38.73163196
OS -4.05740362 -38.73440564
OS -4.05740362 -38.73902844
OS -4.05647906 -38.74550036
OS -4.05647906 -38.75289684
OS -4.0555545 -38.76121788
OS -4.05278082 -38.78063364
OS -4.04815802 -38.80282308
OS -4.04261066 -38.82408796
OS -4.03336506 -38.84535284
OS -4.0278177 -38.85459844
OS -4.02134578 -38.86291948
OS -4.01949666 -38.8647686
OS -4.01487386 -38.8693914
OS -4.00747738 -38.87678788
OS -3.99730722 -38.88418436
OS -3.98436338 -38.89158084
OS -3.96957042 -38.89897732
OS -3.95292834 -38.90360012
OS -3.94368274 -38.90452468
OS -3.93443714 -38.90544924
OS -3.92888978 -38.90544924
OS -3.92519154 -38.90452468
OS -3.91594594 -38.90267556
OS -3.9030021 -38.89990188
OS -3.8891337 -38.89435452
OS -3.87434074 -38.88695804
OS -3.85954778 -38.87586332
OS -3.8521513 -38.8693914
OS -3.84475482 -38.86199492
OS -3.84475482 -38.86107036
OS -3.8429057 -38.8601458
OS -3.84105658 -38.85737212
OS -3.83920746 -38.85367388
OS -3.83550922 -38.84905108
OS -3.83273554 -38.84257916
OS -3.8290373 -38.83610724
OS -3.82533906 -38.8277862
OS -3.82256538 -38.81946516
OS -3.81886714 -38.80837044
OS -3.8151689 -38.79727572
OS -3.81239522 -38.78525644
OS -3.8105461 -38.77138804
OS -3.80869698 -38.75659508
OS -3.80684786 -38.74087756
OS -3.80684786 -38.72423548
OS -3.80684786 -38.72331092
OS -3.80684786 -38.72053724
OS -3.80684786 -38.71591444
OS -3.80777242 -38.70944252
OS -3.80777242 -38.70204604
OS -3.80869698 -38.693725
OS -3.81147066 -38.67430924
OS -3.81609346 -38.65304436
OS -3.82256538 -38.63177948
OS -3.83181098 -38.6105146
OS -3.83735834 -38.60034444
OS -3.84383026 -38.5920234
OS -3.84383026 -38.59109884
OS -3.84567938 -38.59017428
OS -3.85030218 -38.58462692
OS -3.85769866 -38.578155
OS -3.86786882 -38.56983396
OS -3.88081266 -38.56151292
OS -3.89560562 -38.55411644
OS -3.9122477 -38.54949364
OS -3.9214933 -38.54856908
OS -3.9307389 -38.54764452
OE
OB -4.92556546 -38.54764452 H
OS -4.93018826 -38.54764452
OS -4.9338865 -38.54856908
OS -4.9431321 -38.5504182
OS -4.95515138 -38.55319188
OS -4.96901978 -38.55873924
OS -4.98381274 -38.56706028
OS -4.99213378 -38.57260764
OS -4.99953026 -38.57907956
OS -5.00692674 -38.58647604
OS -5.01432322 -38.59479708
OS -5.01432322 -38.59572164
OS -5.01617234 -38.5966462
OS -5.01802146 -38.59941988
OS -5.01987058 -38.60311812
OS -5.02264426 -38.60866548
OS -5.0263425 -38.61421284
OS -5.03004074 -38.62160932
OS -5.03281442 -38.6290058
OS -5.03651266 -38.6382514
OS -5.0402109 -38.64842156
OS -5.04298458 -38.65951628
OS -5.04668282 -38.67153556
OS -5.04853194 -38.68540396
OS -5.05038106 -38.69927236
OS -5.05223018 -38.71406532
OS -5.05223018 -38.7307074
OS -5.05223018 -38.73163196
OS -5.05223018 -38.73440564
OS -5.05223018 -38.73902844
OS -5.05130562 -38.74550036
OS -5.05130562 -38.75289684
OS -5.05038106 -38.76121788
OS -5.04760738 -38.78063364
OS -5.04298458 -38.80282308
OS -5.03743722 -38.82408796
OS -5.02819162 -38.84535284
OS -5.02264426 -38.85459844
OS -5.01617234 -38.86291948
OS -5.01432322 -38.8647686
OS -5.00970042 -38.8693914
OS -5.00230394 -38.87678788
OS -4.99213378 -38.88418436
OS -4.97918994 -38.89158084
OS -4.96439698 -38.89897732
OS -4.9477549 -38.90360012
OS -4.9385093 -38.90452468
OS -4.9292637 -38.90544924
OS -4.92371634 -38.90544924
OS -4.9200181 -38.90452468
OS -4.9107725 -38.90267556
OS -4.89782866 -38.89990188
OS -4.88396026 -38.89435452
OS -4.8691673 -38.88695804
OS -4.85437434 -38.87586332
OS -4.84697786 -38.8693914
OS -4.83958138 -38.86199492
OS -4.83958138 -38.86107036
OS -4.83773226 -38.8601458
OS -4.83588314 -38.85737212
OS -4.83403402 -38.85367388
OS -4.83033578 -38.84905108
OS -4.8275621 -38.84257916
OS -4.82386386 -38.83610724
OS -4.82016562 -38.8277862
OS -4.81739194 -38.81946516
OS -4.8136937 -38.80837044
OS -4.80999546 -38.79727572
OS -4.80722178 -38.78525644
OS -4.80537266 -38.77138804
OS -4.80352354 -38.75659508
OS -4.80167442 -38.74087756
OS -4.80167442 -38.72423548
OS -4.80167442 -38.72331092
OS -4.80167442 -38.72053724
OS -4.80167442 -38.71591444
OS -4.80259898 -38.70944252
OS -4.80259898 -38.70204604
OS -4.80352354 -38.693725
OS -4.80629722 -38.67430924
OS -4.81092002 -38.65304436
OS -4.81739194 -38.63177948
OS -4.82663754 -38.6105146
OS -4.8321849 -38.60034444
OS -4.83865682 -38.5920234
OS -4.83865682 -38.59109884
OS -4.84050594 -38.59017428
OS -4.84512874 -38.58462692
OS -4.85252522 -38.578155
OS -4.86269538 -38.56983396
OS -4.87563922 -38.56151292
OS -4.89043218 -38.55411644
OS -4.90707426 -38.54949364
OS -4.91631986 -38.54856908
OS -4.92556546 -38.54764452
OE
OB -2.24711514 -38.5504182 H
OS -2.2526625 -38.5504182
OS -2.25636074 -38.55134276
OS -2.2665309 -38.55226732
OS -2.27855018 -38.555041
OS -2.29334314 -38.5596638
OS -2.30906066 -38.56613572
OS -2.32385362 -38.57538132
OS -2.33864658 -38.5874006
OS -2.3404957 -38.58924972
OS -2.34419394 -38.59387252
OS -2.35066586 -38.60219356
OS -2.35713778 -38.61328828
OS -2.36453426 -38.62623212
OS -2.37100618 -38.6428742
OS -2.37655354 -38.66228996
OS -2.37932722 -38.68355484
OS -2.11952586 -38.68355484
OS -2.11952586 -38.68263028
OS -2.11952586 -38.68078116
OS -2.12045042 -38.67800748
OS -2.12045042 -38.67430924
OS -2.12229954 -38.66321452
OS -2.12507322 -38.65119524
OS -2.12969602 -38.63640228
OS -2.13431882 -38.62253388
OS -2.1417153 -38.60866548
OS -2.15003634 -38.5966462
OS -2.15003634 -38.59572164
OS -2.15188546 -38.59479708
OS -2.15650826 -38.58924972
OS -2.1648293 -38.58185324
OS -2.17592402 -38.5735322
OS -2.18979242 -38.56521116
OS -2.2064345 -38.55781468
OS -2.22585026 -38.55226732
OS -2.23602042 -38.55134276
OS -2.24711514 -38.5504182
OE
OB -3.3343977 -38.72700916 H
OS -3.33532226 -38.72700916
OS -3.33624682 -38.72793372
OS -3.3390205 -38.72885828
OS -3.34271874 -38.72978284
OS -3.34734154 -38.73163196
OS -3.3528889 -38.73348108
OS -3.35936082 -38.7353302
OS -3.3667573 -38.73717932
OS -3.37507834 -38.739953
OS -3.3852485 -38.74180212
OS -3.39541866 -38.7445758
OS -3.40743794 -38.74734948
OS -3.42038178 -38.75012316
OS -3.43332562 -38.75289684
OS -3.44811858 -38.75474596
OS -3.4638361 -38.75751964
OS -3.46568522 -38.75751964
OS -3.47123258 -38.7584442
OS -3.48047818 -38.76029332
OS -3.49064834 -38.76214244
OS -3.50174306 -38.76399156
OS -3.51283778 -38.76676524
OS -3.52300794 -38.76953892
OS -3.53225354 -38.77323716
OS -3.5331781 -38.77323716
OS -3.53595178 -38.77508628
OS -3.53965002 -38.7769354
OS -3.54334826 -38.77970908
OS -3.55444298 -38.78710556
OS -3.56368858 -38.79820028
OS -3.56368858 -38.79912484
OS -3.5655377 -38.80097396
OS -3.56646226 -38.8046722
OS -3.56831138 -38.809295
OS -3.5701605 -38.81484236
OS -3.57200962 -38.82038972
OS -3.57293418 -38.8277862
OS -3.57385874 -38.83518268
OS -3.57385874 -38.83610724
OS -3.57385874 -38.84073004
OS -3.57293418 -38.8462774
OS -3.57108506 -38.85367388
OS -3.56831138 -38.86199492
OS -3.56368858 -38.87031596
OS -3.55814122 -38.87956156
OS -3.55074474 -38.8878826
OS -3.54982018 -38.88880716
OS -3.54612194 -38.89065628
OS -3.54057458 -38.89435452
OS -3.5331781 -38.89805276
OS -3.52300794 -38.901751
OS -3.51098866 -38.90544924
OS -3.49712026 -38.90729836
OS -3.48047818 -38.90822292
OS -3.4730817 -38.90822292
OS -3.4638361 -38.90729836
OS -3.45366594 -38.90544924
OS -3.4407221 -38.90360012
OS -3.42777826 -38.89990188
OS -3.41390986 -38.89527908
OS -3.40004146 -38.88880716
OS -3.39819234 -38.8878826
OS -3.3944941 -38.88510892
OS -3.38802218 -38.88048612
OS -3.3806257 -38.8740142
OS -3.37230466 -38.86661772
OS -3.36305906 -38.85737212
OS -3.35566258 -38.8462774
OS -3.3482661 -38.83425812
OS -3.34734154 -38.83333356
OS -3.34641698 -38.82963532
OS -3.34456786 -38.8231634
OS -3.34179418 -38.81484236
OS -3.3390205 -38.80374764
OS -3.33717138 -38.7908038
OS -3.33624682 -38.77508628
OS -3.33532226 -38.75659508
OS -3.3343977 -38.72700916
OE
OB -5.4331489 -38.5504182 H
OS -5.43869626 -38.5504182
OS -5.44331906 -38.55134276
OS -5.45348922 -38.55226732
OS -5.46735762 -38.55596556
OS -5.48307514 -38.56151292
OS -5.49971722 -38.5689094
OS -5.51543474 -38.58000412
OS -5.52375578 -38.5874006
OS -5.53115226 -38.59479708
OS -5.53115226 -38.59572164
OS -5.53300138 -38.5966462
OS -5.5348505 -38.59941988
OS -5.53762418 -38.60311812
OS -5.54039786 -38.60774092
OS -5.54317154 -38.61328828
OS -5.54686978 -38.62068476
OS -5.55056802 -38.62808124
OS -5.55426626 -38.63732684
OS -5.5579645 -38.64657244
OS -5.56073818 -38.65766716
OS -5.56351186 -38.66968644
OS -5.56628554 -38.68263028
OS -5.56813466 -38.69649868
OS -5.56905922 -38.7122162
OS -5.56998378 -38.72793372
OS -5.56998378 -38.72885828
OS -5.56998378 -38.73163196
OS -5.56998378 -38.73625476
OS -5.56905922 -38.74272668
OS -5.56905922 -38.75012316
OS -5.56813466 -38.7584442
OS -5.56536098 -38.77785996
OS -5.56073818 -38.8000494
OS -5.5533417 -38.82223884
OS -5.5440961 -38.84350372
OS -5.53762418 -38.85274932
OS -5.53115226 -38.86199492
OS -5.5302277 -38.86199492
OS -5.52930314 -38.86384404
OS -5.52375578 -38.86846684
OS -5.51543474 -38.87586332
OS -5.50434002 -38.8832598
OS -5.49047162 -38.89158084
OS -5.47382954 -38.89897732
OS -5.45441378 -38.90360012
OS -5.44424362 -38.90452468
OS -5.4331489 -38.90544924
OS -5.42760154 -38.90544924
OS -5.42297874 -38.90452468
OS -5.41280858 -38.90267556
OS -5.39894018 -38.89990188
OS -5.38414722 -38.89435452
OS -5.36750514 -38.88695804
OS -5.35178762 -38.87586332
OS -5.34346658 -38.86846684
OS -5.3360701 -38.86107036
OS -5.33514554 -38.8601458
OS -5.33422098 -38.85922124
OS -5.33237186 -38.85644756
OS -5.32959818 -38.85274932
OS -5.3268245 -38.84812652
OS -5.32312626 -38.84257916
OS -5.31942802 -38.83518268
OS -5.31572978 -38.8277862
OS -5.31203154 -38.8185406
OS -5.30925786 -38.80837044
OS -5.30555962 -38.79727572
OS -5.30278594 -38.78525644
OS -5.30001226 -38.77138804
OS -5.29816314 -38.75751964
OS -5.29631402 -38.74180212
OS -5.29631402 -38.72516004
OS -5.29631402 -38.72423548
OS -5.29631402 -38.7214618
OS -5.29631402 -38.716839
OS -5.29723858 -38.71129164
OS -5.29723858 -38.70389516
OS -5.29816314 -38.69557412
OS -5.30093682 -38.67615836
OS -5.30555962 -38.65581804
OS -5.3129561 -38.6336286
OS -5.32312626 -38.61328828
OS -5.32867362 -38.60311812
OS -5.3360701 -38.59479708
OS -5.3360701 -38.59387252
OS -5.33791922 -38.59294796
OS -5.34346658 -38.5874006
OS -5.35178762 -38.58092868
OS -5.36288234 -38.57260764
OS -5.37675074 -38.5642866
OS -5.39339282 -38.55689012
OS -5.41188402 -38.55226732
OS -5.42205418 -38.55134276
OS -5.4331489 -38.5504182
OE
SE
S P 0
OB -4.66714078 -36.5016923 I
OS -4.65465922 -36.5016923
OS -4.62553558 -36.50307914
OS -4.5950251 -36.50723966
OS -4.56174094 -36.51140018
OS -4.53123046 -36.51833438
OS -4.51597522 -36.5224949
OS -4.50349366 -36.52665542
OS -4.50210682 -36.52665542
OS -4.50071998 -36.52804226
OS -4.49239894 -36.53220278
OS -4.47991738 -36.53775014
OS -4.46466214 -36.54745802
OS -4.44802006 -36.55993958
OS -4.42999114 -36.57658166
OS -4.41334906 -36.59599742
OS -4.39670698 -36.61818686
OS -4.39670698 -36.6195737
OS -4.39532014 -36.62096054
OS -4.38977278 -36.62928158
OS -4.38422542 -36.64314998
OS -4.37590438 -36.6611789
OS -4.36897018 -36.6819815
OS -4.36203598 -36.70694462
OS -4.35787546 -36.73329458
OS -4.35648862 -36.76241822
OS -4.35648862 -36.76380506
OS -4.35648862 -36.76657874
OS -4.35648862 -36.7721261
OS -4.35787546 -36.7790603
OS -4.35787546 -36.78876818
OS -4.3592623 -36.79847606
OS -4.36480966 -36.82205234
OS -4.3731307 -36.84978914
OS -4.38422542 -36.87891278
OS -4.4008675 -36.90803642
OS -4.41196222 -36.92190482
OS -4.42305694 -36.93577322
OS -4.42444378 -36.93716006
OS -4.42583062 -36.9385469
OS -4.42999114 -36.94270742
OS -4.4355385 -36.94686794
OS -4.4424727 -36.9524153
OS -4.45079374 -36.95796266
OS -4.46188846 -36.96489686
OS -4.47298318 -36.9732179
OS -4.48685158 -36.9801521
OS -4.50210682 -36.9870863
OS -4.5187489 -36.99540734
OS -4.53677782 -37.00234154
OS -4.55758042 -37.0078889
OS -4.57838302 -37.0148231
OS -4.6019593 -37.01898362
OS -4.62692242 -37.02314414
OS -4.62414874 -37.02453098
OS -4.61860138 -37.02730466
OS -4.61028034 -37.03285202
OS -4.59918562 -37.03839938
OS -4.5742225 -37.05365462
OS -4.56174094 -37.0633625
OS -4.55064622 -37.07168354
OS -4.54787254 -37.07445722
OS -4.54093834 -37.08139142
OS -4.52984362 -37.09248614
OS -4.51597522 -37.10635454
OS -4.50071998 -37.1257703
OS -4.48269106 -37.1465729
OS -4.46466214 -37.17153602
OS -4.44524638 -37.19927282
OS -4.28021242 -37.45999874
OS -4.43831218 -37.45999874
OS -4.56451462 -37.26029378
OS -4.56451462 -37.25890694
OS -4.5672883 -37.25613326
OS -4.57006198 -37.25197274
OS -4.5742225 -37.24642538
OS -4.58393038 -37.23117014
OS -4.59641194 -37.21175438
OS -4.61166718 -37.19095178
OS -4.62692242 -37.16876234
OS -4.64217766 -37.14795974
OS -4.65604606 -37.12854398
OS -4.6574329 -37.12715714
OS -4.66159342 -37.12160978
OS -4.66852762 -37.11328874
OS -4.6782355 -37.10358086
OS -4.6990381 -37.08277826
OS -4.71013282 -37.07307038
OS -4.72122754 -37.06474934
OS -4.72261438 -37.0633625
OS -4.72538806 -37.06197566
OS -4.73093542 -37.05920198
OS -4.73925646 -37.05504146
OS -4.7475775 -37.05088094
OS -4.75728538 -37.04672042
OS -4.77947482 -37.03978622
OS -4.78086166 -37.03978622
OS -4.78363534 -37.03839938
OS -4.7891827 -37.03839938
OS -4.7961169 -37.03701254
OS -4.80582478 -37.0356257
OS -4.8169195 -37.0356257
OS -4.83217474 -37.03423886
OS -4.99582186 -37.03423886
OS -4.99582186 -37.45999874
OS -5.12341114 -37.45999874
OS -5.12341114 -36.50030546
OS -4.6782355 -36.50030546
OS -4.66714078 -36.5016923
OE
OB -1.0100437 -37.45999874 I
OS -1.13208562 -37.45999874
OS -1.13208562 -36.65701838
OS -1.4122273 -37.45999874
OS -1.52594818 -37.45999874
OS -1.80331618 -36.64314998
OS -1.80331618 -37.45999874
OS -1.9253581 -37.45999874
OS -1.9253581 -36.50030546
OS -1.73536102 -36.50030546
OS -1.50791926 -37.1812439
OS -1.50791926 -37.18263074
OS -1.50653242 -37.18540442
OS -1.50514558 -37.18956494
OS -1.5023719 -37.19649914
OS -1.49682454 -37.21314122
OS -1.48989034 -37.23394382
OS -1.48295614 -37.2575201
OS -1.4746351 -37.28109638
OS -1.4677009 -37.30328582
OS -1.46215354 -37.32270158
OS -1.4607667 -37.3199279
OS -1.45937986 -37.3129937
OS -1.45521934 -37.30051214
OS -1.44967198 -37.28387006
OS -1.44273778 -37.26168062
OS -1.4330299 -37.23533066
OS -1.42332202 -37.20482018
OS -1.41084046 -37.16876234
OS -1.18062502 -36.50030546
OS -1.0100437 -36.50030546
OS -1.0100437 -37.45999874
OE
OB -2.02382374 -37.45999874 I
OS -2.1680551 -37.45999874
OS -2.28038914 -37.16876234
OS -2.68257274 -37.16876234
OS -2.78658574 -37.45999874
OS -2.92110922 -37.45999874
OS -2.55498346 -36.50030546
OS -2.41629946 -36.50030546
OS -2.02382374 -37.45999874
OE
OB -3.02928274 -37.45999874 I
OS -3.16103254 -37.45999874
OS -3.66306862 -36.70694462
OS -3.66306862 -37.45999874
OS -3.78511054 -37.45999874
OS -3.78511054 -36.50030546
OS -3.65474758 -36.50030546
OS -3.15132466 -37.25474642
OS -3.15132466 -36.50030546
OS -3.02928274 -36.50030546
OS -3.02928274 -37.45999874
OE
OB -5.3231161 -36.61402634 I
OS -5.89033366 -36.61402634
OS -5.89033366 -36.90664958
OS -5.35917394 -36.90664958
OS -5.35917394 -37.02037046
OS -5.89033366 -37.02037046
OS -5.89033366 -37.34627786
OS -5.30092666 -37.34627786
OS -5.30092666 -37.45999874
OS -6.01792294 -37.45999874
OS -6.01792294 -36.50030546
OS -5.3231161 -36.50030546
OS -5.3231161 -36.61402634
OE
OB -0.10721086 -36.61402634 I
OS -0.67442842 -36.61402634
OS -0.67442842 -36.90664958
OS -0.1432687 -36.90664958
OS -0.1432687 -37.02037046
OS -0.67442842 -37.02037046
OS -0.67442842 -37.34627786
OS -0.08502142 -37.34627786
OS -0.08502142 -37.45999874
OS -0.8020177 -37.45999874
OS -0.8020177 -36.50030546
OS -0.10721086 -36.50030546
OS -0.10721086 -36.61402634
OE
OB -8.43241138 -37.34627786 I
OS -7.95949894 -37.34627786
OS -7.95949894 -37.45999874
OS -8.56000066 -37.45999874
OS -8.56000066 -36.50030546
OS -8.43241138 -36.50030546
OS -8.43241138 -37.34627786
OE
OB -6.51718534 -37.05365462 I
OS -6.51718534 -37.45999874
OS -6.64477462 -37.45999874
OS -6.64477462 -37.05365462
OS -7.0150609 -36.50030546
OS -6.86112166 -36.50030546
OS -6.67251142 -36.79154186
OS -6.67251142 -36.7929287
OS -6.66973774 -36.79570238
OS -6.66696406 -36.7998629
OS -6.66419038 -36.80541026
OS -6.65864302 -36.81234446
OS -6.65309566 -36.8206655
OS -6.6406141 -36.8414681
OS -6.62535886 -36.86643122
OS -6.60871678 -36.89416802
OS -6.59068786 -36.92329166
OS -6.57404578 -36.95380214
OS -6.57404578 -36.9524153
OS -6.57265894 -36.94964162
OS -6.56988526 -36.9454811
OS -6.56572474 -36.93993374
OS -6.56156422 -36.93299954
OS -6.55601686 -36.9246785
OS -6.5435353 -36.9038759
OS -6.52828006 -36.87891278
OS -6.51025114 -36.84978914
OS -6.48944854 -36.81789182
OS -6.4672591 -36.78322082
OS -6.28280938 -36.50030546
OS -6.1344175 -36.50030546
OS -6.51718534 -37.05365462
OE
OB -7.01644774 -37.45999874 I
OS -7.1606791 -37.45999874
OS -7.27301314 -37.16876234
OS -7.67519674 -37.16876234
OS -7.77920974 -37.45999874
OS -7.91373322 -37.45999874
OS -7.54760746 -36.50030546
OS -7.40892346 -36.50030546
OS -7.01644774 -37.45999874
OE
OB -7.48103914 -36.60015794 H
OS -7.48103914 -36.60154478
OS -7.48242598 -36.60431846
OS -7.48242598 -36.60986582
OS -7.48519966 -36.61541318
OS -7.4865865 -36.62512106
OS -7.48936018 -36.63482894
OS -7.49490754 -36.65840522
OS -7.50184174 -36.68614202
OS -7.51154962 -36.7166525
OS -7.5212575 -36.74993666
OS -7.53373906 -36.78460766
OS -7.63775206 -37.06474934
OS -7.3132315 -37.06474934
OS -7.41308398 -36.80124974
OS -7.41308398 -36.7998629
OS -7.41447082 -36.79570238
OS -7.4172445 -36.78876818
OS -7.42001818 -36.78044714
OS -7.4241787 -36.77073926
OS -7.42833922 -36.7582577
OS -7.43249974 -36.7443893
OS -7.4380471 -36.7305209
OS -7.44914182 -36.69862358
OS -7.46023654 -36.66533942
OS -7.47133126 -36.63205526
OS -7.48103914 -36.60015794
OE
OB -4.69349074 -36.60709214 H
OS -4.99582186 -36.60709214
OS -4.99582186 -36.9246785
OS -4.71013282 -36.9246785
OS -4.69349074 -36.92329166
OS -4.67407498 -36.92190482
OS -4.65188554 -36.92051798
OS -4.6296961 -36.9177443
OS -4.60750666 -36.91358378
OS -4.5880909 -36.90803642
OS -4.58531722 -36.90664958
OS -4.57976986 -36.9038759
OS -4.57144882 -36.89971538
OS -4.5603541 -36.89416802
OS -4.54787254 -36.88584698
OS -4.53539098 -36.8761391
OS -4.52290942 -36.86365754
OS -4.51320154 -36.84978914
OS -4.5118147 -36.8484023
OS -4.50904102 -36.84285494
OS -4.5048805 -36.8345339
OS -4.49933314 -36.82343918
OS -4.49517262 -36.81095762
OS -4.4910121 -36.79708922
OS -4.48823842 -36.78044714
OS -4.48685158 -36.76380506
OS -4.48685158 -36.76241822
OS -4.48685158 -36.76103138
OS -4.48823842 -36.75271034
OS -4.48962526 -36.74022878
OS -4.49239894 -36.7235867
OS -4.49933314 -36.70694462
OS -4.50765418 -36.68752886
OS -4.52013574 -36.66949994
OS -4.53677782 -36.65147102
OS -4.5395515 -36.65008418
OS -4.5464857 -36.64453682
OS -4.55758042 -36.63760262
OS -4.57560934 -36.62928158
OS -4.59641194 -36.62096054
OS -4.62414874 -36.61402634
OS -4.65604606 -36.60847898
OS -4.69349074 -36.60709214
OE
OB -2.48841514 -36.60015794 H
OS -2.48841514 -36.60154478
OS -2.48980198 -36.60431846
OS -2.48980198 -36.60986582
OS -2.49257566 -36.61541318
OS -2.4939625 -36.62512106
OS -2.49673618 -36.63482894
OS -2.50228354 -36.65840522
OS -2.50921774 -36.68614202
OS -2.51892562 -36.7166525
OS -2.5286335 -36.74993666
OS -2.54111506 -36.78460766
OS -2.64512806 -37.06474934
OS -2.3206075 -37.06474934
OS -2.42045998 -36.80124974
OS -2.42045998 -36.7998629
OS -2.42184682 -36.79570238
OS -2.4246205 -36.78876818
OS -2.42739418 -36.78044714
OS -2.4315547 -36.77073926
OS -2.43571522 -36.7582577
OS -2.43987574 -36.7443893
OS -2.4454231 -36.7305209
OS -2.45651782 -36.69862358
OS -2.46761254 -36.66533942
OS -2.47870726 -36.63205526
OS -2.48841514 -36.60015794
OE
SE
S P 0
OB 35.73690338 -37.45999874 I
OS 35.61486146 -37.45999874
OS 35.61486146 -36.65701838
OS 35.33471978 -37.45999874
OS 35.2209989 -37.45999874
OS 34.9436309 -36.64314998
OS 34.9436309 -37.45999874
OS 34.82158898 -37.45999874
OS 34.82158898 -36.50030546
OS 35.01158606 -36.50030546
OS 35.23902782 -37.1812439
OS 35.23902782 -37.18263074
OS 35.24041466 -37.18540442
OS 35.2418015 -37.18956494
OS 35.24457518 -37.19649914
OS 35.25012254 -37.21314122
OS 35.25705674 -37.23394382
OS 35.26399094 -37.2575201
OS 35.27231198 -37.28109638
OS 35.27924618 -37.30328582
OS 35.28479354 -37.32270158
OS 35.28618038 -37.3199279
OS 35.28756722 -37.3129937
OS 35.29172774 -37.30051214
OS 35.2972751 -37.28387006
OS 35.3042093 -37.26168062
OS 35.31391718 -37.23533066
OS 35.32362506 -37.20482018
OS 35.33610662 -37.16876234
OS 35.56632206 -36.50030546
OS 35.73690338 -36.50030546
OS 35.73690338 -37.45999874
OE
OB 34.61356298 -37.05504146 I
OS 34.61356298 -37.0564283
OS 34.61356298 -37.06197566
OS 34.61356298 -37.06890986
OS 34.61356298 -37.07861774
OS 34.61217614 -37.0910993
OS 34.61217614 -37.1049677
OS 34.6107893 -37.12160978
OS 34.60940246 -37.13825186
OS 34.60524194 -37.17569654
OS 34.59969458 -37.21452806
OS 34.59137354 -37.25197274
OS 34.58582618 -37.27000166
OS 34.58027882 -37.28664374
OS 34.58027882 -37.28803058
OS 34.57889198 -37.29080426
OS 34.5761183 -37.29496478
OS 34.57334462 -37.30051214
OS 34.56502358 -37.31576738
OS 34.55254202 -37.33518314
OS 34.53589994 -37.35737258
OS 34.51648418 -37.37956202
OS 34.49152106 -37.4031383
OS 34.46101058 -37.4239409
OS 34.45962374 -37.4239409
OS 34.45685006 -37.42671458
OS 34.45268954 -37.42810142
OS 34.44575534 -37.43226194
OS 34.4374343 -37.43642246
OS 34.42633958 -37.44058298
OS 34.41524486 -37.4447435
OS 34.40137646 -37.45029086
OS 34.38612122 -37.45583822
OS 34.36947914 -37.45999874
OS 34.35145022 -37.46415926
OS 34.33064762 -37.46831978
OS 34.30984502 -37.47109346
OS 34.28765558 -37.47386714
OS 34.23772934 -37.47664082
OS 34.22524778 -37.47664082
OS 34.2155399 -37.47525398
OS 34.20444518 -37.47525398
OS 34.19057678 -37.47386714
OS 34.17532154 -37.4724803
OS 34.1600663 -37.47109346
OS 34.1253953 -37.4655461
OS 34.08795062 -37.45722506
OS 34.05189278 -37.44613034
OS 34.01722178 -37.4308751
OS 34.01583494 -37.4308751
OS 34.01306126 -37.42810142
OS 34.00890074 -37.42532774
OS 34.00335338 -37.42255406
OS 33.98809814 -37.41145934
OS 33.97006922 -37.3962041
OS 33.94926662 -37.37678834
OS 33.92985086 -37.3545989
OS 33.9104351 -37.3268621
OS 33.89517986 -37.29635162
OS 33.89517986 -37.29496478
OS 33.89379302 -37.2921911
OS 33.89240618 -37.28664374
OS 33.8896325 -37.27970954
OS 33.88685882 -37.2713885
OS 33.88408514 -37.26029378
OS 33.87992462 -37.24781222
OS 33.87715094 -37.23255698
OS 33.87437726 -37.2159149
OS 33.87021674 -37.19788598
OS 33.86744306 -37.17847022
OS 33.86466938 -37.15766762
OS 33.8618957 -37.13409134
OS 33.86050886 -37.10912822
OS 33.85912202 -37.08277826
OS 33.85912202 -37.05504146
OS 33.85912202 -36.50030546
OS 33.9867113 -36.50030546
OS 33.9867113 -37.05504146
OS 33.9867113 -37.0564283
OS 33.9867113 -37.06058882
OS 33.9867113 -37.06752302
OS 33.9867113 -37.07584406
OS 33.98809814 -37.08555194
OS 33.98809814 -37.0980335
OS 33.98948498 -37.12438346
OS 33.99225866 -37.15489394
OS 33.99641918 -37.18540442
OS 34.00196654 -37.21452806
OS 34.00474022 -37.22700962
OS 34.00890074 -37.23949118
OS 34.01028758 -37.24226486
OS 34.01306126 -37.24919906
OS 34.01999546 -37.25890694
OS 34.0283165 -37.27277534
OS 34.03802438 -37.28664374
OS 34.05189278 -37.30189898
OS 34.06853486 -37.31715422
OS 34.08795062 -37.32963578
OS 34.0907243 -37.33102262
OS 34.0976585 -37.33518314
OS 34.11014006 -37.33934366
OS 34.12678214 -37.34489102
OS 34.1461979 -37.35182522
OS 34.17116102 -37.35598574
OS 34.19751098 -37.36014626
OS 34.22663462 -37.3615331
OS 34.24050302 -37.3615331
OS 34.24882406 -37.36014626
OS 34.26130562 -37.36014626
OS 34.27378718 -37.35875942
OS 34.30429766 -37.35321206
OS 34.33758182 -37.34627786
OS 34.36947914 -37.33518314
OS 34.39998962 -37.3199279
OS 34.41385802 -37.31022002
OS 34.42633958 -37.2991253
OS 34.42772642 -37.29773846
OS 34.42911326 -37.29635162
OS 34.43188694 -37.2921911
OS 34.43604746 -37.28664374
OS 34.44020798 -37.2783227
OS 34.44575534 -37.27000166
OS 34.4513027 -37.2575201
OS 34.45685006 -37.24503854
OS 34.46239742 -37.2297833
OS 34.46655794 -37.21175438
OS 34.4721053 -37.19095178
OS 34.47626582 -37.16876234
OS 34.48042634 -37.14379922
OS 34.48320002 -37.11744926
OS 34.4859737 -37.08693878
OS 34.4859737 -37.05504146
OS 34.4859737 -36.50030546
OS 34.61356298 -36.50030546
OS 34.61356298 -37.05504146
OE
OB 33.64416182 -37.45999874 I
OS 33.51241202 -37.45999874
OS 33.01037594 -36.70694462
OS 33.01037594 -37.45999874
OS 32.88833402 -37.45999874
OS 32.88833402 -36.50030546
OS 33.01869698 -36.50030546
OS 33.5221199 -37.25474642
OS 33.5221199 -36.50030546
OS 33.64416182 -36.50030546
OS 33.64416182 -37.45999874
OE
OB 38.19022334 -36.5016923 I
OS 38.2027049 -36.5016923
OS 38.23182854 -36.50307914
OS 38.26233902 -36.50723966
OS 38.29562318 -36.51140018
OS 38.32613366 -36.51833438
OS 38.3413889 -36.5224949
OS 38.35387046 -36.52665542
OS 38.3552573 -36.52665542
OS 38.35664414 -36.52804226
OS 38.36496518 -36.53220278
OS 38.37744674 -36.53775014
OS 38.39270198 -36.54745802
OS 38.40934406 -36.55993958
OS 38.42737298 -36.57658166
OS 38.44401506 -36.59599742
OS 38.46065714 -36.61818686
OS 38.46065714 -36.6195737
OS 38.46204398 -36.62096054
OS 38.46759134 -36.62928158
OS 38.4731387 -36.64314998
OS 38.48145974 -36.6611789
OS 38.48839394 -36.6819815
OS 38.49532814 -36.70694462
OS 38.49948866 -36.73329458
OS 38.5008755 -36.76241822
OS 38.5008755 -36.76380506
OS 38.5008755 -36.76657874
OS 38.5008755 -36.7721261
OS 38.49948866 -36.7790603
OS 38.49948866 -36.78876818
OS 38.49810182 -36.79847606
OS 38.49255446 -36.82205234
OS 38.48423342 -36.84978914
OS 38.4731387 -36.87891278
OS 38.45649662 -36.90803642
OS 38.4454019 -36.92190482
OS 38.43430718 -36.93577322
OS 38.43292034 -36.93716006
OS 38.4315335 -36.9385469
OS 38.42737298 -36.94270742
OS 38.42182562 -36.94686794
OS 38.41489142 -36.9524153
OS 38.40657038 -36.95796266
OS 38.39547566 -36.96489686
OS 38.38438094 -36.9732179
OS 38.37051254 -36.9801521
OS 38.3552573 -36.9870863
OS 38.33861522 -36.99540734
OS 38.3205863 -37.00234154
OS 38.2997837 -37.0078889
OS 38.2789811 -37.0148231
OS 38.25540482 -37.01898362
OS 38.2304417 -37.02314414
OS 38.23321538 -37.02453098
OS 38.23876274 -37.02730466
OS 38.24708378 -37.03285202
OS 38.2581785 -37.03839938
OS 38.28314162 -37.05365462
OS 38.29562318 -37.0633625
OS 38.3067179 -37.07168354
OS 38.30949158 -37.07445722
OS 38.31642578 -37.08139142
OS 38.3275205 -37.09248614
OS 38.3413889 -37.10635454
OS 38.35664414 -37.1257703
OS 38.37467306 -37.1465729
OS 38.39270198 -37.17153602
OS 38.41211774 -37.19927282
OS 38.5771517 -37.45999874
OS 38.41905194 -37.45999874
OS 38.2928495 -37.26029378
OS 38.2928495 -37.25890694
OS 38.29007582 -37.25613326
OS 38.28730214 -37.25197274
OS 38.28314162 -37.24642538
OS 38.27343374 -37.23117014
OS 38.26095218 -37.21175438
OS 38.24569694 -37.19095178
OS 38.2304417 -37.16876234
OS 38.21518646 -37.14795974
OS 38.20131806 -37.12854398
OS 38.19993122 -37.12715714
OS 38.1957707 -37.12160978
OS 38.1888365 -37.11328874
OS 38.17912862 -37.10358086
OS 38.15832602 -37.08277826
OS 38.1472313 -37.07307038
OS 38.13613658 -37.06474934
OS 38.13474974 -37.0633625
OS 38.13197606 -37.06197566
OS 38.1264287 -37.05920198
OS 38.11810766 -37.05504146
OS 38.10978662 -37.05088094
OS 38.10007874 -37.04672042
OS 38.0778893 -37.03978622
OS 38.07650246 -37.03978622
OS 38.07372878 -37.03839938
OS 38.06818142 -37.03839938
OS 38.06124722 -37.03701254
OS 38.05153934 -37.0356257
OS 38.04044462 -37.0356257
OS 38.02518938 -37.03423886
OS 37.86154226 -37.03423886
OS 37.86154226 -37.45999874
OS 37.73395298 -37.45999874
OS 37.73395298 -36.50030546
OS 38.17912862 -36.50030546
OS 38.19022334 -36.5016923
OE
OB 37.53424802 -36.61402634 I
OS 36.96703046 -36.61402634
OS 36.96703046 -36.90664958
OS 37.49819018 -36.90664958
OS 37.49819018 -37.02037046
OS 36.96703046 -37.02037046
OS 36.96703046 -37.34627786
OS 37.55643746 -37.34627786
OS 37.55643746 -37.45999874
OS 36.83944118 -37.45999874
OS 36.83944118 -36.50030546
OS 37.53424802 -36.50030546
OS 37.53424802 -36.61402634
OE
OB 36.32492354 -36.5016923 I
OS 36.33601826 -36.5016923
OS 36.36098138 -36.50446598
OS 36.38871818 -36.50723966
OS 36.41784182 -36.51278702
OS 36.44696546 -36.51972122
OS 36.47331542 -36.5294291
OS 36.47470226 -36.5294291
OS 36.4760891 -36.53081594
OS 36.48441014 -36.53497646
OS 36.4968917 -36.54191066
OS 36.5107601 -36.55161854
OS 36.52740218 -36.5641001
OS 36.5454311 -36.57935534
OS 36.56207318 -36.5987711
OS 36.57732842 -36.6195737
OS 36.57871526 -36.62234738
OS 36.58287578 -36.63066842
OS 36.58980998 -36.64176314
OS 36.59674418 -36.65840522
OS 36.60367838 -36.67782098
OS 36.61061258 -36.69862358
OS 36.6147731 -36.72219986
OS 36.61615994 -36.74577614
OS 36.61615994 -36.74854982
OS 36.61615994 -36.75548402
OS 36.6147731 -36.76796558
OS 36.61199942 -36.78322082
OS 36.6078389 -36.80124974
OS 36.6009047 -36.8206655
OS 36.59258366 -36.84008126
OS 36.58148894 -36.86088386
OS 36.5801021 -36.86365754
OS 36.57594158 -36.8692049
OS 36.56762054 -36.88029962
OS 36.55652582 -36.89139434
OS 36.54265742 -36.90526274
OS 36.52601534 -36.92051798
OS 36.50521274 -36.93438638
OS 36.48163646 -36.94825478
OS 36.4830233 -36.94825478
OS 36.48579698 -36.94964162
OS 36.4899575 -36.95102846
OS 36.49550486 -36.95380214
OS 36.51214694 -36.9593495
OS 36.5315627 -36.96905738
OS 36.5523653 -36.98153894
OS 36.57594158 -36.99679418
OS 36.59674418 -37.0148231
OS 36.61615994 -37.03701254
OS 36.61754678 -37.03978622
OS 36.62309414 -37.04810726
OS 36.63141518 -37.06058882
OS 36.63973622 -37.0772309
OS 36.64805726 -37.09942034
OS 36.6563783 -37.12299662
OS 36.66192566 -37.15073342
OS 36.6633125 -37.1812439
OS 36.6633125 -37.18263074
OS 36.6633125 -37.18401758
OS 36.6633125 -37.19233862
OS 36.66192566 -37.20620702
OS 36.65915198 -37.2228491
OS 36.6563783 -37.24226486
OS 36.65083094 -37.26306746
OS 36.64389674 -37.2852569
OS 36.63418886 -37.30744634
OS 36.63280202 -37.31022002
OS 36.6286415 -37.31715422
OS 36.62309414 -37.3268621
OS 36.6147731 -37.3407305
OS 36.60367838 -37.3545989
OS 36.59258366 -37.36985414
OS 36.57871526 -37.38510938
OS 36.56346002 -37.39759094
OS 36.56207318 -37.39897778
OS 36.55652582 -37.4031383
OS 36.54681794 -37.40868566
OS 36.53433638 -37.41423302
OS 36.51908114 -37.42255406
OS 36.50105222 -37.4308751
OS 36.48163646 -37.4378093
OS 36.45806018 -37.4447435
OS 36.4552865 -37.4447435
OS 36.44696546 -37.44751718
OS 36.43309706 -37.44890402
OS 36.41506814 -37.4516777
OS 36.3928787 -37.45445138
OS 36.36652874 -37.45722506
OS 36.3374051 -37.4586119
OS 36.30412094 -37.45999874
OS 35.93799518 -37.45999874
OS 35.93799518 -36.50030546
OS 36.31521566 -36.50030546
OS 36.32492354 -36.5016923
OE
OB 32.3849111 -36.61402634 I
OS 32.06871158 -36.61402634
OS 32.06871158 -37.45999874
OS 31.9411223 -37.45999874
OS 31.9411223 -36.61402634
OS 31.62492278 -36.61402634
OS 31.62492278 -36.50030546
OS 32.3849111 -36.50030546
OS 32.3849111 -36.61402634
OE
OB 30.62639798 -37.45999874 I
OS 30.48216662 -37.45999874
OS 30.36983258 -37.16876234
OS 29.96764898 -37.16876234
OS 29.86363598 -37.45999874
OS 29.7291125 -37.45999874
OS 30.09523826 -36.50030546
OS 30.23392226 -36.50030546
OS 30.62639798 -37.45999874
OE
OB 29.3546657 -36.5016923 I
OS 29.37824198 -36.50307914
OS 29.4032051 -36.50446598
OS 29.42678138 -36.50723966
OS 29.44758398 -36.51001334
OS 29.45035766 -36.51001334
OS 29.46006554 -36.51278702
OS 29.4725471 -36.5155607
OS 29.48918918 -36.51972122
OS 29.5072181 -36.52665542
OS 29.52663386 -36.53497646
OS 29.54743646 -36.54468434
OS 29.56546538 -36.55577906
OS 29.56823906 -36.5571659
OS 29.57378642 -36.56132642
OS 29.58210746 -36.56964746
OS 29.59320218 -36.57935534
OS 29.60568374 -36.5918369
OS 29.6181653 -36.60847898
OS 29.6320337 -36.6265079
OS 29.64312842 -36.6473105
OS 29.64451526 -36.65008418
OS 29.64728894 -36.65701838
OS 29.6528363 -36.66949994
OS 29.65838366 -36.68614202
OS 29.66254418 -36.70555778
OS 29.66809154 -36.72774722
OS 29.67086522 -36.75271034
OS 29.67225206 -36.7790603
OS 29.67225206 -36.78044714
OS 29.67225206 -36.78460766
OS 29.67225206 -36.79015502
OS 29.67086522 -36.7998629
OS 29.66947838 -36.80957078
OS 29.66809154 -36.82205234
OS 29.66531786 -36.83592074
OS 29.66254418 -36.85117598
OS 29.6528363 -36.8830733
OS 29.64728894 -36.89971538
OS 29.6389679 -36.9177443
OS 29.62926002 -36.93577322
OS 29.61955214 -36.9524153
OS 29.60707058 -36.96905738
OS 29.59320218 -36.98569946
OS 29.59181534 -36.9870863
OS 29.58904166 -36.98985998
OS 29.58488114 -36.9940205
OS 29.57794694 -36.99818102
OS 29.5696259 -37.00511522
OS 29.55853118 -37.01204942
OS 29.54466278 -37.02037046
OS 29.52940754 -37.02730466
OS 29.51137862 -37.0356257
OS 29.49057602 -37.04394674
OS 29.46838658 -37.05088094
OS 29.44203662 -37.0564283
OS 29.41429982 -37.06197566
OS 29.38378934 -37.06613618
OS 29.34911834 -37.06890986
OS 29.3130605 -37.0702967
OS 29.06758982 -37.0702967
OS 29.06758982 -37.45999874
OS 28.94000054 -37.45999874
OS 28.94000054 -36.50030546
OS 29.3338631 -36.50030546
OS 29.3546657 -36.5016923
OE
OB 31.18668134 -36.5016923 I
OS 31.1991629 -36.5016923
OS 31.22828654 -36.50307914
OS 31.25879702 -36.50723966
OS 31.29208118 -36.51140018
OS 31.32259166 -36.51833438
OS 31.3378469 -36.5224949
OS 31.35032846 -36.52665542
OS 31.3517153 -36.52665542
OS 31.35310214 -36.52804226
OS 31.36142318 -36.53220278
OS 31.37390474 -36.53775014
OS 31.38915998 -36.54745802
OS 31.40580206 -36.55993958
OS 31.42383098 -36.57658166
OS 31.44047306 -36.59599742
OS 31.45711514 -36.61818686
OS 31.45711514 -36.6195737
OS 31.45850198 -36.62096054
OS 31.46404934 -36.62928158
OS 31.4695967 -36.64314998
OS 31.47791774 -36.6611789
OS 31.48485194 -36.6819815
OS 31.49178614 -36.70694462
OS 31.49594666 -36.73329458
OS 31.4973335 -36.76241822
OS 31.4973335 -36.76380506
OS 31.4973335 -36.76657874
OS 31.4973335 -36.7721261
OS 31.49594666 -36.7790603
OS 31.49594666 -36.78876818
OS 31.49455982 -36.79847606
OS 31.48901246 -36.82205234
OS 31.48069142 -36.84978914
OS 31.4695967 -36.87891278
OS 31.45295462 -36.90803642
OS 31.4418599 -36.92190482
OS 31.43076518 -36.93577322
OS 31.42937834 -36.93716006
OS 31.4279915 -36.9385469
OS 31.42383098 -36.94270742
OS 31.41828362 -36.94686794
OS 31.41134942 -36.9524153
OS 31.40302838 -36.95796266
OS 31.39193366 -36.96489686
OS 31.38083894 -36.9732179
OS 31.36697054 -36.9801521
OS 31.3517153 -36.9870863
OS 31.33507322 -36.99540734
OS 31.3170443 -37.00234154
OS 31.2962417 -37.0078889
OS 31.2754391 -37.0148231
OS 31.25186282 -37.01898362
OS 31.2268997 -37.02314414
OS 31.22967338 -37.02453098
OS 31.23522074 -37.02730466
OS 31.24354178 -37.03285202
OS 31.2546365 -37.03839938
OS 31.27959962 -37.05365462
OS 31.29208118 -37.0633625
OS 31.3031759 -37.07168354
OS 31.30594958 -37.07445722
OS 31.31288378 -37.08139142
OS 31.3239785 -37.09248614
OS 31.3378469 -37.10635454
OS 31.35310214 -37.1257703
OS 31.37113106 -37.1465729
OS 31.38915998 -37.17153602
OS 31.40857574 -37.19927282
OS 31.5736097 -37.45999874
OS 31.41550994 -37.45999874
OS 31.2893075 -37.26029378
OS 31.2893075 -37.25890694
OS 31.28653382 -37.25613326
OS 31.28376014 -37.25197274
OS 31.27959962 -37.24642538
OS 31.26989174 -37.23117014
OS 31.25741018 -37.21175438
OS 31.24215494 -37.19095178
OS 31.2268997 -37.16876234
OS 31.21164446 -37.14795974
OS 31.19777606 -37.12854398
OS 31.19638922 -37.12715714
OS 31.1922287 -37.12160978
OS 31.1852945 -37.11328874
OS 31.17558662 -37.10358086
OS 31.15478402 -37.08277826
OS 31.1436893 -37.07307038
OS 31.13259458 -37.06474934
OS 31.13120774 -37.0633625
OS 31.12843406 -37.06197566
OS 31.1228867 -37.05920198
OS 31.11456566 -37.05504146
OS 31.10624462 -37.05088094
OS 31.09653674 -37.04672042
OS 31.0743473 -37.03978622
OS 31.07296046 -37.03978622
OS 31.07018678 -37.03839938
OS 31.06463942 -37.03839938
OS 31.05770522 -37.03701254
OS 31.04799734 -37.0356257
OS 31.03690262 -37.0356257
OS 31.02164738 -37.03423886
OS 30.85800026 -37.03423886
OS 30.85800026 -37.45999874
OS 30.73041098 -37.45999874
OS 30.73041098 -36.50030546
OS 31.17558662 -36.50030546
OS 31.18668134 -36.5016923
OE
OB 38.16387338 -36.60709214 H
OS 37.86154226 -36.60709214
OS 37.86154226 -36.9246785
OS 38.1472313 -36.9246785
OS 38.16387338 -36.92329166
OS 38.18328914 -36.92190482
OS 38.20547858 -36.92051798
OS 38.22766802 -36.9177443
OS 38.24985746 -36.91358378
OS 38.26927322 -36.90803642
OS 38.2720469 -36.90664958
OS 38.27759426 -36.9038759
OS 38.2859153 -36.89971538
OS 38.29701002 -36.89416802
OS 38.30949158 -36.88584698
OS 38.32197314 -36.8761391
OS 38.3344547 -36.86365754
OS 38.34416258 -36.84978914
OS 38.34554942 -36.8484023
OS 38.3483231 -36.84285494
OS 38.35248362 -36.8345339
OS 38.35803098 -36.82343918
OS 38.3621915 -36.81095762
OS 38.36635202 -36.79708922
OS 38.3691257 -36.78044714
OS 38.37051254 -36.76380506
OS 38.37051254 -36.76241822
OS 38.37051254 -36.76103138
OS 38.3691257 -36.75271034
OS 38.36773886 -36.74022878
OS 38.36496518 -36.7235867
OS 38.35803098 -36.70694462
OS 38.34970994 -36.68752886
OS 38.33722838 -36.66949994
OS 38.3205863 -36.65147102
OS 38.31781262 -36.65008418
OS 38.31087842 -36.64453682
OS 38.2997837 -36.63760262
OS 38.28175478 -36.62928158
OS 38.26095218 -36.62096054
OS 38.23321538 -36.61402634
OS 38.20131806 -36.60847898
OS 38.16387338 -36.60709214
OE
OB 29.34218414 -36.61402634 H
OS 29.06758982 -36.61402634
OS 29.06758982 -36.95657582
OS 29.32554206 -36.95657582
OS 29.33524994 -36.95518898
OS 29.34495782 -36.95518898
OS 29.35605254 -36.95380214
OS 29.3824025 -36.95102846
OS 29.41152614 -36.9454811
OS 29.44064978 -36.93716006
OS 29.46699974 -36.92606534
OS 29.4794813 -36.91913114
OS 29.48918918 -36.9108101
OS 29.49196286 -36.90803642
OS 29.49751022 -36.90248906
OS 29.50583126 -36.89139434
OS 29.51553914 -36.87752594
OS 29.52524702 -36.85949702
OS 29.53356806 -36.83730758
OS 29.53911542 -36.81234446
OS 29.5418891 -36.78322082
OS 29.5418891 -36.78183398
OS 29.5418891 -36.78044714
OS 29.5418891 -36.77351294
OS 29.54050226 -36.76103138
OS 29.53772858 -36.74716298
OS 29.5349549 -36.73190774
OS 29.52940754 -36.71387882
OS 29.5210865 -36.69723674
OS 29.51137862 -36.68059466
OS 29.50999178 -36.67920782
OS 29.50583126 -36.67366046
OS 29.49889706 -36.66672626
OS 29.49057602 -36.65701838
OS 29.47809446 -36.6473105
OS 29.46422606 -36.63898946
OS 29.44897082 -36.63066842
OS 29.4309419 -36.62373422
OS 29.42955506 -36.62373422
OS 29.4240077 -36.62234738
OS 29.41568666 -36.62096054
OS 29.40459194 -36.61818686
OS 29.38794986 -36.61680002
OS 29.36714726 -36.61541318
OS 29.34218414 -36.61402634
OE
OB 30.16180658 -36.60015794 H
OS 30.16180658 -36.60154478
OS 30.16041974 -36.60431846
OS 30.16041974 -36.60986582
OS 30.15764606 -36.61541318
OS 30.15625922 -36.62512106
OS 30.15348554 -36.63482894
OS 30.14793818 -36.65840522
OS 30.14100398 -36.68614202
OS 30.1312961 -36.7166525
OS 30.12158822 -36.74993666
OS 30.10910666 -36.78460766
OS 30.00509366 -37.06474934
OS 30.32961422 -37.06474934
OS 30.22976174 -36.80124974
OS 30.22976174 -36.7998629
OS 30.2283749 -36.79570238
OS 30.22560122 -36.78876818
OS 30.22282754 -36.78044714
OS 30.21866702 -36.77073926
OS 30.2145065 -36.7582577
OS 30.21034598 -36.7443893
OS 30.20479862 -36.7305209
OS 30.1937039 -36.69862358
OS 30.18260918 -36.66533942
OS 30.17151446 -36.63205526
OS 30.16180658 -36.60015794
OE
OB 31.16033138 -36.60709214 H
OS 30.85800026 -36.60709214
OS 30.85800026 -36.9246785
OS 31.1436893 -36.9246785
OS 31.16033138 -36.92329166
OS 31.17974714 -36.92190482
OS 31.20193658 -36.92051798
OS 31.22412602 -36.9177443
OS 31.24631546 -36.91358378
OS 31.26573122 -36.90803642
OS 31.2685049 -36.90664958
OS 31.27405226 -36.9038759
OS 31.2823733 -36.89971538
OS 31.29346802 -36.89416802
OS 31.30594958 -36.88584698
OS 31.31843114 -36.8761391
OS 31.3309127 -36.86365754
OS 31.34062058 -36.84978914
OS 31.34200742 -36.8484023
OS 31.3447811 -36.84285494
OS 31.34894162 -36.8345339
OS 31.35448898 -36.82343918
OS 31.3586495 -36.81095762
OS 31.36281002 -36.79708922
OS 31.3655837 -36.78044714
OS 31.36697054 -36.76380506
OS 31.36697054 -36.76241822
OS 31.36697054 -36.76103138
OS 31.3655837 -36.75271034
OS 31.36419686 -36.74022878
OS 31.36142318 -36.7235867
OS 31.35448898 -36.70694462
OS 31.34616794 -36.68752886
OS 31.33368638 -36.66949994
OS 31.3170443 -36.65147102
OS 31.31427062 -36.65008418
OS 31.30733642 -36.64453682
OS 31.2962417 -36.63760262
OS 31.27821278 -36.62928158
OS 31.25741018 -36.62096054
OS 31.22967338 -36.61402634
OS 31.19777606 -36.60847898
OS 31.16033138 -36.60709214
OE
OB 36.29302622 -36.61402634 H
OS 36.06558446 -36.61402634
OS 36.06558446 -36.90248906
OS 36.30134726 -36.90248906
OS 36.31937618 -36.90110222
OS 36.33879194 -36.89971538
OS 36.3582077 -36.89832854
OS 36.37762346 -36.89555486
OS 36.3928787 -36.89278118
OS 36.39565238 -36.89139434
OS 36.40119974 -36.8900075
OS 36.40952078 -36.88584698
OS 36.4206155 -36.88029962
OS 36.43171022 -36.87475226
OS 36.44419178 -36.86643122
OS 36.45667334 -36.8553365
OS 36.46638122 -36.84424178
OS 36.46776806 -36.84285494
OS 36.47054174 -36.83869442
OS 36.47470226 -36.83037338
OS 36.47886278 -36.8206655
OS 36.4830233 -36.80957078
OS 36.48718382 -36.79570238
OS 36.4899575 -36.7790603
OS 36.49134434 -36.76103138
OS 36.49134434 -36.7582577
OS 36.49134434 -36.75271034
OS 36.4899575 -36.7443893
OS 36.48857066 -36.73329458
OS 36.48579698 -36.71942618
OS 36.48163646 -36.70555778
OS 36.4760891 -36.69168938
OS 36.46776806 -36.67782098
OS 36.46638122 -36.67643414
OS 36.46360754 -36.67227362
OS 36.45806018 -36.66533942
OS 36.45112598 -36.65840522
OS 36.4414181 -36.65008418
OS 36.43032338 -36.64176314
OS 36.41645498 -36.6334421
OS 36.40119974 -36.62789474
OS 36.3998129 -36.62789474
OS 36.3928787 -36.62512106
OS 36.38317082 -36.62373422
OS 36.36791558 -36.62096054
OS 36.34711298 -36.61818686
OS 36.3235367 -36.61680002
OS 36.29302622 -36.61402634
OE
OB 36.31798934 -37.01620994 H
OS 36.06558446 -37.01620994
OS 36.06558446 -37.34627786
OS 36.33879194 -37.34627786
OS 36.36791558 -37.34489102
OS 36.38039714 -37.34350418
OS 36.39149186 -37.34211734
OS 36.3928787 -37.34211734
OS 36.39842606 -37.3407305
OS 36.4067471 -37.33934366
OS 36.41645498 -37.33656998
OS 36.44003126 -37.32824894
OS 36.46360754 -37.31715422
OS 36.46499438 -37.31576738
OS 36.4691549 -37.3129937
OS 36.47470226 -37.30883318
OS 36.48163646 -37.30328582
OS 36.48857066 -37.29496478
OS 36.49827854 -37.28664374
OS 36.50521274 -37.27554902
OS 36.51353378 -37.26306746
OS 36.51492062 -37.26168062
OS 36.51630746 -37.2575201
OS 36.51908114 -37.24919906
OS 36.52324166 -37.23949118
OS 36.52740218 -37.22839646
OS 36.53017586 -37.21452806
OS 36.5315627 -37.19788598
OS 36.53294954 -37.1812439
OS 36.53294954 -37.17847022
OS 36.53294954 -37.17292286
OS 36.5315627 -37.16182814
OS 36.52878902 -37.14934658
OS 36.52601534 -37.13547818
OS 36.52046798 -37.12022294
OS 36.51353378 -37.1049677
OS 36.5038259 -37.08971246
OS 36.50243906 -37.08832562
OS 36.49827854 -37.08277826
OS 36.49273118 -37.07584406
OS 36.48441014 -37.06752302
OS 36.47331542 -37.05781514
OS 36.45944702 -37.04810726
OS 36.44419178 -37.03978622
OS 36.42616286 -37.03285202
OS 36.42338918 -37.03146518
OS 36.41784182 -37.03007834
OS 36.40536026 -37.02730466
OS 36.39010502 -37.02453098
OS 36.37068926 -37.0217573
OS 36.34711298 -37.01898362
OS 36.31798934 -37.01620994
OE
SE
S P 0
OB 40.9056459 -38.32112732 I
OS 40.92136342 -38.32205188
OS 40.9380055 -38.32297644
OS 40.95372302 -38.32482556
OS 40.96759142 -38.32667468
OS 40.96944054 -38.32667468
OS 40.97591246 -38.3285238
OS 40.9842335 -38.33037292
OS 40.99532822 -38.3331466
OS 41.0073475 -38.3377694
OS 41.02029134 -38.34331676
OS 41.03415974 -38.34978868
OS 41.04617902 -38.35718516
OS 41.04802814 -38.35810972
OS 41.05172638 -38.3608834
OS 41.05727374 -38.36643076
OS 41.06467022 -38.37290268
OS 41.07299126 -38.38122372
OS 41.0813123 -38.39231844
OS 41.0905579 -38.40433772
OS 41.09795438 -38.41820612
OS 41.09887894 -38.42005524
OS 41.10072806 -38.42467804
OS 41.1044263 -38.43299908
OS 41.10812454 -38.4440938
OS 41.11089822 -38.45703764
OS 41.11459646 -38.4718306
OS 41.11644558 -38.48847268
OS 41.11737014 -38.50603932
OS 41.11737014 -38.50696388
OS 41.11737014 -38.50973756
OS 41.11737014 -38.5134358
OS 41.11644558 -38.51990772
OS 41.11552102 -38.52637964
OS 41.11459646 -38.53470068
OS 41.11274734 -38.54394628
OS 41.11089822 -38.55411644
OS 41.1044263 -38.57538132
OS 41.10072806 -38.58647604
OS 41.0951807 -38.59849532
OS 41.08870878 -38.6105146
OS 41.08223686 -38.62160932
OS 41.07391582 -38.63270404
OS 41.06467022 -38.64379876
OS 41.06374566 -38.64472332
OS 41.06189654 -38.64657244
OS 41.05912286 -38.64934612
OS 41.05450006 -38.6521198
OS 41.0489527 -38.6567426
OS 41.04155622 -38.6613654
OS 41.03231062 -38.66691276
OS 41.02214046 -38.67153556
OS 41.01012118 -38.67708292
OS 40.99625278 -38.68263028
OS 40.98145982 -38.68725308
OS 40.96389318 -38.69095132
OS 40.94540198 -38.69464956
OS 40.92506166 -38.69742324
OS 40.90194766 -38.69927236
OS 40.8779091 -38.70019692
OS 40.71426198 -38.70019692
OS 40.71426198 -38.95999828
OS 40.62920246 -38.95999828
OS 40.62920246 -38.32020276
OS 40.8917775 -38.32020276
OS 40.9056459 -38.32112732
OE
OB 40.49791494 -38.98403684 I
OS 40.49791494 -38.9849614
OS 40.49791494 -38.98773508
OS 40.49791494 -38.99235788
OS 40.49791494 -38.99790524
OS 40.49699038 -39.00530172
OS 40.49699038 -39.0126982
OS 40.49514126 -39.0311894
OS 40.49236758 -39.05060516
OS 40.48866934 -39.07094548
OS 40.48312198 -39.08851212
OS 40.47942374 -39.09683316
OS 40.4757255 -39.10330508
OS 40.4757255 -39.10422964
OS 40.47480094 -39.1051542
OS 40.47017814 -39.109777
OS 40.46278166 -39.11717348
OS 40.45353606 -39.12549452
OS 40.44059222 -39.13381556
OS 40.42395014 -39.14028748
OS 40.40453438 -39.14583484
OS 40.39343966 -39.1467594
OS 40.38142038 -39.14768396
OS 40.37587302 -39.14768396
OS 40.37032566 -39.1467594
OS 40.36200462 -39.1467594
OS 40.35275902 -39.14583484
OS 40.34258886 -39.14398572
OS 40.32039942 -39.13843836
OS 40.33519238 -39.07187004
OS 40.33611694 -39.07187004
OS 40.33889062 -39.0727946
OS 40.34351342 -39.07371916
OS 40.34813622 -39.07464372
OS 40.3601555 -39.0774174
OS 40.36570286 -39.07834196
OS 40.37494846 -39.07834196
OS 40.37957126 -39.0774174
OS 40.38511862 -39.07649284
OS 40.39066598 -39.07464372
OS 40.39621334 -39.07094548
OS 40.40268526 -39.06724724
OS 40.40730806 -39.06169988
OS 40.40823262 -39.06077532
OS 40.40915718 -39.05800164
OS 40.4110063 -39.05337884
OS 40.41377998 -39.04598236
OS 40.4156291 -39.0358122
OS 40.41655366 -39.02841572
OS 40.41747822 -39.0219438
OS 40.41840278 -39.01362276
OS 40.41840278 -39.0034526
OS 40.41932734 -38.99328244
OS 40.41932734 -38.98218772
OS 40.41932734 -38.49586916
OS 40.49791494 -38.49586916
OS 40.49791494 -38.98403684
OE
OB 41.51770462 -38.3100326 I
OS 41.52602566 -38.31095716
OS 41.53619582 -38.31188172
OS 41.54636598 -38.31280628
OS 41.55838526 -38.31557996
OS 41.58334838 -38.32112732
OS 41.61108518 -38.32944836
OS 41.62495358 -38.33499572
OS 41.63789742 -38.34146764
OS 41.65084126 -38.34978868
OS 41.6637851 -38.35810972
OS 41.66470966 -38.35903428
OS 41.66655878 -38.35995884
OS 41.67025702 -38.36273252
OS 41.67487982 -38.36735532
OS 41.67950262 -38.37197812
OS 41.68597454 -38.37845004
OS 41.69244646 -38.38584652
OS 41.69984294 -38.393243
OS 41.70723942 -38.4024886
OS 41.7146359 -38.41358332
OS 41.72295694 -38.42467804
OS 41.73035342 -38.43669732
OS 41.73682534 -38.45056572
OS 41.74422182 -38.46443412
OS 41.74976918 -38.47922708
OS 41.75531654 -38.49586916
OS 41.67210614 -38.51528492
OS 41.67210614 -38.51436036
OS 41.67118158 -38.51251124
OS 41.66933246 -38.508813
OS 41.66748334 -38.5041902
OS 41.66563422 -38.49864284
OS 41.66286054 -38.49124636
OS 41.65546406 -38.4764534
OS 41.64621846 -38.45981132
OS 41.63512374 -38.44316924
OS 41.62125534 -38.42745172
OS 41.60646238 -38.41358332
OS 41.60461326 -38.4117342
OS 41.5990659 -38.40803596
OS 41.5898203 -38.40341316
OS 41.57780102 -38.39694124
OS 41.5620835 -38.39139388
OS 41.54451686 -38.38584652
OS 41.52325198 -38.38214828
OS 41.50013798 -38.38122372
OS 41.4927415 -38.38122372
OS 41.4881187 -38.38214828
OS 41.48164678 -38.38214828
OS 41.4742503 -38.38307284
OS 41.45668366 -38.38584652
OS 41.4372679 -38.38954476
OS 41.41692758 -38.39601668
OS 41.3956627 -38.40526228
OS 41.37624694 -38.41728156
OS 41.37532238 -38.41728156
OS 41.37439782 -38.41913068
OS 41.3679259 -38.42375348
OS 41.35960486 -38.43114996
OS 41.3494347 -38.44224468
OS 41.33741542 -38.45611308
OS 41.3263207 -38.4718306
OS 41.31615054 -38.49124636
OS 41.30690494 -38.51251124
OS 41.30690494 -38.5134358
OS 41.30598038 -38.51528492
OS 41.30505582 -38.5180586
OS 41.30413126 -38.5226814
OS 41.30228214 -38.52822876
OS 41.30043302 -38.53470068
OS 41.29765934 -38.5504182
OS 41.2939611 -38.5689094
OS 41.29026286 -38.58924972
OS 41.28841374 -38.61143916
OS 41.28748918 -38.63547772
OS 41.28748918 -38.63640228
OS 41.28748918 -38.63917596
OS 41.28748918 -38.64379876
OS 41.28748918 -38.64934612
OS 41.28841374 -38.65581804
OS 41.28841374 -38.66413908
OS 41.2893383 -38.67338468
OS 41.29026286 -38.68355484
OS 41.29303654 -38.70574428
OS 41.29765934 -38.72978284
OS 41.3032067 -38.7538214
OS 41.31060318 -38.77785996
OS 41.31060318 -38.77878452
OS 41.31152774 -38.78063364
OS 41.31337686 -38.78340732
OS 41.31522598 -38.78803012
OS 41.32077334 -38.79912484
OS 41.32909438 -38.81206868
OS 41.33926454 -38.82686164
OS 41.35220838 -38.84257916
OS 41.36700134 -38.85644756
OS 41.38456798 -38.8693914
OS 41.38549254 -38.8693914
OS 41.38734166 -38.87031596
OS 41.39011534 -38.87216508
OS 41.39381358 -38.8740142
OS 41.39843638 -38.87586332
OS 41.40398374 -38.878637
OS 41.41692758 -38.88418436
OS 41.43356966 -38.88973172
OS 41.45206086 -38.89435452
OS 41.47240118 -38.89805276
OS 41.49366606 -38.89897732
OS 41.50013798 -38.89897732
OS 41.50568534 -38.89805276
OS 41.51215726 -38.89805276
OS 41.51862918 -38.8971282
OS 41.53527126 -38.89342996
OS 41.55468702 -38.88880716
OS 41.57410278 -38.88141068
OS 41.5944431 -38.87124052
OS 41.60461326 -38.86569316
OS 41.61385886 -38.85829668
OS 41.61478342 -38.85737212
OS 41.61570798 -38.85644756
OS 41.61848166 -38.85367388
OS 41.6221799 -38.8509002
OS 41.62587814 -38.8462774
OS 41.63050094 -38.84073004
OS 41.6360483 -38.83518268
OS 41.6406711 -38.8277862
OS 41.64621846 -38.81946516
OS 41.65269038 -38.81021956
OS 41.65823774 -38.80097396
OS 41.6637851 -38.78987924
OS 41.6684079 -38.77785996
OS 41.6730307 -38.76491612
OS 41.6776535 -38.75104772
OS 41.68135174 -38.73625476
OS 41.76641126 -38.75751964
OS 41.76641126 -38.7584442
OS 41.7654867 -38.76214244
OS 41.76363758 -38.7676898
OS 41.7608639 -38.77508628
OS 41.75809022 -38.78340732
OS 41.75439198 -38.79357748
OS 41.74976918 -38.8046722
OS 41.74422182 -38.81669148
OS 41.73127798 -38.84257916
OS 41.7146359 -38.86846684
OS 41.70446574 -38.88141068
OS 41.69429558 -38.89435452
OS 41.68320086 -38.90544924
OS 41.67025702 -38.91654396
OS 41.66933246 -38.91746852
OS 41.66748334 -38.91931764
OS 41.66286054 -38.92116676
OS 41.65823774 -38.924865
OS 41.65084126 -38.9294878
OS 41.64344478 -38.9341106
OS 41.63327462 -38.9387334
OS 41.62310446 -38.9433562
OS 41.61108518 -38.94890356
OS 41.59814134 -38.95352636
OS 41.58427294 -38.95814916
OS 41.56947998 -38.96277196
OS 41.55376246 -38.9664702
OS 41.53712038 -38.96831932
OS 41.51955374 -38.97016844
OS 41.50106254 -38.971093
OS 41.49089238 -38.971093
OS 41.4834959 -38.97016844
OS 41.47517486 -38.97016844
OS 41.4650047 -38.96924388
OS 41.45390998 -38.96739476
OS 41.44096614 -38.96554564
OS 41.4141539 -38.96092284
OS 41.3864171 -38.95352636
OS 41.3586803 -38.9433562
OS 41.34573646 -38.93688428
OS 41.33279262 -38.9294878
OS 41.33186806 -38.92856324
OS 41.33001894 -38.92763868
OS 41.3263207 -38.924865
OS 41.32262246 -38.92116676
OS 41.3170751 -38.91746852
OS 41.31060318 -38.91192116
OS 41.3032067 -38.90544924
OS 41.29581022 -38.89805276
OS 41.28841374 -38.88973172
OS 41.2800927 -38.88141068
OS 41.26345062 -38.8601458
OS 41.2477331 -38.83518268
OS 41.2338647 -38.80744588
OS 41.2338647 -38.80652132
OS 41.23201558 -38.80374764
OS 41.23109102 -38.79912484
OS 41.22831734 -38.79357748
OS 41.22646822 -38.786181
OS 41.22369454 -38.7769354
OS 41.2199963 -38.76676524
OS 41.21722262 -38.75567052
OS 41.21444894 -38.74365124
OS 41.2107507 -38.72978284
OS 41.2061279 -38.70112148
OS 41.20242966 -38.66876188
OS 41.20058054 -38.63547772
OS 41.20058054 -38.63455316
OS 41.20058054 -38.63085492
OS 41.20058054 -38.62530756
OS 41.2015051 -38.61883564
OS 41.2015051 -38.60959004
OS 41.20242966 -38.60034444
OS 41.20335422 -38.58832516
OS 41.20520334 -38.57630588
OS 41.20982614 -38.54949364
OS 41.21629806 -38.51990772
OS 41.22554366 -38.4903218
OS 41.2384875 -38.46166044
OS 41.23941206 -38.46073588
OS 41.24033662 -38.4579622
OS 41.24218574 -38.45426396
OS 41.24588398 -38.44964116
OS 41.24958222 -38.44316924
OS 41.25420502 -38.43577276
OS 41.2662243 -38.41913068
OS 41.28194182 -38.40063948
OS 41.30043302 -38.38214828
OS 41.3216979 -38.36365708
OS 41.34666102 -38.34793956
OS 41.34758558 -38.347015
OS 41.35035926 -38.34609044
OS 41.3540575 -38.34424132
OS 41.3586803 -38.34146764
OS 41.36607678 -38.33869396
OS 41.37347326 -38.33592028
OS 41.38271886 -38.33222204
OS 41.39288902 -38.3285238
OS 41.40398374 -38.32482556
OS 41.41600302 -38.32112732
OS 41.4418907 -38.31557996
OS 41.47147662 -38.31095716
OS 41.5019871 -38.30910804
OS 41.5112327 -38.30910804
OS 41.51770462 -38.3100326
OE
OB 42.90454462 -39.1375138 I
OS 42.38401734 -39.1375138
OS 42.38401734 -39.08111564
OS 42.90454462 -39.08111564
OS 42.90454462 -39.1375138
OE
OB 42.12514054 -38.32112732 I
OS 42.13253702 -38.32112732
OS 42.1491791 -38.32297644
OS 42.1676703 -38.32482556
OS 42.18708606 -38.3285238
OS 42.20650182 -38.3331466
OS 42.22406846 -38.33961852
OS 42.22499302 -38.33961852
OS 42.22591758 -38.34054308
OS 42.23146494 -38.34331676
OS 42.23978598 -38.34793956
OS 42.24903158 -38.35441148
OS 42.2601263 -38.36273252
OS 42.27214558 -38.37290268
OS 42.2832403 -38.38584652
OS 42.29341046 -38.39971492
OS 42.29433502 -38.40156404
OS 42.2971087 -38.4071114
OS 42.3017315 -38.41450788
OS 42.3063543 -38.4256026
OS 42.3109771 -38.43854644
OS 42.3155999 -38.45241484
OS 42.31837358 -38.46813236
OS 42.31929814 -38.48384988
OS 42.31929814 -38.485699
OS 42.31929814 -38.4903218
OS 42.31837358 -38.49864284
OS 42.31652446 -38.508813
OS 42.31375078 -38.52083228
OS 42.30912798 -38.53377612
OS 42.30358062 -38.54671996
OS 42.29618414 -38.56058836
OS 42.29525958 -38.56243748
OS 42.2924859 -38.56613572
OS 42.28693854 -38.5735322
OS 42.27954206 -38.58092868
OS 42.27029646 -38.59017428
OS 42.25920174 -38.60034444
OS 42.24533334 -38.60959004
OS 42.22961582 -38.61883564
OS 42.23054038 -38.61883564
OS 42.2323895 -38.6197602
OS 42.23516318 -38.62068476
OS 42.23886142 -38.62253388
OS 42.24995614 -38.62623212
OS 42.26289998 -38.63270404
OS 42.27676838 -38.64102508
OS 42.2924859 -38.65119524
OS 42.3063543 -38.66321452
OS 42.31929814 -38.67800748
OS 42.3202227 -38.6798566
OS 42.32392094 -38.68540396
OS 42.3294683 -38.693725
OS 42.33501566 -38.70481972
OS 42.34056302 -38.71961268
OS 42.34611038 -38.7353302
OS 42.34980862 -38.7538214
OS 42.35073318 -38.77416172
OS 42.35073318 -38.77508628
OS 42.35073318 -38.77601084
OS 42.35073318 -38.7815582
OS 42.34980862 -38.7908038
OS 42.3479595 -38.80189852
OS 42.34611038 -38.81484236
OS 42.34241214 -38.82871076
OS 42.33778934 -38.84350372
OS 42.33131742 -38.85829668
OS 42.33039286 -38.8601458
OS 42.32761918 -38.8647686
OS 42.32392094 -38.87124052
OS 42.31837358 -38.88048612
OS 42.3109771 -38.88973172
OS 42.30358062 -38.89990188
OS 42.29433502 -38.91007204
OS 42.28416486 -38.91839308
OS 42.2832403 -38.91931764
OS 42.27954206 -38.92209132
OS 42.27307014 -38.92578956
OS 42.2647491 -38.9294878
OS 42.25457894 -38.93503516
OS 42.24255966 -38.94058252
OS 42.22961582 -38.94520532
OS 42.2138983 -38.94982812
OS 42.21204918 -38.94982812
OS 42.20650182 -38.95167724
OS 42.19725622 -38.9526018
OS 42.18523694 -38.95445092
OS 42.17044398 -38.95630004
OS 42.15287734 -38.95814916
OS 42.13346158 -38.95907372
OS 42.11127214 -38.95999828
OS 41.8671883 -38.95999828
OS 41.8671883 -38.32020276
OS 42.11866862 -38.32020276
OS 42.12514054 -38.32112732
OE
OB 40.30745558 -38.48662356 I
OS 40.31762574 -38.48847268
OS 40.32964502 -38.49217092
OS 40.34258886 -38.49679372
OS 40.35738182 -38.50326564
OS 40.37309934 -38.51158668
OS 40.34443798 -38.58370236
OS 40.34351342 -38.5827778
OS 40.33981518 -38.58092868
OS 40.33426782 -38.578155
OS 40.32687134 -38.57538132
OS 40.3185503 -38.57260764
OS 40.30838014 -38.56983396
OS 40.29820998 -38.56798484
OS 40.28803982 -38.56706028
OS 40.28341702 -38.56706028
OS 40.27879422 -38.56798484
OS 40.2723223 -38.5689094
OS 40.26585038 -38.57075852
OS 40.25752934 -38.5735322
OS 40.2492083 -38.57723044
OS 40.24181182 -38.5827778
OS 40.24088726 -38.58370236
OS 40.23811358 -38.58555148
OS 40.2353399 -38.58924972
OS 40.2307171 -38.59387252
OS 40.2260943 -38.60034444
OS 40.2214715 -38.60774092
OS 40.2168487 -38.61606196
OS 40.21315046 -38.62623212
OS 40.2122259 -38.62808124
OS 40.21130134 -38.6336286
OS 40.20945222 -38.64194964
OS 40.20667854 -38.65304436
OS 40.20390486 -38.66691276
OS 40.20205574 -38.68263028
OS 40.20113118 -38.69927236
OS 40.20020662 -38.71776356
OS 40.20020662 -38.95999828
OS 40.12161902 -38.95999828
OS 40.12161902 -38.49586916
OS 40.19281014 -38.49586916
OS 40.19281014 -38.56613572
OS 40.1937347 -38.56521116
OS 40.19743294 -38.55873924
OS 40.20205574 -38.5504182
OS 40.20945222 -38.54024804
OS 40.2168487 -38.53007788
OS 40.22516974 -38.51898316
OS 40.23349078 -38.50973756
OS 40.24181182 -38.50234108
OS 40.24273638 -38.50141652
OS 40.24551006 -38.4995674
OS 40.25105742 -38.49679372
OS 40.25660478 -38.49402004
OS 40.26400126 -38.49124636
OS 40.27324686 -38.48847268
OS 40.28249246 -38.48662356
OS 40.29266262 -38.485699
OS 40.29913454 -38.485699
OS 40.30745558 -38.48662356
OE
OB 39.48829542 -38.95999828 I
OS 39.3986131 -38.95999828
OS 39.3986131 -38.87031596
OS 39.48829542 -38.87031596
OS 39.48829542 -38.95999828
OE
OB 38.6404739 -38.95999828 I
OS 38.55171614 -38.95999828
OS 38.30393406 -38.32020276
OS 38.39639006 -38.32020276
OS 38.56281086 -38.78525644
OS 38.56281086 -38.786181
OS 38.56373542 -38.78803012
OS 38.56465998 -38.7908038
OS 38.5665091 -38.79450204
OS 38.56743366 -38.8000494
OS 38.56928278 -38.80559676
OS 38.57390558 -38.81946516
OS 38.57945294 -38.83518268
OS 38.5850003 -38.85274932
OS 38.59609502 -38.88973172
OS 38.59609502 -38.88880716
OS 38.59701958 -38.88695804
OS 38.59794414 -38.88418436
OS 38.5988687 -38.88048612
OS 38.60164238 -38.87031596
OS 38.60626518 -38.85644756
OS 38.61088798 -38.84073004
OS 38.61643534 -38.8231634
OS 38.62290726 -38.8046722
OS 38.63030374 -38.78525644
OS 38.80412102 -38.32020276
OS 38.8901051 -38.32020276
OS 38.6404739 -38.95999828
OE
OB 39.27564662 -38.42745172 I
OS 39.25438174 -38.54671996
OS 39.20538006 -38.54671996
OS 39.1859643 -38.42745172
OS 39.1859643 -38.32020276
OS 39.27564662 -38.32020276
OS 39.27564662 -38.42745172
OE
OB 40.49791494 -38.4117342 I
OS 40.41932734 -38.4117342
OS 40.41932734 -38.32020276
OS 40.49791494 -38.32020276
OS 40.49791494 -38.4117342
OE
OB 39.84517558 -38.48662356 I
OS 39.8516475 -38.48754812
OS 39.8655159 -38.48939724
OS 39.88215798 -38.49309548
OS 39.89972462 -38.49864284
OS 39.91729126 -38.50696388
OS 39.9348579 -38.51713404
OS 39.93578246 -38.51713404
OS 39.93670702 -38.51898316
OS 39.94225438 -38.5226814
OS 39.95057542 -38.53007788
OS 39.96074558 -38.53932348
OS 39.9718403 -38.55134276
OS 39.98293502 -38.56613572
OS 39.99402974 -38.58370236
OS 40.00327534 -38.60311812
OS 40.00327534 -38.60404268
OS 40.0041999 -38.6058918
OS 40.00512446 -38.60866548
OS 40.00697358 -38.61236372
OS 40.0088227 -38.61791108
OS 40.01067182 -38.624383
OS 40.01529462 -38.63917596
OS 40.01991742 -38.65766716
OS 40.02361566 -38.67800748
OS 40.02638934 -38.70112148
OS 40.0273139 -38.72516004
OS 40.0273139 -38.7260846
OS 40.0273139 -38.72793372
OS 40.0273139 -38.73163196
OS 40.0273139 -38.73717932
OS 40.02638934 -38.74365124
OS 40.02638934 -38.75104772
OS 40.02454022 -38.7676898
OS 40.02084198 -38.78803012
OS 40.01621918 -38.809295
OS 40.00974726 -38.83148444
OS 40.00142622 -38.85367388
OS 40.00142622 -38.85459844
OS 40.00050166 -38.85644756
OS 39.99865254 -38.85922124
OS 39.99680342 -38.86291948
OS 39.9903315 -38.87308964
OS 39.98201046 -38.88603348
OS 39.9718403 -38.89990188
OS 39.95889646 -38.91377028
OS 39.9441035 -38.92763868
OS 39.92653686 -38.94058252
OS 39.9256123 -38.94058252
OS 39.92468774 -38.94150708
OS 39.92191406 -38.9433562
OS 39.91821582 -38.94520532
OS 39.90897022 -38.94982812
OS 39.89602638 -38.95537548
OS 39.88030886 -38.96092284
OS 39.86366678 -38.96554564
OS 39.84425102 -38.96924388
OS 39.82483526 -38.97016844
OS 39.81836334 -38.97016844
OS 39.81096686 -38.96924388
OS 39.80172126 -38.96831932
OS 39.79062654 -38.9664702
OS 39.77860726 -38.96369652
OS 39.76658798 -38.95999828
OS 39.7545687 -38.95445092
OS 39.75364414 -38.95352636
OS 39.74902134 -38.95167724
OS 39.74347398 -38.947979
OS 39.7360775 -38.94243164
OS 39.72868102 -38.93688428
OS 39.71943542 -38.9294878
OS 39.71111438 -38.92116676
OS 39.7037179 -38.91192116
OS 39.7037179 -39.1375138
OS 39.6251303 -39.1375138
OS 39.6251303 -38.49586916
OS 39.69632142 -38.49586916
OS 39.69632142 -38.55689012
OS 39.69724598 -38.555041
OS 39.70094422 -38.55134276
OS 39.70556702 -38.54487084
OS 39.7129635 -38.53747436
OS 39.72128454 -38.52822876
OS 39.73053014 -38.51990772
OS 39.74162486 -38.51158668
OS 39.75271958 -38.5041902
OS 39.7545687 -38.50326564
OS 39.75826694 -38.50141652
OS 39.76566342 -38.49864284
OS 39.77490902 -38.4949446
OS 39.78600374 -38.49124636
OS 39.79894758 -38.48847268
OS 39.81374054 -38.48662356
OS 39.83038262 -38.485699
OS 39.84055278 -38.485699
OS 39.84517558 -38.48662356
OE
OB 44.92193454 -38.40988508 I
OS 44.84334694 -38.40988508
OS 44.84334694 -38.32020276
OS 44.92193454 -38.32020276
OS 44.92193454 -38.40988508
OE
OB 45.24553054 -38.48662356 I
OS 45.25385158 -38.48754812
OS 45.26309718 -38.48939724
OS 45.27326734 -38.49124636
OS 45.28528662 -38.49309548
OS 45.31024974 -38.50141652
OS 45.32319358 -38.50603932
OS 45.33613742 -38.51251124
OS 45.34908126 -38.51898316
OS 45.3620251 -38.52822876
OS 45.37404438 -38.53747436
OS 45.38606366 -38.54856908
OS 45.38698822 -38.54949364
OS 45.38883734 -38.55134276
OS 45.39161102 -38.555041
OS 45.39530926 -38.5596638
OS 45.39993206 -38.56613572
OS 45.40547942 -38.57445676
OS 45.41102678 -38.58370236
OS 45.41657414 -38.59387252
OS 45.4221215 -38.60496724
OS 45.42766886 -38.61883564
OS 45.43321622 -38.63270404
OS 45.43783902 -38.64842156
OS 45.44153726 -38.66506364
OS 45.44431094 -38.68263028
OS 45.44616006 -38.70112148
OS 45.44708462 -38.7214618
OS 45.44708462 -38.72238636
OS 45.44708462 -38.72516004
OS 45.44708462 -38.72978284
OS 45.44708462 -38.73625476
OS 45.44616006 -38.74365124
OS 45.4452355 -38.75289684
OS 45.4452355 -38.76214244
OS 45.44338638 -38.7723126
OS 45.4406127 -38.7954266
OS 45.43506534 -38.8185406
OS 45.42859342 -38.8416546
OS 45.41934782 -38.86291948
OS 45.41934782 -38.86384404
OS 45.41842326 -38.8647686
OS 45.41657414 -38.86754228
OS 45.41472502 -38.87124052
OS 45.4082531 -38.88048612
OS 45.39993206 -38.89158084
OS 45.38883734 -38.90452468
OS 45.37496894 -38.91746852
OS 45.35925142 -38.93041236
OS 45.34076022 -38.94243164
OS 45.33983566 -38.94243164
OS 45.3389111 -38.9433562
OS 45.33613742 -38.94520532
OS 45.33151462 -38.94705444
OS 45.32689182 -38.94890356
OS 45.32134446 -38.95075268
OS 45.30747606 -38.95630004
OS 45.29175854 -38.96092284
OS 45.27234278 -38.96554564
OS 45.25200246 -38.96924388
OS 45.22981302 -38.97016844
OS 45.22056742 -38.97016844
OS 45.21317094 -38.96924388
OS 45.2048499 -38.96831932
OS 45.1956043 -38.9664702
OS 45.18450958 -38.96462108
OS 45.17341486 -38.96277196
OS 45.14845174 -38.95537548
OS 45.13458334 -38.94982812
OS 45.1216395 -38.94428076
OS 45.10869566 -38.93688428
OS 45.09575182 -38.92856324
OS 45.08373254 -38.91931764
OS 45.07171326 -38.90822292
OS 45.0707887 -38.90729836
OS 45.06893958 -38.90544924
OS 45.0661659 -38.901751
OS 45.06246766 -38.89620364
OS 45.05784486 -38.88973172
OS 45.05322206 -38.88233524
OS 45.0476747 -38.87308964
OS 45.04212734 -38.86199492
OS 45.03657998 -38.84997564
OS 45.03103262 -38.83610724
OS 45.02640982 -38.82131428
OS 45.02178702 -38.80559676
OS 45.01808878 -38.78803012
OS 45.0153151 -38.76953892
OS 45.01346598 -38.7491986
OS 45.01254142 -38.72793372
OS 45.01254142 -38.7260846
OS 45.01254142 -38.72238636
OS 45.01346598 -38.71591444
OS 45.01346598 -38.70666884
OS 45.01439054 -38.69649868
OS 45.01623966 -38.68355484
OS 45.01808878 -38.670611
OS 45.02178702 -38.65581804
OS 45.02548526 -38.64102508
OS 45.03010806 -38.62530756
OS 45.03565542 -38.60866548
OS 45.0430519 -38.59294796
OS 45.05044838 -38.578155
OS 45.06061854 -38.56336204
OS 45.0707887 -38.54949364
OS 45.08373254 -38.53747436
OS 45.0846571 -38.5365498
OS 45.08650622 -38.53562524
OS 45.09020446 -38.53285156
OS 45.09482726 -38.52915332
OS 45.10037462 -38.52545508
OS 45.1077711 -38.52083228
OS 45.11516758 -38.51620948
OS 45.12441318 -38.51158668
OS 45.13458334 -38.50696388
OS 45.14567806 -38.50234108
OS 45.17064118 -38.49402004
OS 45.19930254 -38.48754812
OS 45.2140955 -38.48662356
OS 45.22981302 -38.485699
OS 45.23905862 -38.485699
OS 45.24553054 -38.48662356
OE
OB 44.92193454 -38.95999828 I
OS 44.84334694 -38.95999828
OS 44.84334694 -38.49586916
OS 44.92193454 -38.49586916
OS 44.92193454 -38.95999828
OE
OB 46.10722046 -38.42745172 I
OS 46.08595558 -38.54671996
OS 46.0369539 -38.54671996
OS 46.01753814 -38.42745172
OS 46.01753814 -38.32020276
OS 46.10722046 -38.32020276
OS 46.10722046 -38.42745172
OE
OB 45.77160518 -38.48662356 I
OS 45.78177534 -38.48754812
OS 45.79379462 -38.48939724
OS 45.80673846 -38.49217092
OS 45.82060686 -38.49586916
OS 45.8335507 -38.50141652
OS 45.83539982 -38.50234108
OS 45.83909806 -38.5041902
OS 45.84556998 -38.50696388
OS 45.85296646 -38.51158668
OS 45.86221206 -38.51713404
OS 45.8705331 -38.52453052
OS 45.87885414 -38.531927
OS 45.88625062 -38.5411726
OS 45.88717518 -38.54209716
OS 45.8890243 -38.5457954
OS 45.89179798 -38.5504182
OS 45.89642078 -38.55689012
OS 45.90011902 -38.56613572
OS 45.90381726 -38.57538132
OS 45.90844006 -38.58647604
OS 45.91121374 -38.59849532
OS 45.91121374 -38.59941988
OS 45.9121383 -38.60311812
OS 45.91306286 -38.60866548
OS 45.91398742 -38.61606196
OS 45.91398742 -38.62715668
OS 45.91491198 -38.64010052
OS 45.91583654 -38.65581804
OS 45.91583654 -38.6752338
OS 45.91583654 -38.95999828
OS 45.83724894 -38.95999828
OS 45.83724894 -38.67893204
OS 45.83724894 -38.67800748
OS 45.83724894 -38.67708292
OS 45.83724894 -38.670611
OS 45.83724894 -38.66228996
OS 45.83632438 -38.6521198
OS 45.83539982 -38.64010052
OS 45.8335507 -38.62808124
OS 45.83077702 -38.61698652
OS 45.82800334 -38.60681636
OS 45.82800334 -38.6058918
OS 45.82615422 -38.60311812
OS 45.82338054 -38.59849532
OS 45.82060686 -38.59294796
OS 45.81598406 -38.5874006
OS 45.8104367 -38.58092868
OS 45.80304022 -38.57445676
OS 45.79471918 -38.5689094
OS 45.79379462 -38.56798484
OS 45.79102094 -38.56613572
OS 45.78547358 -38.5642866
OS 45.77900166 -38.56151292
OS 45.77160518 -38.55873924
OS 45.76235958 -38.55596556
OS 45.75126486 -38.555041
OS 45.74017014 -38.55411644
OS 45.73554734 -38.55411644
OS 45.7318491 -38.555041
OS 45.7226035 -38.55596556
OS 45.71058422 -38.55781468
OS 45.69764038 -38.56243748
OS 45.68284742 -38.56798484
OS 45.66805446 -38.57538132
OS 45.65418606 -38.58647604
OS 45.65233694 -38.58832516
OS 45.6486387 -38.59294796
OS 45.64586502 -38.5966462
OS 45.64309134 -38.601269
OS 45.6393931 -38.60681636
OS 45.63661942 -38.61328828
OS 45.63292118 -38.62068476
OS 45.62922294 -38.62993036
OS 45.62644926 -38.64010052
OS 45.62367558 -38.65119524
OS 45.62182646 -38.66321452
OS 45.61997734 -38.67615836
OS 45.61812822 -38.69187588
OS 45.61812822 -38.7075934
OS 45.61812822 -38.95999828
OS 45.53954062 -38.95999828
OS 45.53954062 -38.49586916
OS 45.60980718 -38.49586916
OS 45.60980718 -38.56243748
OS 45.61073174 -38.56151292
OS 45.61258086 -38.55873924
OS 45.61535454 -38.555041
OS 45.61905278 -38.5504182
OS 45.62460014 -38.54487084
OS 45.63107206 -38.53839892
OS 45.63846854 -38.53100244
OS 45.64771414 -38.52360596
OS 45.65695974 -38.51713404
OS 45.66805446 -38.50973756
OS 45.68007374 -38.50326564
OS 45.69301758 -38.49771828
OS 45.70781054 -38.49309548
OS 45.7226035 -38.48939724
OS 45.73924558 -38.48662356
OS 45.75681222 -38.485699
OS 45.7642087 -38.485699
OS 45.77160518 -38.48662356
OE
OB 44.2756671 -38.95999828 I
OS 44.1970795 -38.95999828
OS 44.1970795 -38.49586916
OS 44.2756671 -38.49586916
OS 44.2756671 -38.95999828
OE
OB 43.4574315 -38.48662356 I
OS 43.46482798 -38.48754812
OS 43.47407358 -38.48939724
OS 43.48424374 -38.49124636
OS 43.49626302 -38.49402004
OS 43.50735774 -38.49679372
OS 43.52030158 -38.50141652
OS 43.53232086 -38.50603932
OS 43.5452647 -38.51251124
OS 43.55820854 -38.51990772
OS 43.57115238 -38.52822876
OS 43.58317166 -38.53839892
OS 43.59426638 -38.54949364
OS 43.59519094 -38.5504182
OS 43.59704006 -38.55226732
OS 43.59981374 -38.55596556
OS 43.60351198 -38.56151292
OS 43.60813478 -38.56798484
OS 43.61275758 -38.57538132
OS 43.61830494 -38.58462692
OS 43.6238523 -38.59572164
OS 43.62939966 -38.60774092
OS 43.63494702 -38.62068476
OS 43.63956982 -38.63547772
OS 43.64419262 -38.65119524
OS 43.64789086 -38.66876188
OS 43.65066454 -38.68725308
OS 43.65251366 -38.70666884
OS 43.65343822 -38.72793372
OS 43.65343822 -38.72885828
OS 43.65343822 -38.73255652
OS 43.65343822 -38.73902844
OS 43.65251366 -38.74827404
OS 43.30580366 -38.74827404
OS 43.30580366 -38.7491986
OS 43.30580366 -38.75197228
OS 43.30672822 -38.75567052
OS 43.30672822 -38.76121788
OS 43.30765278 -38.7676898
OS 43.3095019 -38.77508628
OS 43.31227558 -38.79172836
OS 43.31782294 -38.81021956
OS 43.32521942 -38.83055988
OS 43.33538958 -38.84905108
OS 43.34833342 -38.86569316
OS 43.34925798 -38.86569316
OS 43.35018254 -38.86754228
OS 43.3557299 -38.87216508
OS 43.36405094 -38.878637
OS 43.37514566 -38.88510892
OS 43.38993862 -38.8925054
OS 43.4065807 -38.89897732
OS 43.4250719 -38.90360012
OS 43.43524206 -38.90452468
OS 43.44633678 -38.90544924
OS 43.45373326 -38.90544924
OS 43.4620543 -38.90452468
OS 43.47222446 -38.90267556
OS 43.48331918 -38.89990188
OS 43.49626302 -38.89620364
OS 43.5082823 -38.89065628
OS 43.52030158 -38.8832598
OS 43.52122614 -38.88233524
OS 43.52584894 -38.878637
OS 43.5313963 -38.87308964
OS 43.53786822 -38.86569316
OS 43.5452647 -38.855523
OS 43.55358574 -38.84257916
OS 43.56190678 -38.8277862
OS 43.56930326 -38.81021956
OS 43.65066454 -38.82038972
OS 43.65066454 -38.82131428
OS 43.64973998 -38.8231634
OS 43.64881542 -38.82686164
OS 43.6469663 -38.832409
OS 43.64419262 -38.83795636
OS 43.64141894 -38.84535284
OS 43.63402246 -38.86107036
OS 43.62477686 -38.878637
OS 43.61183302 -38.8971282
OS 43.59704006 -38.91469484
OS 43.57854886 -38.93133692
OS 43.5776243 -38.93133692
OS 43.57577518 -38.93318604
OS 43.5730015 -38.93503516
OS 43.56930326 -38.93780884
OS 43.5637559 -38.94058252
OS 43.55820854 -38.9433562
OS 43.55081206 -38.94705444
OS 43.54249102 -38.95075268
OS 43.53324542 -38.95445092
OS 43.52399982 -38.95814916
OS 43.50088582 -38.96369652
OS 43.47499814 -38.96831932
OS 43.44633678 -38.97016844
OS 43.43616662 -38.97016844
OS 43.4296947 -38.96924388
OS 43.42137366 -38.96831932
OS 43.4112035 -38.9664702
OS 43.40010878 -38.96462108
OS 43.3880895 -38.96277196
OS 43.36220182 -38.95537548
OS 43.34833342 -38.94982812
OS 43.33538958 -38.94428076
OS 43.32152118 -38.93688428
OS 43.30857734 -38.92856324
OS 43.29655806 -38.91931764
OS 43.28453878 -38.90822292
OS 43.28361422 -38.90729836
OS 43.2817651 -38.90544924
OS 43.27899142 -38.901751
OS 43.27529318 -38.89620364
OS 43.27067038 -38.88973172
OS 43.26604758 -38.88233524
OS 43.26050022 -38.87308964
OS 43.25495286 -38.86291948
OS 43.2494055 -38.8509002
OS 43.24385814 -38.83795636
OS 43.23923534 -38.8231634
OS 43.23461254 -38.80744588
OS 43.2309143 -38.7908038
OS 43.22814062 -38.7723126
OS 43.2262915 -38.75289684
OS 43.22536694 -38.73255652
OS 43.22536694 -38.73163196
OS 43.22536694 -38.72700916
OS 43.22536694 -38.7214618
OS 43.2262915 -38.71314076
OS 43.22721606 -38.7029706
OS 43.22814062 -38.69187588
OS 43.22998974 -38.67893204
OS 43.23276342 -38.6659882
OS 43.2401599 -38.63640228
OS 43.2447827 -38.62160932
OS 43.25033006 -38.6058918
OS 43.25772654 -38.59109884
OS 43.26604758 -38.57723044
OS 43.27529318 -38.56336204
OS 43.28546334 -38.5504182
OS 43.2863879 -38.54949364
OS 43.28823702 -38.54764452
OS 43.29193526 -38.54487084
OS 43.29655806 -38.54024804
OS 43.30210542 -38.53562524
OS 43.3095019 -38.53007788
OS 43.31782294 -38.52360596
OS 43.3279931 -38.5180586
OS 43.33816326 -38.51158668
OS 43.35018254 -38.50603932
OS 43.36312638 -38.50049196
OS 43.37699478 -38.49586916
OS 43.39178774 -38.49124636
OS 43.40750526 -38.48847268
OS 43.42414734 -38.48662356
OS 43.44171398 -38.485699
OS 43.45095958 -38.485699
OS 43.4574315 -38.48662356
OE
OB 43.13938286 -38.48662356 I
OS 43.14955302 -38.48847268
OS 43.1615723 -38.49217092
OS 43.17451614 -38.49679372
OS 43.1893091 -38.50326564
OS 43.20502662 -38.51158668
OS 43.17636526 -38.58370236
OS 43.1754407 -38.5827778
OS 43.17174246 -38.58092868
OS 43.1661951 -38.578155
OS 43.15879862 -38.57538132
OS 43.15047758 -38.57260764
OS 43.14030742 -38.56983396
OS 43.13013726 -38.56798484
OS 43.1199671 -38.56706028
OS 43.1153443 -38.56706028
OS 43.1107215 -38.56798484
OS 43.10424958 -38.5689094
OS 43.09777766 -38.57075852
OS 43.08945662 -38.5735322
OS 43.08113558 -38.57723044
OS 43.0737391 -38.5827778
OS 43.07281454 -38.58370236
OS 43.07004086 -38.58555148
OS 43.06726718 -38.58924972
OS 43.06264438 -38.59387252
OS 43.05802158 -38.60034444
OS 43.05339878 -38.60774092
OS 43.04877598 -38.61606196
OS 43.04507774 -38.62623212
OS 43.04415318 -38.62808124
OS 43.04322862 -38.6336286
OS 43.0413795 -38.64194964
OS 43.03860582 -38.65304436
OS 43.03583214 -38.66691276
OS 43.03398302 -38.68263028
OS 43.03305846 -38.69927236
OS 43.0321339 -38.71776356
OS 43.0321339 -38.95999828
OS 42.9535463 -38.95999828
OS 42.9535463 -38.49586916
OS 43.02473742 -38.49586916
OS 43.02473742 -38.56613572
OS 43.02566198 -38.56521116
OS 43.02936022 -38.55873924
OS 43.03398302 -38.5504182
OS 43.0413795 -38.54024804
OS 43.04877598 -38.53007788
OS 43.05709702 -38.51898316
OS 43.06541806 -38.50973756
OS 43.0737391 -38.50234108
OS 43.07466366 -38.50141652
OS 43.07743734 -38.4995674
OS 43.0829847 -38.49679372
OS 43.08853206 -38.49402004
OS 43.09592854 -38.49124636
OS 43.10517414 -38.48847268
OS 43.11441974 -38.48662356
OS 43.1245899 -38.485699
OS 43.13106182 -38.485699
OS 43.13938286 -38.48662356
OE
OB 43.95022198 -38.95999828 I
OS 43.87533262 -38.95999828
OS 43.70059078 -38.49586916
OS 43.78380118 -38.49586916
OS 43.88365366 -38.77416172
OS 43.88365366 -38.77508628
OS 43.88457822 -38.77601084
OS 43.88550278 -38.77878452
OS 43.88642734 -38.7815582
OS 43.88920102 -38.7908038
OS 43.89289926 -38.80282308
OS 43.89752206 -38.81669148
OS 43.90306942 -38.832409
OS 43.90769222 -38.84997564
OS 43.91323958 -38.86754228
OS 43.91416414 -38.86569316
OS 43.9150887 -38.86107036
OS 43.91786238 -38.85367388
OS 43.92063606 -38.84257916
OS 43.92525886 -38.83055988
OS 43.92988166 -38.81484236
OS 43.93635358 -38.79820028
OS 43.9428255 -38.77970908
OS 44.04545166 -38.49586916
OS 44.12681294 -38.49586916
OS 43.95022198 -38.95999828
OE
OB 44.2756671 -38.40988508 I
OS 44.1970795 -38.40988508
OS 44.1970795 -38.32020276
OS 44.2756671 -38.32020276
OS 44.2756671 -38.40988508
OE
OB 44.5669035 -38.48662356 I
OS 44.5807719 -38.48754812
OS 44.59556486 -38.48939724
OS 44.61128238 -38.49309548
OS 44.62792446 -38.49679372
OS 44.64364198 -38.50234108
OS 44.64456654 -38.50234108
OS 44.6454911 -38.50326564
OS 44.6501139 -38.50511476
OS 44.65751038 -38.508813
OS 44.66675598 -38.5134358
OS 44.67692614 -38.51990772
OS 44.6870963 -38.5273042
OS 44.6963419 -38.53562524
OS 44.70466294 -38.54487084
OS 44.7055875 -38.5457954
OS 44.70743662 -38.54949364
OS 44.71113486 -38.55596556
OS 44.71575766 -38.56336204
OS 44.72038046 -38.57445676
OS 44.72500326 -38.58647604
OS 44.7287015 -38.60034444
OS 44.73239974 -38.61606196
OS 44.65566126 -38.62623212
OS 44.65566126 -38.624383
OS 44.6547367 -38.62068476
OS 44.65288758 -38.61421284
OS 44.6501139 -38.6058918
OS 44.6454911 -38.59757076
OS 44.63994374 -38.58832516
OS 44.63347182 -38.57907956
OS 44.62422622 -38.57075852
OS 44.62330166 -38.56983396
OS 44.61960342 -38.56798484
OS 44.61405606 -38.5642866
OS 44.60573502 -38.56058836
OS 44.59648942 -38.55689012
OS 44.58447014 -38.55319188
OS 44.56967718 -38.55134276
OS 44.55395966 -38.5504182
OS 44.54471406 -38.5504182
OS 44.53546846 -38.55134276
OS 44.52344918 -38.55226732
OS 44.5114299 -38.555041
OS 44.49848606 -38.55781468
OS 44.48646678 -38.56243748
OS 44.47629662 -38.5689094
OS 44.47537206 -38.56983396
OS 44.47259838 -38.57168308
OS 44.46890014 -38.57538132
OS 44.4652019 -38.58092868
OS 44.4605791 -38.58647604
OS 44.45688086 -38.59387252
OS 44.45410718 -38.60219356
OS 44.45318262 -38.6105146
OS 44.45318262 -38.61143916
OS 44.45318262 -38.61328828
OS 44.45410718 -38.61606196
OS 44.45410718 -38.6197602
OS 44.45688086 -38.6290058
OS 44.46242822 -38.6382514
OS 44.46335278 -38.63917596
OS 44.46427734 -38.64010052
OS 44.46612646 -38.6428742
OS 44.4698247 -38.64564788
OS 44.47352294 -38.64842156
OS 44.4790703 -38.6521198
OS 44.48554222 -38.65489348
OS 44.4929387 -38.65859172
OS 44.49386326 -38.65859172
OS 44.49571238 -38.65951628
OS 44.49941062 -38.66044084
OS 44.50588254 -38.66321452
OS 44.51512814 -38.6659882
OS 44.52714742 -38.66876188
OS 44.5345439 -38.67153556
OS 44.54286494 -38.67338468
OS 44.55211054 -38.67615836
OS 44.5622807 -38.67893204
OS 44.56320526 -38.67893204
OS 44.56597894 -38.6798566
OS 44.57060174 -38.68078116
OS 44.5761491 -38.68263028
OS 44.58262102 -38.6844794
OS 44.59094206 -38.68632852
OS 44.6085087 -38.69187588
OS 44.62792446 -38.69742324
OS 44.64734022 -38.70389516
OS 44.66490686 -38.71036708
OS 44.67230334 -38.71314076
OS 44.67877526 -38.71591444
OS 44.68062438 -38.716839
OS 44.68432262 -38.71868812
OS 44.68986998 -38.7214618
OS 44.69819102 -38.7260846
OS 44.70651206 -38.73163196
OS 44.7148331 -38.73902844
OS 44.72315414 -38.74734948
OS 44.73055062 -38.75659508
OS 44.73147518 -38.75751964
OS 44.7333243 -38.76121788
OS 44.73702254 -38.76676524
OS 44.74072078 -38.77508628
OS 44.74349446 -38.78525644
OS 44.7471927 -38.79635116
OS 44.74904182 -38.809295
OS 44.74996638 -38.82408796
OS 44.74996638 -38.82593708
OS 44.74996638 -38.83055988
OS 44.74904182 -38.83795636
OS 44.7471927 -38.84812652
OS 44.74441902 -38.85922124
OS 44.73979622 -38.87124052
OS 44.73424886 -38.88510892
OS 44.72685238 -38.89805276
OS 44.72592782 -38.89990188
OS 44.72222958 -38.90360012
OS 44.71760678 -38.91007204
OS 44.7102103 -38.91746852
OS 44.70004014 -38.92578956
OS 44.68894542 -38.93503516
OS 44.67600158 -38.9433562
OS 44.66028406 -38.95167724
OS 44.6593595 -38.95167724
OS 44.65843494 -38.9526018
OS 44.65288758 -38.95445092
OS 44.64364198 -38.9572246
OS 44.6316227 -38.96092284
OS 44.61682974 -38.96462108
OS 44.60018766 -38.96739476
OS 44.58262102 -38.96924388
OS 44.5622807 -38.97016844
OS 44.55395966 -38.97016844
OS 44.54748774 -38.96924388
OS 44.54009126 -38.96924388
OS 44.53084566 -38.96831932
OS 44.52160006 -38.96739476
OS 44.5114299 -38.96554564
OS 44.48924046 -38.96092284
OS 44.46612646 -38.95445092
OS 44.44393702 -38.94520532
OS 44.43376686 -38.93965796
OS 44.42452126 -38.93318604
OS 44.4235967 -38.93226148
OS 44.42267214 -38.93133692
OS 44.41712478 -38.92578956
OS 44.40880374 -38.91746852
OS 44.39955814 -38.90452468
OS 44.38938798 -38.88880716
OS 44.37921782 -38.87031596
OS 44.37089678 -38.84720196
OS 44.36442486 -38.82131428
OS 44.4420879 -38.809295
OS 44.4420879 -38.81021956
OS 44.4420879 -38.81114412
OS 44.44393702 -38.81669148
OS 44.44578614 -38.82593708
OS 44.44948438 -38.83610724
OS 44.45410718 -38.84720196
OS 44.45965454 -38.85922124
OS 44.46797558 -38.87124052
OS 44.47814574 -38.88141068
OS 44.47999486 -38.88233524
OS 44.4836931 -38.88510892
OS 44.49108958 -38.88880716
OS 44.50033518 -38.89342996
OS 44.51235446 -38.89805276
OS 44.52622286 -38.901751
OS 44.54286494 -38.90452468
OS 44.5622807 -38.90544924
OS 44.5715263 -38.90544924
OS 44.5807719 -38.90452468
OS 44.59279118 -38.90267556
OS 44.60573502 -38.89990188
OS 44.61960342 -38.89620364
OS 44.6316227 -38.89158084
OS 44.64271742 -38.88418436
OS 44.64364198 -38.8832598
OS 44.64734022 -38.88048612
OS 44.65103846 -38.87586332
OS 44.65658582 -38.8693914
OS 44.66120862 -38.86199492
OS 44.66583142 -38.85274932
OS 44.6686051 -38.84350372
OS 44.66952966 -38.832409
OS 44.66952966 -38.83148444
OS 44.66952966 -38.8277862
OS 44.6686051 -38.8231634
OS 44.66675598 -38.81669148
OS 44.6639823 -38.81021956
OS 44.6593595 -38.80374764
OS 44.65381214 -38.79635116
OS 44.6454911 -38.7908038
OS 44.64456654 -38.78987924
OS 44.64179286 -38.78895468
OS 44.63717006 -38.786181
OS 44.62977358 -38.78340732
OS 44.61867886 -38.77970908
OS 44.61220694 -38.7769354
OS 44.60481046 -38.77508628
OS 44.59648942 -38.7723126
OS 44.58724382 -38.76953892
OS 44.57707366 -38.76676524
OS 44.56505438 -38.76399156
OS 44.56412982 -38.76399156
OS 44.56135614 -38.763067
OS 44.55673334 -38.76214244
OS 44.55118598 -38.76029332
OS 44.5437895 -38.7584442
OS 44.53546846 -38.75567052
OS 44.51790182 -38.75104772
OS 44.4975615 -38.7445758
OS 44.47814574 -38.73902844
OS 44.45965454 -38.73255652
OS 44.4513335 -38.72885828
OS 44.44486158 -38.7260846
OS 44.44301246 -38.72516004
OS 44.43931422 -38.72331092
OS 44.43376686 -38.71961268
OS 44.42637038 -38.71498988
OS 44.41804934 -38.70851796
OS 44.4097283 -38.70112148
OS 44.40140726 -38.69280044
OS 44.39401078 -38.68263028
OS 44.39308622 -38.68170572
OS 44.3912371 -38.67800748
OS 44.38846342 -38.67153556
OS 44.38568974 -38.66413908
OS 44.38291606 -38.65489348
OS 44.38014238 -38.64379876
OS 44.37829326 -38.63270404
OS 44.3773687 -38.6197602
OS 44.3773687 -38.61791108
OS 44.3773687 -38.61421284
OS 44.37829326 -38.60866548
OS 44.37921782 -38.60034444
OS 44.38106694 -38.5920234
OS 44.38291606 -38.58185324
OS 44.3866143 -38.57260764
OS 44.3912371 -38.56243748
OS 44.39216166 -38.56151292
OS 44.39401078 -38.55781468
OS 44.39678446 -38.55319188
OS 44.40140726 -38.54671996
OS 44.40695462 -38.54024804
OS 44.41342654 -38.531927
OS 44.42082302 -38.52453052
OS 44.43006862 -38.5180586
OS 44.43099318 -38.51713404
OS 44.43376686 -38.51620948
OS 44.4374651 -38.5134358
OS 44.44301246 -38.51066212
OS 44.45040894 -38.50696388
OS 44.45872998 -38.50326564
OS 44.46890014 -38.4995674
OS 44.47999486 -38.49586916
OS 44.48184398 -38.4949446
OS 44.48554222 -38.49402004
OS 44.49201414 -38.49217092
OS 44.50033518 -38.4903218
OS 44.51050534 -38.48847268
OS 44.52160006 -38.48754812
OS 44.5345439 -38.485699
OS 44.55673334 -38.485699
OS 44.5669035 -38.48662356
OE
OB 33.15968222 -38.32112732 I
OS 33.17539974 -38.32205188
OS 33.19204182 -38.32297644
OS 33.20775934 -38.32482556
OS 33.22162774 -38.32667468
OS 33.22347686 -38.32667468
OS 33.22994878 -38.3285238
OS 33.23826982 -38.33037292
OS 33.24936454 -38.3331466
OS 33.26138382 -38.3377694
OS 33.27432766 -38.34331676
OS 33.28819606 -38.34978868
OS 33.30021534 -38.35718516
OS 33.30206446 -38.35810972
OS 33.3057627 -38.3608834
OS 33.31131006 -38.36643076
OS 33.31870654 -38.37290268
OS 33.32702758 -38.38122372
OS 33.33534862 -38.39231844
OS 33.34459422 -38.40433772
OS 33.3519907 -38.41820612
OS 33.35291526 -38.42005524
OS 33.35476438 -38.42467804
OS 33.35846262 -38.43299908
OS 33.36216086 -38.4440938
OS 33.36493454 -38.45703764
OS 33.36863278 -38.4718306
OS 33.3704819 -38.48847268
OS 33.37140646 -38.50603932
OS 33.37140646 -38.50696388
OS 33.37140646 -38.50973756
OS 33.37140646 -38.5134358
OS 33.3704819 -38.51990772
OS 33.36955734 -38.52637964
OS 33.36863278 -38.53470068
OS 33.36678366 -38.54394628
OS 33.36493454 -38.55411644
OS 33.35846262 -38.57538132
OS 33.35476438 -38.58647604
OS 33.34921702 -38.59849532
OS 33.3427451 -38.6105146
OS 33.33627318 -38.62160932
OS 33.32795214 -38.63270404
OS 33.31870654 -38.64379876
OS 33.31778198 -38.64472332
OS 33.31593286 -38.64657244
OS 33.31315918 -38.64934612
OS 33.30853638 -38.6521198
OS 33.30298902 -38.6567426
OS 33.29559254 -38.6613654
OS 33.28634694 -38.66691276
OS 33.27617678 -38.67153556
OS 33.2641575 -38.67708292
OS 33.2502891 -38.68263028
OS 33.23549614 -38.68725308
OS 33.2179295 -38.69095132
OS 33.1994383 -38.69464956
OS 33.17909798 -38.69742324
OS 33.15598398 -38.69927236
OS 33.13194542 -38.70019692
OS 32.9682983 -38.70019692
OS 32.9682983 -38.95999828
OS 32.88323878 -38.95999828
OS 32.88323878 -38.32020276
OS 33.14581382 -38.32020276
OS 33.15968222 -38.32112732
OE
OB 32.75195126 -38.98403684 I
OS 32.75195126 -38.9849614
OS 32.75195126 -38.98773508
OS 32.75195126 -38.99235788
OS 32.75195126 -38.99790524
OS 32.7510267 -39.00530172
OS 32.7510267 -39.0126982
OS 32.74917758 -39.0311894
OS 32.7464039 -39.05060516
OS 32.74270566 -39.07094548
OS 32.7371583 -39.08851212
OS 32.73346006 -39.09683316
OS 32.72976182 -39.10330508
OS 32.72976182 -39.10422964
OS 32.72883726 -39.1051542
OS 32.72421446 -39.109777
OS 32.71681798 -39.11717348
OS 32.70757238 -39.12549452
OS 32.69462854 -39.13381556
OS 32.67798646 -39.14028748
OS 32.6585707 -39.14583484
OS 32.64747598 -39.1467594
OS 32.6354567 -39.14768396
OS 32.62990934 -39.14768396
OS 32.62436198 -39.1467594
OS 32.61604094 -39.1467594
OS 32.60679534 -39.14583484
OS 32.59662518 -39.14398572
OS 32.57443574 -39.13843836
OS 32.5892287 -39.07187004
OS 32.59015326 -39.07187004
OS 32.59292694 -39.0727946
OS 32.59754974 -39.07371916
OS 32.60217254 -39.07464372
OS 32.61419182 -39.0774174
OS 32.61973918 -39.07834196
OS 32.62898478 -39.07834196
OS 32.63360758 -39.0774174
OS 32.63915494 -39.07649284
OS 32.6447023 -39.07464372
OS 32.65024966 -39.07094548
OS 32.65672158 -39.06724724
OS 32.66134438 -39.06169988
OS 32.66226894 -39.06077532
OS 32.6631935 -39.05800164
OS 32.66504262 -39.05337884
OS 32.6678163 -39.04598236
OS 32.66966542 -39.0358122
OS 32.67058998 -39.02841572
OS 32.67151454 -39.0219438
OS 32.6724391 -39.01362276
OS 32.6724391 -39.0034526
OS 32.67336366 -38.99328244
OS 32.67336366 -38.98218772
OS 32.67336366 -38.49586916
OS 32.75195126 -38.49586916
OS 32.75195126 -38.98403684
OE
OB 33.77174094 -38.3100326 I
OS 33.78006198 -38.31095716
OS 33.79023214 -38.31188172
OS 33.8004023 -38.31280628
OS 33.81242158 -38.31557996
OS 33.8373847 -38.32112732
OS 33.8651215 -38.32944836
OS 33.8789899 -38.33499572
OS 33.89193374 -38.34146764
OS 33.90487758 -38.34978868
OS 33.91782142 -38.35810972
OS 33.91874598 -38.35903428
OS 33.9205951 -38.35995884
OS 33.92429334 -38.36273252
OS 33.92891614 -38.36735532
OS 33.93353894 -38.37197812
OS 33.94001086 -38.37845004
OS 33.94648278 -38.38584652
OS 33.95387926 -38.393243
OS 33.96127574 -38.4024886
OS 33.96867222 -38.41358332
OS 33.97699326 -38.42467804
OS 33.98438974 -38.43669732
OS 33.99086166 -38.45056572
OS 33.99825814 -38.46443412
OS 34.0038055 -38.47922708
OS 34.00935286 -38.49586916
OS 33.92614246 -38.51528492
OS 33.92614246 -38.51436036
OS 33.9252179 -38.51251124
OS 33.92336878 -38.508813
OS 33.92151966 -38.5041902
OS 33.91967054 -38.49864284
OS 33.91689686 -38.49124636
OS 33.90950038 -38.4764534
OS 33.90025478 -38.45981132
OS 33.88916006 -38.44316924
OS 33.87529166 -38.42745172
OS 33.8604987 -38.41358332
OS 33.85864958 -38.4117342
OS 33.85310222 -38.40803596
OS 33.84385662 -38.40341316
OS 33.83183734 -38.39694124
OS 33.81611982 -38.39139388
OS 33.79855318 -38.38584652
OS 33.7772883 -38.38214828
OS 33.7541743 -38.38122372
OS 33.74677782 -38.38122372
OS 33.74215502 -38.38214828
OS 33.7356831 -38.38214828
OS 33.72828662 -38.38307284
OS 33.71071998 -38.38584652
OS 33.69130422 -38.38954476
OS 33.6709639 -38.39601668
OS 33.64969902 -38.40526228
OS 33.63028326 -38.41728156
OS 33.6293587 -38.41728156
OS 33.62843414 -38.41913068
OS 33.62196222 -38.42375348
OS 33.61364118 -38.43114996
OS 33.60347102 -38.44224468
OS 33.59145174 -38.45611308
OS 33.58035702 -38.4718306
OS 33.57018686 -38.49124636
OS 33.56094126 -38.51251124
OS 33.56094126 -38.5134358
OS 33.5600167 -38.51528492
OS 33.55909214 -38.5180586
OS 33.55816758 -38.5226814
OS 33.55631846 -38.52822876
OS 33.55446934 -38.53470068
OS 33.55169566 -38.5504182
OS 33.54799742 -38.5689094
OS 33.54429918 -38.58924972
OS 33.54245006 -38.61143916
OS 33.5415255 -38.63547772
OS 33.5415255 -38.63640228
OS 33.5415255 -38.63917596
OS 33.5415255 -38.64379876
OS 33.5415255 -38.64934612
OS 33.54245006 -38.65581804
OS 33.54245006 -38.66413908
OS 33.54337462 -38.67338468
OS 33.54429918 -38.68355484
OS 33.54707286 -38.70574428
OS 33.55169566 -38.72978284
OS 33.55724302 -38.7538214
OS 33.5646395 -38.77785996
OS 33.5646395 -38.77878452
OS 33.56556406 -38.78063364
OS 33.56741318 -38.78340732
OS 33.5692623 -38.78803012
OS 33.57480966 -38.79912484
OS 33.5831307 -38.81206868
OS 33.59330086 -38.82686164
OS 33.6062447 -38.84257916
OS 33.62103766 -38.85644756
OS 33.6386043 -38.8693914
OS 33.63952886 -38.8693914
OS 33.64137798 -38.87031596
OS 33.64415166 -38.87216508
OS 33.6478499 -38.8740142
OS 33.6524727 -38.87586332
OS 33.65802006 -38.878637
OS 33.6709639 -38.88418436
OS 33.68760598 -38.88973172
OS 33.70609718 -38.89435452
OS 33.7264375 -38.89805276
OS 33.74770238 -38.89897732
OS 33.7541743 -38.89897732
OS 33.75972166 -38.89805276
OS 33.76619358 -38.89805276
OS 33.7726655 -38.8971282
OS 33.78930758 -38.89342996
OS 33.80872334 -38.88880716
OS 33.8281391 -38.88141068
OS 33.84847942 -38.87124052
OS 33.85864958 -38.86569316
OS 33.86789518 -38.85829668
OS 33.86881974 -38.85737212
OS 33.8697443 -38.85644756
OS 33.87251798 -38.85367388
OS 33.87621622 -38.8509002
OS 33.87991446 -38.8462774
OS 33.88453726 -38.84073004
OS 33.89008462 -38.83518268
OS 33.89470742 -38.8277862
OS 33.90025478 -38.81946516
OS 33.9067267 -38.81021956
OS 33.91227406 -38.80097396
OS 33.91782142 -38.78987924
OS 33.92244422 -38.77785996
OS 33.92706702 -38.76491612
OS 33.93168982 -38.75104772
OS 33.93538806 -38.73625476
OS 34.02044758 -38.75751964
OS 34.02044758 -38.7584442
OS 34.01952302 -38.76214244
OS 34.0176739 -38.7676898
OS 34.01490022 -38.77508628
OS 34.01212654 -38.78340732
OS 34.0084283 -38.79357748
OS 34.0038055 -38.8046722
OS 33.99825814 -38.81669148
OS 33.9853143 -38.84257916
OS 33.96867222 -38.86846684
OS 33.95850206 -38.88141068
OS 33.9483319 -38.89435452
OS 33.93723718 -38.90544924
OS 33.92429334 -38.91654396
OS 33.92336878 -38.91746852
OS 33.92151966 -38.91931764
OS 33.91689686 -38.92116676
OS 33.91227406 -38.924865
OS 33.90487758 -38.9294878
OS 33.8974811 -38.9341106
OS 33.88731094 -38.9387334
OS 33.87714078 -38.9433562
OS 33.8651215 -38.94890356
OS 33.85217766 -38.95352636
OS 33.83830926 -38.95814916
OS 33.8235163 -38.96277196
OS 33.80779878 -38.9664702
OS 33.7911567 -38.96831932
OS 33.77359006 -38.97016844
OS 33.75509886 -38.971093
OS 33.7449287 -38.971093
OS 33.73753222 -38.97016844
OS 33.72921118 -38.97016844
OS 33.71904102 -38.96924388
OS 33.7079463 -38.96739476
OS 33.69500246 -38.96554564
OS 33.66819022 -38.96092284
OS 33.64045342 -38.95352636
OS 33.61271662 -38.9433562
OS 33.59977278 -38.93688428
OS 33.58682894 -38.9294878
OS 33.58590438 -38.92856324
OS 33.58405526 -38.92763868
OS 33.58035702 -38.924865
OS 33.57665878 -38.92116676
OS 33.57111142 -38.91746852
OS 33.5646395 -38.91192116
OS 33.55724302 -38.90544924
OS 33.54984654 -38.89805276
OS 33.54245006 -38.88973172
OS 33.53412902 -38.88141068
OS 33.51748694 -38.8601458
OS 33.50176942 -38.83518268
OS 33.48790102 -38.80744588
OS 33.48790102 -38.80652132
OS 33.4860519 -38.80374764
OS 33.48512734 -38.79912484
OS 33.48235366 -38.79357748
OS 33.48050454 -38.786181
OS 33.47773086 -38.7769354
OS 33.47403262 -38.76676524
OS 33.47125894 -38.75567052
OS 33.46848526 -38.74365124
OS 33.46478702 -38.72978284
OS 33.46016422 -38.70112148
OS 33.45646598 -38.66876188
OS 33.45461686 -38.63547772
OS 33.45461686 -38.63455316
OS 33.45461686 -38.63085492
OS 33.45461686 -38.62530756
OS 33.45554142 -38.61883564
OS 33.45554142 -38.60959004
OS 33.45646598 -38.60034444
OS 33.45739054 -38.58832516
OS 33.45923966 -38.57630588
OS 33.46386246 -38.54949364
OS 33.47033438 -38.51990772
OS 33.47957998 -38.4903218
OS 33.49252382 -38.46166044
OS 33.49344838 -38.46073588
OS 33.49437294 -38.4579622
OS 33.49622206 -38.45426396
OS 33.4999203 -38.44964116
OS 33.50361854 -38.44316924
OS 33.50824134 -38.43577276
OS 33.52026062 -38.41913068
OS 33.53597814 -38.40063948
OS 33.55446934 -38.38214828
OS 33.57573422 -38.36365708
OS 33.60069734 -38.34793956
OS 33.6016219 -38.347015
OS 33.60439558 -38.34609044
OS 33.60809382 -38.34424132
OS 33.61271662 -38.34146764
OS 33.6201131 -38.33869396
OS 33.62750958 -38.33592028
OS 33.63675518 -38.33222204
OS 33.64692534 -38.3285238
OS 33.65802006 -38.32482556
OS 33.67003934 -38.32112732
OS 33.69592702 -38.31557996
OS 33.72551294 -38.31095716
OS 33.75602342 -38.30910804
OS 33.76526902 -38.30910804
OS 33.77174094 -38.3100326
OE
OB 35.15858094 -39.1375138 I
OS 34.63805366 -39.1375138
OS 34.63805366 -39.08111564
OS 35.15858094 -39.08111564
OS 35.15858094 -39.1375138
OE
OB 34.37917686 -38.32112732 I
OS 34.38657334 -38.32112732
OS 34.40321542 -38.32297644
OS 34.42170662 -38.32482556
OS 34.44112238 -38.3285238
OS 34.46053814 -38.3331466
OS 34.47810478 -38.33961852
OS 34.47902934 -38.33961852
OS 34.4799539 -38.34054308
OS 34.48550126 -38.34331676
OS 34.4938223 -38.34793956
OS 34.5030679 -38.35441148
OS 34.51416262 -38.36273252
OS 34.5261819 -38.37290268
OS 34.53727662 -38.38584652
OS 34.54744678 -38.39971492
OS 34.54837134 -38.40156404
OS 34.55114502 -38.4071114
OS 34.55576782 -38.41450788
OS 34.56039062 -38.4256026
OS 34.56501342 -38.43854644
OS 34.56963622 -38.45241484
OS 34.5724099 -38.46813236
OS 34.57333446 -38.48384988
OS 34.57333446 -38.485699
OS 34.57333446 -38.4903218
OS 34.5724099 -38.49864284
OS 34.57056078 -38.508813
OS 34.5677871 -38.52083228
OS 34.5631643 -38.53377612
OS 34.55761694 -38.54671996
OS 34.55022046 -38.56058836
OS 34.5492959 -38.56243748
OS 34.54652222 -38.56613572
OS 34.54097486 -38.5735322
OS 34.53357838 -38.58092868
OS 34.52433278 -38.59017428
OS 34.51323806 -38.60034444
OS 34.49936966 -38.60959004
OS 34.48365214 -38.61883564
OS 34.4845767 -38.61883564
OS 34.48642582 -38.6197602
OS 34.4891995 -38.62068476
OS 34.49289774 -38.62253388
OS 34.50399246 -38.62623212
OS 34.5169363 -38.63270404
OS 34.5308047 -38.64102508
OS 34.54652222 -38.65119524
OS 34.56039062 -38.66321452
OS 34.57333446 -38.67800748
OS 34.57425902 -38.6798566
OS 34.57795726 -38.68540396
OS 34.58350462 -38.693725
OS 34.58905198 -38.70481972
OS 34.59459934 -38.71961268
OS 34.6001467 -38.7353302
OS 34.60384494 -38.7538214
OS 34.6047695 -38.77416172
OS 34.6047695 -38.77508628
OS 34.6047695 -38.77601084
OS 34.6047695 -38.7815582
OS 34.60384494 -38.7908038
OS 34.60199582 -38.80189852
OS 34.6001467 -38.81484236
OS 34.59644846 -38.82871076
OS 34.59182566 -38.84350372
OS 34.58535374 -38.85829668
OS 34.58442918 -38.8601458
OS 34.5816555 -38.8647686
OS 34.57795726 -38.87124052
OS 34.5724099 -38.88048612
OS 34.56501342 -38.88973172
OS 34.55761694 -38.89990188
OS 34.54837134 -38.91007204
OS 34.53820118 -38.91839308
OS 34.53727662 -38.91931764
OS 34.53357838 -38.92209132
OS 34.52710646 -38.92578956
OS 34.51878542 -38.9294878
OS 34.50861526 -38.93503516
OS 34.49659598 -38.94058252
OS 34.48365214 -38.94520532
OS 34.46793462 -38.94982812
OS 34.4660855 -38.94982812
OS 34.46053814 -38.95167724
OS 34.45129254 -38.9526018
OS 34.43927326 -38.95445092
OS 34.4244803 -38.95630004
OS 34.40691366 -38.95814916
OS 34.3874979 -38.95907372
OS 34.36530846 -38.95999828
OS 34.12122462 -38.95999828
OS 34.12122462 -38.32020276
OS 34.37270494 -38.32020276
OS 34.37917686 -38.32112732
OE
OB 31.74233174 -38.95999828 I
OS 31.65264942 -38.95999828
OS 31.65264942 -38.87031596
OS 31.74233174 -38.87031596
OS 31.74233174 -38.95999828
OE
OB 31.52968294 -38.42745172 I
OS 31.50841806 -38.54671996
OS 31.45941638 -38.54671996
OS 31.44000062 -38.42745172
OS 31.44000062 -38.32020276
OS 31.52968294 -38.32020276
OS 31.52968294 -38.42745172
OE
OB 32.0992119 -38.48662356 I
OS 32.10568382 -38.48754812
OS 32.11955222 -38.48939724
OS 32.1361943 -38.49309548
OS 32.15376094 -38.49864284
OS 32.17132758 -38.50696388
OS 32.18889422 -38.51713404
OS 32.18981878 -38.51713404
OS 32.19074334 -38.51898316
OS 32.1962907 -38.5226814
OS 32.20461174 -38.53007788
OS 32.2147819 -38.53932348
OS 32.22587662 -38.55134276
OS 32.23697134 -38.56613572
OS 32.24806606 -38.58370236
OS 32.25731166 -38.60311812
OS 32.25731166 -38.60404268
OS 32.25823622 -38.6058918
OS 32.25916078 -38.60866548
OS 32.2610099 -38.61236372
OS 32.26285902 -38.61791108
OS 32.26470814 -38.624383
OS 32.26933094 -38.63917596
OS 32.27395374 -38.65766716
OS 32.27765198 -38.67800748
OS 32.28042566 -38.70112148
OS 32.28135022 -38.72516004
OS 32.28135022 -38.7260846
OS 32.28135022 -38.72793372
OS 32.28135022 -38.73163196
OS 32.28135022 -38.73717932
OS 32.28042566 -38.74365124
OS 32.28042566 -38.75104772
OS 32.27857654 -38.7676898
OS 32.2748783 -38.78803012
OS 32.2702555 -38.809295
OS 32.26378358 -38.83148444
OS 32.25546254 -38.85367388
OS 32.25546254 -38.85459844
OS 32.25453798 -38.85644756
OS 32.25268886 -38.85922124
OS 32.25083974 -38.86291948
OS 32.24436782 -38.87308964
OS 32.23604678 -38.88603348
OS 32.22587662 -38.89990188
OS 32.21293278 -38.91377028
OS 32.19813982 -38.92763868
OS 32.18057318 -38.94058252
OS 32.17964862 -38.94058252
OS 32.17872406 -38.94150708
OS 32.17595038 -38.9433562
OS 32.17225214 -38.94520532
OS 32.16300654 -38.94982812
OS 32.1500627 -38.95537548
OS 32.13434518 -38.96092284
OS 32.1177031 -38.96554564
OS 32.09828734 -38.96924388
OS 32.07887158 -38.97016844
OS 32.07239966 -38.97016844
OS 32.06500318 -38.96924388
OS 32.05575758 -38.96831932
OS 32.04466286 -38.9664702
OS 32.03264358 -38.96369652
OS 32.0206243 -38.95999828
OS 32.00860502 -38.95445092
OS 32.00768046 -38.95352636
OS 32.00305766 -38.95167724
OS 31.9975103 -38.947979
OS 31.99011382 -38.94243164
OS 31.98271734 -38.93688428
OS 31.97347174 -38.9294878
OS 31.9651507 -38.92116676
OS 31.95775422 -38.91192116
OS 31.95775422 -39.1375138
OS 31.87916662 -39.1375138
OS 31.87916662 -38.49586916
OS 31.95035774 -38.49586916
OS 31.95035774 -38.55689012
OS 31.9512823 -38.555041
OS 31.95498054 -38.55134276
OS 31.95960334 -38.54487084
OS 31.96699982 -38.53747436
OS 31.97532086 -38.52822876
OS 31.98456646 -38.51990772
OS 31.99566118 -38.51158668
OS 32.0067559 -38.5041902
OS 32.00860502 -38.50326564
OS 32.01230326 -38.50141652
OS 32.01969974 -38.49864284
OS 32.02894534 -38.4949446
OS 32.04004006 -38.49124636
OS 32.0529839 -38.48847268
OS 32.06777686 -38.48662356
OS 32.08441894 -38.485699
OS 32.0945891 -38.485699
OS 32.0992119 -38.48662356
OE
OB 32.5614919 -38.48662356 I
OS 32.57166206 -38.48847268
OS 32.58368134 -38.49217092
OS 32.59662518 -38.49679372
OS 32.61141814 -38.50326564
OS 32.62713566 -38.51158668
OS 32.5984743 -38.58370236
OS 32.59754974 -38.5827778
OS 32.5938515 -38.58092868
OS 32.58830414 -38.578155
OS 32.58090766 -38.57538132
OS 32.57258662 -38.57260764
OS 32.56241646 -38.56983396
OS 32.5522463 -38.56798484
OS 32.54207614 -38.56706028
OS 32.53745334 -38.56706028
OS 32.53283054 -38.56798484
OS 32.52635862 -38.5689094
OS 32.5198867 -38.57075852
OS 32.51156566 -38.5735322
OS 32.50324462 -38.57723044
OS 32.49584814 -38.5827778
OS 32.49492358 -38.58370236
OS 32.4921499 -38.58555148
OS 32.48937622 -38.58924972
OS 32.48475342 -38.59387252
OS 32.48013062 -38.60034444
OS 32.47550782 -38.60774092
OS 32.47088502 -38.61606196
OS 32.46718678 -38.62623212
OS 32.46626222 -38.62808124
OS 32.46533766 -38.6336286
OS 32.46348854 -38.64194964
OS 32.46071486 -38.65304436
OS 32.45794118 -38.66691276
OS 32.45609206 -38.68263028
OS 32.4551675 -38.69927236
OS 32.45424294 -38.71776356
OS 32.45424294 -38.95999828
OS 32.37565534 -38.95999828
OS 32.37565534 -38.49586916
OS 32.44684646 -38.49586916
OS 32.44684646 -38.56613572
OS 32.44777102 -38.56521116
OS 32.45146926 -38.55873924
OS 32.45609206 -38.5504182
OS 32.46348854 -38.54024804
OS 32.47088502 -38.53007788
OS 32.47920606 -38.51898316
OS 32.4875271 -38.50973756
OS 32.49584814 -38.50234108
OS 32.4967727 -38.50141652
OS 32.49954638 -38.4995674
OS 32.50509374 -38.49679372
OS 32.5106411 -38.49402004
OS 32.51803758 -38.49124636
OS 32.52728318 -38.48847268
OS 32.53652878 -38.48662356
OS 32.54669894 -38.485699
OS 32.55317086 -38.485699
OS 32.5614919 -38.48662356
OE
OB 32.75195126 -38.4117342 I
OS 32.67336366 -38.4117342
OS 32.67336366 -38.32020276
OS 32.75195126 -38.32020276
OS 32.75195126 -38.4117342
OE
OB 36.56668582 -38.95999828 I
OS 36.47885262 -38.95999828
OS 36.1441619 -38.4579622
OS 36.1441619 -38.95999828
OS 36.06280062 -38.95999828
OS 36.06280062 -38.32020276
OS 36.14970926 -38.32020276
OS 36.48532454 -38.8231634
OS 36.48532454 -38.32020276
OS 36.56668582 -38.32020276
OS 36.56668582 -38.95999828
OE
OB 35.74382742 -38.32112732 I
OS 35.75954494 -38.32205188
OS 35.77618702 -38.32297644
OS 35.79190454 -38.32482556
OS 35.80577294 -38.32667468
OS 35.80762206 -38.32667468
OS 35.81409398 -38.3285238
OS 35.82241502 -38.33037292
OS 35.83350974 -38.3331466
OS 35.84552902 -38.3377694
OS 35.85847286 -38.34331676
OS 35.87234126 -38.34978868
OS 35.88436054 -38.35718516
OS 35.88620966 -38.35810972
OS 35.8899079 -38.3608834
OS 35.89545526 -38.36643076
OS 35.90285174 -38.37290268
OS 35.91117278 -38.38122372
OS 35.91949382 -38.39231844
OS 35.92873942 -38.40433772
OS 35.9361359 -38.41820612
OS 35.93706046 -38.42005524
OS 35.93890958 -38.42467804
OS 35.94260782 -38.43299908
OS 35.94630606 -38.4440938
OS 35.94907974 -38.45703764
OS 35.95277798 -38.4718306
OS 35.9546271 -38.48847268
OS 35.95555166 -38.50603932
OS 35.95555166 -38.50696388
OS 35.95555166 -38.50973756
OS 35.95555166 -38.5134358
OS 35.9546271 -38.51990772
OS 35.95370254 -38.52637964
OS 35.95277798 -38.53470068
OS 35.95092886 -38.54394628
OS 35.94907974 -38.55411644
OS 35.94260782 -38.57538132
OS 35.93890958 -38.58647604
OS 35.93336222 -38.59849532
OS 35.9268903 -38.6105146
OS 35.92041838 -38.62160932
OS 35.91209734 -38.63270404
OS 35.90285174 -38.64379876
OS 35.90192718 -38.64472332
OS 35.90007806 -38.64657244
OS 35.89730438 -38.64934612
OS 35.89268158 -38.6521198
OS 35.88713422 -38.6567426
OS 35.87973774 -38.6613654
OS 35.87049214 -38.66691276
OS 35.86032198 -38.67153556
OS 35.8483027 -38.67708292
OS 35.8344343 -38.68263028
OS 35.81964134 -38.68725308
OS 35.8020747 -38.69095132
OS 35.7835835 -38.69464956
OS 35.76324318 -38.69742324
OS 35.74012918 -38.69927236
OS 35.71609062 -38.70019692
OS 35.5524435 -38.70019692
OS 35.5524435 -38.95999828
OS 35.46738398 -38.95999828
OS 35.46738398 -38.32020276
OS 35.72995902 -38.32020276
OS 35.74382742 -38.32112732
OE
OB 36.76916446 -38.42745172 I
OS 36.74789958 -38.54671996
OS 36.6988979 -38.54671996
OS 36.67948214 -38.42745172
OS 36.67948214 -38.32020276
OS 36.76916446 -38.32020276
OS 36.76916446 -38.42745172
OE
OB 38.2382903 -38.39601668 I
OS 37.86014526 -38.39601668
OS 37.86014526 -38.59109884
OS 38.21425174 -38.59109884
OS 38.21425174 -38.66691276
OS 37.86014526 -38.66691276
OS 37.86014526 -38.88418436
OS 38.25308326 -38.88418436
OS 38.25308326 -38.95999828
OS 37.77508574 -38.95999828
OS 37.77508574 -38.32020276
OS 38.2382903 -38.32020276
OS 38.2382903 -38.39601668
OE
OB 37.4339231 -38.32112732 I
OS 37.44224414 -38.32112732
OS 37.4616599 -38.32205188
OS 37.48200022 -38.32482556
OS 37.50418966 -38.32759924
OS 37.52452998 -38.33222204
OS 37.53470014 -38.33499572
OS 37.54302118 -38.3377694
OS 37.54394574 -38.3377694
OS 37.5448703 -38.33869396
OS 37.55041766 -38.34146764
OS 37.5587387 -38.34516588
OS 37.56890886 -38.3516378
OS 37.58000358 -38.35995884
OS 37.59202286 -38.37105356
OS 37.60311758 -38.3839974
OS 37.6142123 -38.39879036
OS 37.6142123 -38.39971492
OS 37.61513686 -38.40063948
OS 37.6188351 -38.40618684
OS 37.62253334 -38.41543244
OS 37.6280807 -38.42745172
OS 37.6327035 -38.44132012
OS 37.6373263 -38.4579622
OS 37.64009998 -38.47552884
OS 37.64102454 -38.4949446
OS 37.64102454 -38.49586916
OS 37.64102454 -38.49771828
OS 37.64102454 -38.50141652
OS 37.64009998 -38.50603932
OS 37.64009998 -38.51251124
OS 37.63917542 -38.51898316
OS 37.63547718 -38.53470068
OS 37.62992982 -38.55319188
OS 37.62253334 -38.57260764
OS 37.61143862 -38.5920234
OS 37.60404214 -38.601269
OS 37.59664566 -38.6105146
OS 37.5957211 -38.61143916
OS 37.59479654 -38.61236372
OS 37.59202286 -38.6151374
OS 37.58832462 -38.61791108
OS 37.58370182 -38.62160932
OS 37.57815446 -38.62530756
OS 37.57075798 -38.62993036
OS 37.5633615 -38.63547772
OS 37.5541159 -38.64010052
OS 37.54394574 -38.64472332
OS 37.53285102 -38.65027068
OS 37.52083174 -38.65489348
OS 37.50696334 -38.65859172
OS 37.49309494 -38.66321452
OS 37.47737742 -38.6659882
OS 37.46073534 -38.66876188
OS 37.46258446 -38.66968644
OS 37.4662827 -38.67153556
OS 37.47183006 -38.6752338
OS 37.47922654 -38.67893204
OS 37.49586862 -38.6891022
OS 37.50418966 -38.69557412
OS 37.51158614 -38.70112148
OS 37.51343526 -38.7029706
OS 37.51805806 -38.7075934
OS 37.52545454 -38.71498988
OS 37.53470014 -38.72423548
OS 37.5448703 -38.73717932
OS 37.55688958 -38.75104772
OS 37.56890886 -38.7676898
OS 37.5818527 -38.786181
OS 37.69187534 -38.95999828
OS 37.5864755 -38.95999828
OS 37.50234054 -38.82686164
OS 37.50234054 -38.82593708
OS 37.50049142 -38.82408796
OS 37.4986423 -38.82131428
OS 37.49586862 -38.81761604
OS 37.4893967 -38.80744588
OS 37.48107566 -38.79450204
OS 37.4709055 -38.78063364
OS 37.46073534 -38.76584068
OS 37.45056518 -38.75197228
OS 37.44131958 -38.73902844
OS 37.44039502 -38.73810388
OS 37.43762134 -38.73440564
OS 37.43299854 -38.72885828
OS 37.42652662 -38.72238636
OS 37.41265822 -38.70851796
OS 37.40526174 -38.70204604
OS 37.39786526 -38.69649868
OS 37.3969407 -38.69557412
OS 37.39509158 -38.69464956
OS 37.39139334 -38.69280044
OS 37.38584598 -38.69002676
OS 37.38029862 -38.68725308
OS 37.3738267 -38.6844794
OS 37.35903374 -38.6798566
OS 37.35810918 -38.6798566
OS 37.35626006 -38.67893204
OS 37.35256182 -38.67893204
OS 37.34793902 -38.67800748
OS 37.3414671 -38.67708292
OS 37.33407062 -38.67708292
OS 37.32390046 -38.67615836
OS 37.21480238 -38.67615836
OS 37.21480238 -38.95999828
OS 37.12974286 -38.95999828
OS 37.12974286 -38.32020276
OS 37.42652662 -38.32020276
OS 37.4339231 -38.32112732
OE
OB 35.31760526 -38.95999828 I
OS 35.23254574 -38.95999828
OS 35.23254574 -38.32020276
OS 35.31760526 -38.32020276
OS 35.31760526 -38.95999828
OE
OB 42.12051774 -38.66413908 H
OS 41.95224782 -38.66413908
OS 41.95224782 -38.88418436
OS 42.13438614 -38.88418436
OS 42.1538019 -38.8832598
OS 42.16212294 -38.88233524
OS 42.16951942 -38.88141068
OS 42.17044398 -38.88141068
OS 42.17414222 -38.88048612
OS 42.17968958 -38.87956156
OS 42.1861615 -38.87771244
OS 42.20187902 -38.87216508
OS 42.21759654 -38.8647686
OS 42.2185211 -38.86384404
OS 42.22129478 -38.86199492
OS 42.22499302 -38.85922124
OS 42.22961582 -38.855523
OS 42.23423862 -38.84997564
OS 42.24071054 -38.84442828
OS 42.24533334 -38.8370318
OS 42.2508807 -38.82871076
OS 42.25180526 -38.8277862
OS 42.25272982 -38.82501252
OS 42.25457894 -38.81946516
OS 42.25735262 -38.81299324
OS 42.2601263 -38.80559676
OS 42.26197542 -38.79635116
OS 42.26289998 -38.78525644
OS 42.26382454 -38.77416172
OS 42.26382454 -38.7723126
OS 42.26382454 -38.76861436
OS 42.26289998 -38.76121788
OS 42.26105086 -38.75289684
OS 42.25920174 -38.74365124
OS 42.2555035 -38.73348108
OS 42.2508807 -38.72331092
OS 42.24440878 -38.71314076
OS 42.24348422 -38.7122162
OS 42.24071054 -38.70851796
OS 42.2370123 -38.70389516
OS 42.23146494 -38.6983478
OS 42.22406846 -38.69187588
OS 42.21482286 -38.68540396
OS 42.2046527 -38.6798566
OS 42.19263342 -38.6752338
OS 42.1907843 -38.67430924
OS 42.18708606 -38.67338468
OS 42.17876502 -38.67153556
OS 42.16859486 -38.66968644
OS 42.15565102 -38.66783732
OS 42.1399335 -38.6659882
OS 42.12051774 -38.66413908
OE
OB 45.22981302 -38.5504182 H
OS 45.22426566 -38.5504182
OS 45.21964286 -38.55134276
OS 45.2094727 -38.55226732
OS 45.1956043 -38.55596556
OS 45.17988678 -38.56151292
OS 45.1632447 -38.5689094
OS 45.14752718 -38.58000412
OS 45.13920614 -38.5874006
OS 45.13180966 -38.59479708
OS 45.13180966 -38.59572164
OS 45.12996054 -38.5966462
OS 45.12811142 -38.59941988
OS 45.12533774 -38.60311812
OS 45.12256406 -38.60774092
OS 45.11979038 -38.61328828
OS 45.11609214 -38.62068476
OS 45.1123939 -38.62808124
OS 45.10869566 -38.63732684
OS 45.10499742 -38.64657244
OS 45.10222374 -38.65766716
OS 45.09945006 -38.66968644
OS 45.09667638 -38.68263028
OS 45.09482726 -38.69649868
OS 45.0939027 -38.7122162
OS 45.09297814 -38.72793372
OS 45.09297814 -38.72885828
OS 45.09297814 -38.73163196
OS 45.09297814 -38.73625476
OS 45.0939027 -38.74272668
OS 45.0939027 -38.75012316
OS 45.09482726 -38.7584442
OS 45.09760094 -38.77785996
OS 45.10222374 -38.8000494
OS 45.10962022 -38.82223884
OS 45.11886582 -38.84350372
OS 45.12533774 -38.85274932
OS 45.13180966 -38.86199492
OS 45.13273422 -38.86199492
OS 45.13365878 -38.86384404
OS 45.13920614 -38.86846684
OS 45.14752718 -38.87586332
OS 45.1586219 -38.8832598
OS 45.1724903 -38.89158084
OS 45.18913238 -38.89897732
OS 45.20854814 -38.90360012
OS 45.2187183 -38.90452468
OS 45.22981302 -38.90544924
OS 45.23536038 -38.90544924
OS 45.23998318 -38.90452468
OS 45.25015334 -38.90267556
OS 45.26402174 -38.89990188
OS 45.2788147 -38.89435452
OS 45.29545678 -38.88695804
OS 45.3111743 -38.87586332
OS 45.31949534 -38.86846684
OS 45.32689182 -38.86107036
OS 45.32781638 -38.8601458
OS 45.32874094 -38.85922124
OS 45.33059006 -38.85644756
OS 45.33336374 -38.85274932
OS 45.33613742 -38.84812652
OS 45.33983566 -38.84257916
OS 45.3435339 -38.83518268
OS 45.34723214 -38.8277862
OS 45.35093038 -38.8185406
OS 45.35370406 -38.80837044
OS 45.3574023 -38.79727572
OS 45.36017598 -38.78525644
OS 45.36294966 -38.77138804
OS 45.36479878 -38.75751964
OS 45.3666479 -38.74180212
OS 45.3666479 -38.72516004
OS 45.3666479 -38.72423548
OS 45.3666479 -38.7214618
OS 45.3666479 -38.716839
OS 45.36572334 -38.71129164
OS 45.36572334 -38.70389516
OS 45.36479878 -38.69557412
OS 45.3620251 -38.67615836
OS 45.3574023 -38.65581804
OS 45.35000582 -38.6336286
OS 45.33983566 -38.61328828
OS 45.3342883 -38.60311812
OS 45.32689182 -38.59479708
OS 45.32689182 -38.59387252
OS 45.3250427 -38.59294796
OS 45.31949534 -38.5874006
OS 45.3111743 -38.58092868
OS 45.30007958 -38.57260764
OS 45.28621118 -38.5642866
OS 45.2695691 -38.55689012
OS 45.2510779 -38.55226732
OS 45.24090774 -38.55134276
OS 45.22981302 -38.5504182
OE
OB 32.07702246 -38.54764452 H
OS 32.07239966 -38.54764452
OS 32.06870142 -38.54856908
OS 32.05945582 -38.5504182
OS 32.04743654 -38.55319188
OS 32.03356814 -38.55873924
OS 32.01877518 -38.56706028
OS 32.01045414 -38.57260764
OS 32.00305766 -38.57907956
OS 31.99566118 -38.58647604
OS 31.9882647 -38.59479708
OS 31.9882647 -38.59572164
OS 31.98641558 -38.5966462
OS 31.98456646 -38.59941988
OS 31.98271734 -38.60311812
OS 31.97994366 -38.60866548
OS 31.97624542 -38.61421284
OS 31.97254718 -38.62160932
OS 31.9697735 -38.6290058
OS 31.96607526 -38.6382514
OS 31.96237702 -38.64842156
OS 31.95960334 -38.65951628
OS 31.9559051 -38.67153556
OS 31.95405598 -38.68540396
OS 31.95220686 -38.69927236
OS 31.95035774 -38.71406532
OS 31.95035774 -38.7307074
OS 31.95035774 -38.73163196
OS 31.95035774 -38.73440564
OS 31.95035774 -38.73902844
OS 31.9512823 -38.74550036
OS 31.9512823 -38.75289684
OS 31.95220686 -38.76121788
OS 31.95498054 -38.78063364
OS 31.95960334 -38.80282308
OS 31.9651507 -38.82408796
OS 31.9743963 -38.84535284
OS 31.97994366 -38.85459844
OS 31.98641558 -38.86291948
OS 31.9882647 -38.8647686
OS 31.9928875 -38.8693914
OS 32.00028398 -38.87678788
OS 32.01045414 -38.88418436
OS 32.02339798 -38.89158084
OS 32.03819094 -38.89897732
OS 32.05483302 -38.90360012
OS 32.06407862 -38.90452468
OS 32.07332422 -38.90544924
OS 32.07887158 -38.90544924
OS 32.08256982 -38.90452468
OS 32.09181542 -38.90267556
OS 32.10475926 -38.89990188
OS 32.11862766 -38.89435452
OS 32.13342062 -38.88695804
OS 32.14821358 -38.87586332
OS 32.15561006 -38.8693914
OS 32.16300654 -38.86199492
OS 32.16300654 -38.86107036
OS 32.16485566 -38.8601458
OS 32.16670478 -38.85737212
OS 32.1685539 -38.85367388
OS 32.17225214 -38.84905108
OS 32.17502582 -38.84257916
OS 32.17872406 -38.83610724
OS 32.1824223 -38.8277862
OS 32.18519598 -38.81946516
OS 32.18889422 -38.80837044
OS 32.19259246 -38.79727572
OS 32.19536614 -38.78525644
OS 32.19721526 -38.77138804
OS 32.19906438 -38.75659508
OS 32.2009135 -38.74087756
OS 32.2009135 -38.72423548
OS 32.2009135 -38.72331092
OS 32.2009135 -38.72053724
OS 32.2009135 -38.71591444
OS 32.19998894 -38.70944252
OS 32.19998894 -38.70204604
OS 32.19906438 -38.693725
OS 32.1962907 -38.67430924
OS 32.1916679 -38.65304436
OS 32.18519598 -38.63177948
OS 32.17595038 -38.6105146
OS 32.17040302 -38.60034444
OS 32.1639311 -38.5920234
OS 32.1639311 -38.59109884
OS 32.16208198 -38.59017428
OS 32.15745918 -38.58462692
OS 32.1500627 -38.578155
OS 32.13989254 -38.56983396
OS 32.1269487 -38.56151292
OS 32.11215574 -38.55411644
OS 32.09551366 -38.54949364
OS 32.08626806 -38.54856908
OS 32.07702246 -38.54764452
OE
OB 42.10387566 -38.39601668 H
OS 41.95224782 -38.39601668
OS 41.95224782 -38.58832516
OS 42.10942302 -38.58832516
OS 42.1214423 -38.5874006
OS 42.13438614 -38.58647604
OS 42.14732998 -38.58555148
OS 42.16027382 -38.58370236
OS 42.17044398 -38.58185324
OS 42.1722931 -38.58092868
OS 42.17599134 -38.58000412
OS 42.1815387 -38.57723044
OS 42.18893518 -38.5735322
OS 42.19633166 -38.56983396
OS 42.2046527 -38.5642866
OS 42.21297374 -38.55689012
OS 42.21944566 -38.54949364
OS 42.22037022 -38.54856908
OS 42.22221934 -38.5457954
OS 42.22499302 -38.54024804
OS 42.2277667 -38.53377612
OS 42.23054038 -38.52637964
OS 42.23331406 -38.51713404
OS 42.23516318 -38.50603932
OS 42.23608774 -38.49402004
OS 42.23608774 -38.49217092
OS 42.23608774 -38.48847268
OS 42.23516318 -38.48292532
OS 42.23423862 -38.47552884
OS 42.2323895 -38.46628324
OS 42.22961582 -38.45703764
OS 42.22591758 -38.44779204
OS 42.22037022 -38.43854644
OS 42.21944566 -38.43762188
OS 42.21759654 -38.4348482
OS 42.2138983 -38.4302254
OS 42.2092755 -38.4256026
OS 42.20280358 -38.42005524
OS 42.1954071 -38.41450788
OS 42.1861615 -38.40896052
OS 42.17599134 -38.40526228
OS 42.17506678 -38.40526228
OS 42.17044398 -38.40341316
OS 42.16397206 -38.4024886
OS 42.1538019 -38.40063948
OS 42.1399335 -38.39879036
OS 42.12421598 -38.3978658
OS 42.10387566 -38.39601668
OE
OB 37.41635646 -38.39139388 H
OS 37.21480238 -38.39139388
OS 37.21480238 -38.60311812
OS 37.40526174 -38.60311812
OS 37.41635646 -38.60219356
OS 37.4293003 -38.601269
OS 37.44409326 -38.60034444
OS 37.45888622 -38.59849532
OS 37.47367918 -38.59572164
OS 37.48662302 -38.5920234
OS 37.48847214 -38.59109884
OS 37.49217038 -38.58924972
OS 37.49771774 -38.58647604
OS 37.50511422 -38.5827778
OS 37.51343526 -38.57723044
OS 37.5217563 -38.57075852
OS 37.53007734 -38.56243748
OS 37.53654926 -38.55319188
OS 37.53747382 -38.55226732
OS 37.53932294 -38.54856908
OS 37.54209662 -38.54302172
OS 37.54579486 -38.53562524
OS 37.54856854 -38.5273042
OS 37.55134222 -38.5180586
OS 37.55319134 -38.50696388
OS 37.5541159 -38.49586916
OS 37.5541159 -38.4949446
OS 37.5541159 -38.49402004
OS 37.55319134 -38.48847268
OS 37.55226678 -38.48015164
OS 37.55041766 -38.46905692
OS 37.54579486 -38.4579622
OS 37.5402475 -38.44501836
OS 37.53192646 -38.43299908
OS 37.52083174 -38.4209798
OS 37.51898262 -38.42005524
OS 37.51435982 -38.416357
OS 37.50696334 -38.4117342
OS 37.49494406 -38.40618684
OS 37.48107566 -38.40063948
OS 37.46258446 -38.39601668
OS 37.44131958 -38.39231844
OS 37.41635646 -38.39139388
OE
OB 39.82298614 -38.54764452 H
OS 39.81836334 -38.54764452
OS 39.8146651 -38.54856908
OS 39.8054195 -38.5504182
OS 39.79340022 -38.55319188
OS 39.77953182 -38.55873924
OS 39.76473886 -38.56706028
OS 39.75641782 -38.57260764
OS 39.74902134 -38.57907956
OS 39.74162486 -38.58647604
OS 39.73422838 -38.59479708
OS 39.73422838 -38.59572164
OS 39.73237926 -38.5966462
OS 39.73053014 -38.59941988
OS 39.72868102 -38.60311812
OS 39.72590734 -38.60866548
OS 39.7222091 -38.61421284
OS 39.71851086 -38.62160932
OS 39.71573718 -38.6290058
OS 39.71203894 -38.6382514
OS 39.7083407 -38.64842156
OS 39.70556702 -38.65951628
OS 39.70186878 -38.67153556
OS 39.70001966 -38.68540396
OS 39.69817054 -38.69927236
OS 39.69632142 -38.71406532
OS 39.69632142 -38.7307074
OS 39.69632142 -38.73163196
OS 39.69632142 -38.73440564
OS 39.69632142 -38.73902844
OS 39.69724598 -38.74550036
OS 39.69724598 -38.75289684
OS 39.69817054 -38.76121788
OS 39.70094422 -38.78063364
OS 39.70556702 -38.80282308
OS 39.71111438 -38.82408796
OS 39.72035998 -38.84535284
OS 39.72590734 -38.85459844
OS 39.73237926 -38.86291948
OS 39.73422838 -38.8647686
OS 39.73885118 -38.8693914
OS 39.74624766 -38.87678788
OS 39.75641782 -38.88418436
OS 39.76936166 -38.89158084
OS 39.78415462 -38.89897732
OS 39.8007967 -38.90360012
OS 39.8100423 -38.90452468
OS 39.8192879 -38.90544924
OS 39.82483526 -38.90544924
OS 39.8285335 -38.90452468
OS 39.8377791 -38.90267556
OS 39.85072294 -38.89990188
OS 39.86459134 -38.89435452
OS 39.8793843 -38.88695804
OS 39.89417726 -38.87586332
OS 39.90157374 -38.8693914
OS 39.90897022 -38.86199492
OS 39.90897022 -38.86107036
OS 39.91081934 -38.8601458
OS 39.91266846 -38.85737212
OS 39.91451758 -38.85367388
OS 39.91821582 -38.84905108
OS 39.9209895 -38.84257916
OS 39.92468774 -38.83610724
OS 39.92838598 -38.8277862
OS 39.93115966 -38.81946516
OS 39.9348579 -38.80837044
OS 39.93855614 -38.79727572
OS 39.94132982 -38.78525644
OS 39.94317894 -38.77138804
OS 39.94502806 -38.75659508
OS 39.94687718 -38.74087756
OS 39.94687718 -38.72423548
OS 39.94687718 -38.72331092
OS 39.94687718 -38.72053724
OS 39.94687718 -38.71591444
OS 39.94595262 -38.70944252
OS 39.94595262 -38.70204604
OS 39.94502806 -38.693725
OS 39.94225438 -38.67430924
OS 39.93763158 -38.65304436
OS 39.93115966 -38.63177948
OS 39.92191406 -38.6105146
OS 39.9163667 -38.60034444
OS 39.90989478 -38.5920234
OS 39.90989478 -38.59109884
OS 39.90804566 -38.59017428
OS 39.90342286 -38.58462692
OS 39.89602638 -38.578155
OS 39.88585622 -38.56983396
OS 39.87291238 -38.56151292
OS 39.85811942 -38.55411644
OS 39.84147734 -38.54949364
OS 39.83223174 -38.54856908
OS 39.82298614 -38.54764452
OE
OB 35.73550638 -38.39601668 H
OS 35.5524435 -38.39601668
OS 35.5524435 -38.624383
OS 35.72441166 -38.624383
OS 35.73088358 -38.62345844
OS 35.7373555 -38.62345844
OS 35.74475198 -38.62253388
OS 35.76231862 -38.62068476
OS 35.78173438 -38.61698652
OS 35.80115014 -38.61143916
OS 35.81871678 -38.60404268
OS 35.82703782 -38.59941988
OS 35.83350974 -38.59387252
OS 35.83535886 -38.5920234
OS 35.8390571 -38.58832516
OS 35.84460446 -38.58092868
OS 35.85107638 -38.57168308
OS 35.8575483 -38.5596638
OS 35.86309566 -38.54487084
OS 35.8667939 -38.52822876
OS 35.86864302 -38.508813
OS 35.86864302 -38.50788844
OS 35.86864302 -38.50696388
OS 35.86864302 -38.50234108
OS 35.86771846 -38.49402004
OS 35.86586934 -38.48477444
OS 35.86402022 -38.47460428
OS 35.86032198 -38.462585
OS 35.85477462 -38.45149028
OS 35.8483027 -38.44039556
OS 35.84737814 -38.439471
OS 35.84460446 -38.43577276
OS 35.83998166 -38.43114996
OS 35.8344343 -38.42467804
OS 35.82611326 -38.41820612
OS 35.81686766 -38.41265876
OS 35.8066975 -38.4071114
OS 35.79467822 -38.4024886
OS 35.79375366 -38.4024886
OS 35.79005542 -38.40156404
OS 35.78450806 -38.40063948
OS 35.77711158 -38.39879036
OS 35.76601686 -38.3978658
OS 35.75214846 -38.39694124
OS 35.73550638 -38.39601668
OE
OB 43.44263854 -38.5504182 H
OS 43.43709118 -38.5504182
OS 43.43339294 -38.55134276
OS 43.42322278 -38.55226732
OS 43.4112035 -38.555041
OS 43.39641054 -38.5596638
OS 43.38069302 -38.56613572
OS 43.36590006 -38.57538132
OS 43.3511071 -38.5874006
OS 43.34925798 -38.58924972
OS 43.34555974 -38.59387252
OS 43.33908782 -38.60219356
OS 43.3326159 -38.61328828
OS 43.32521942 -38.62623212
OS 43.3187475 -38.6428742
OS 43.31320014 -38.66228996
OS 43.31042646 -38.68355484
OS 43.57022782 -38.68355484
OS 43.57022782 -38.68263028
OS 43.57022782 -38.68078116
OS 43.56930326 -38.67800748
OS 43.56930326 -38.67430924
OS 43.56745414 -38.66321452
OS 43.56468046 -38.65119524
OS 43.56005766 -38.63640228
OS 43.55543486 -38.62253388
OS 43.54803838 -38.60866548
OS 43.53971734 -38.5966462
OS 43.53971734 -38.59572164
OS 43.53786822 -38.59479708
OS 43.53324542 -38.58924972
OS 43.52492438 -38.58185324
OS 43.51382966 -38.5735322
OS 43.49996126 -38.56521116
OS 43.48331918 -38.55781468
OS 43.46390342 -38.55226732
OS 43.45373326 -38.55134276
OS 43.44263854 -38.5504182
OE
OB 34.35791198 -38.39601668 H
OS 34.20628414 -38.39601668
OS 34.20628414 -38.58832516
OS 34.36345934 -38.58832516
OS 34.37547862 -38.5874006
OS 34.38842246 -38.58647604
OS 34.4013663 -38.58555148
OS 34.41431014 -38.58370236
OS 34.4244803 -38.58185324
OS 34.42632942 -38.58092868
OS 34.43002766 -38.58000412
OS 34.43557502 -38.57723044
OS 34.4429715 -38.5735322
OS 34.45036798 -38.56983396
OS 34.45868902 -38.5642866
OS 34.46701006 -38.55689012
OS 34.47348198 -38.54949364
OS 34.47440654 -38.54856908
OS 34.47625566 -38.5457954
OS 34.47902934 -38.54024804
OS 34.48180302 -38.53377612
OS 34.4845767 -38.52637964
OS 34.48735038 -38.51713404
OS 34.4891995 -38.50603932
OS 34.49012406 -38.49402004
OS 34.49012406 -38.49217092
OS 34.49012406 -38.48847268
OS 34.4891995 -38.48292532
OS 34.48827494 -38.47552884
OS 34.48642582 -38.46628324
OS 34.48365214 -38.45703764
OS 34.4799539 -38.44779204
OS 34.47440654 -38.43854644
OS 34.47348198 -38.43762188
OS 34.47163286 -38.4348482
OS 34.46793462 -38.4302254
OS 34.46331182 -38.4256026
OS 34.4568399 -38.42005524
OS 34.44944342 -38.41450788
OS 34.44019782 -38.40896052
OS 34.43002766 -38.40526228
OS 34.4291031 -38.40526228
OS 34.4244803 -38.40341316
OS 34.41800838 -38.4024886
OS 34.40783822 -38.40063948
OS 34.39396982 -38.39879036
OS 34.3782523 -38.3978658
OS 34.35791198 -38.39601668
OE
OB 40.89732486 -38.39601668 H
OS 40.71426198 -38.39601668
OS 40.71426198 -38.624383
OS 40.88623014 -38.624383
OS 40.89270206 -38.62345844
OS 40.89917398 -38.62345844
OS 40.90657046 -38.62253388
OS 40.9241371 -38.62068476
OS 40.94355286 -38.61698652
OS 40.96296862 -38.61143916
OS 40.98053526 -38.60404268
OS 40.9888563 -38.59941988
OS 40.99532822 -38.59387252
OS 40.99717734 -38.5920234
OS 41.00087558 -38.58832516
OS 41.00642294 -38.58092868
OS 41.01289486 -38.57168308
OS 41.01936678 -38.5596638
OS 41.02491414 -38.54487084
OS 41.02861238 -38.52822876
OS 41.0304615 -38.508813
OS 41.0304615 -38.50788844
OS 41.0304615 -38.50696388
OS 41.0304615 -38.50234108
OS 41.02953694 -38.49402004
OS 41.02768782 -38.48477444
OS 41.0258387 -38.47460428
OS 41.02214046 -38.462585
OS 41.0165931 -38.45149028
OS 41.01012118 -38.44039556
OS 41.00919662 -38.439471
OS 41.00642294 -38.43577276
OS 41.00180014 -38.43114996
OS 40.99625278 -38.42467804
OS 40.98793174 -38.41820612
OS 40.97868614 -38.41265876
OS 40.96851598 -38.4071114
OS 40.9564967 -38.4024886
OS 40.95557214 -38.4024886
OS 40.9518739 -38.40156404
OS 40.94632654 -38.40063948
OS 40.93893006 -38.39879036
OS 40.92783534 -38.3978658
OS 40.91396694 -38.39694124
OS 40.89732486 -38.39601668
OE
OB 33.15136118 -38.39601668 H
OS 32.9682983 -38.39601668
OS 32.9682983 -38.624383
OS 33.14026646 -38.624383
OS 33.14673838 -38.62345844
OS 33.1532103 -38.62345844
OS 33.16060678 -38.62253388
OS 33.17817342 -38.62068476
OS 33.19758918 -38.61698652
OS 33.21700494 -38.61143916
OS 33.23457158 -38.60404268
OS 33.24289262 -38.59941988
OS 33.24936454 -38.59387252
OS 33.25121366 -38.5920234
OS 33.2549119 -38.58832516
OS 33.26045926 -38.58092868
OS 33.26693118 -38.57168308
OS 33.2734031 -38.5596638
OS 33.27895046 -38.54487084
OS 33.2826487 -38.52822876
OS 33.28449782 -38.508813
OS 33.28449782 -38.50788844
OS 33.28449782 -38.50696388
OS 33.28449782 -38.50234108
OS 33.28357326 -38.49402004
OS 33.28172414 -38.48477444
OS 33.27987502 -38.47460428
OS 33.27617678 -38.462585
OS 33.27062942 -38.45149028
OS 33.2641575 -38.44039556
OS 33.26323294 -38.439471
OS 33.26045926 -38.43577276
OS 33.25583646 -38.43114996
OS 33.2502891 -38.42467804
OS 33.24196806 -38.41820612
OS 33.23272246 -38.41265876
OS 33.2225523 -38.4071114
OS 33.21053302 -38.4024886
OS 33.20960846 -38.4024886
OS 33.20591022 -38.40156404
OS 33.20036286 -38.40063948
OS 33.19296638 -38.39879036
OS 33.18187166 -38.3978658
OS 33.16800326 -38.39694124
OS 33.15136118 -38.39601668
OE
OB 34.37455406 -38.66413908 H
OS 34.20628414 -38.66413908
OS 34.20628414 -38.88418436
OS 34.38842246 -38.88418436
OS 34.40783822 -38.8832598
OS 34.41615926 -38.88233524
OS 34.42355574 -38.88141068
OS 34.4244803 -38.88141068
OS 34.42817854 -38.88048612
OS 34.4337259 -38.87956156
OS 34.44019782 -38.87771244
OS 34.45591534 -38.87216508
OS 34.47163286 -38.8647686
OS 34.47255742 -38.86384404
OS 34.4753311 -38.86199492
OS 34.47902934 -38.85922124
OS 34.48365214 -38.855523
OS 34.48827494 -38.84997564
OS 34.49474686 -38.84442828
OS 34.49936966 -38.8370318
OS 34.50491702 -38.82871076
OS 34.50584158 -38.8277862
OS 34.50676614 -38.82501252
OS 34.50861526 -38.81946516
OS 34.51138894 -38.81299324
OS 34.51416262 -38.80559676
OS 34.51601174 -38.79635116
OS 34.5169363 -38.78525644
OS 34.51786086 -38.77416172
OS 34.51786086 -38.7723126
OS 34.51786086 -38.76861436
OS 34.5169363 -38.76121788
OS 34.51508718 -38.75289684
OS 34.51323806 -38.74365124
OS 34.50953982 -38.73348108
OS 34.50491702 -38.72331092
OS 34.4984451 -38.71314076
OS 34.49752054 -38.7122162
OS 34.49474686 -38.70851796
OS 34.49104862 -38.70389516
OS 34.48550126 -38.6983478
OS 34.47810478 -38.69187588
OS 34.46885918 -38.68540396
OS 34.45868902 -38.6798566
OS 34.44666974 -38.6752338
OS 34.44482062 -38.67430924
OS 34.44112238 -38.67338468
OS 34.43280134 -38.67153556
OS 34.42263118 -38.66968644
OS 34.40968734 -38.66783732
OS 34.39396982 -38.6659882
OS 34.37455406 -38.66413908
OE
SE
S P 0
OB 48.49040086 -36.61402634 I
OS 48.17420134 -36.61402634
OS 48.17420134 -37.45999874
OS 48.04661206 -37.45999874
OS 48.04661206 -36.61402634
OS 47.73041254 -36.61402634
OS 47.73041254 -36.50030546
OS 48.49040086 -36.50030546
OS 48.49040086 -36.61402634
OE
OB 47.69990206 -37.45999874 I
OS 47.5556707 -37.45999874
OS 47.44333666 -37.16876234
OS 47.04115306 -37.16876234
OS 46.93714006 -37.45999874
OS 46.80261658 -37.45999874
OS 47.16874234 -36.50030546
OS 47.30742634 -36.50030546
OS 47.69990206 -37.45999874
OE
OB 49.31834434 -36.61402634 I
OS 48.75112678 -36.61402634
OS 48.75112678 -36.90664958
OS 49.2822865 -36.90664958
OS 49.2822865 -37.02037046
OS 48.75112678 -37.02037046
OS 48.75112678 -37.34627786
OS 49.34053378 -37.34627786
OS 49.34053378 -37.45999874
OS 48.6235375 -37.45999874
OS 48.6235375 -36.50030546
OS 49.31834434 -36.50030546
OS 49.31834434 -36.61402634
OE
OB 46.33386466 -36.5016923 I
OS 46.36160146 -36.50307914
OS 46.38933826 -36.50585282
OS 46.41707506 -36.51001334
OS 46.44065134 -36.51417386
OS 46.44203818 -36.51417386
OS 46.44481186 -36.5155607
OS 46.44897238 -36.5155607
OS 46.45451974 -36.51833438
OS 46.46977498 -36.5224949
OS 46.48919074 -36.5294291
OS 46.51138018 -36.53913698
OS 46.53495646 -36.55161854
OS 46.55853274 -36.56548694
OS 46.58072218 -36.58351586
OS 46.58210902 -36.5849027
OS 46.58349586 -36.58628954
OS 46.58765638 -36.59045006
OS 46.59320374 -36.59461058
OS 46.60707214 -36.60847898
OS 46.62371422 -36.62789474
OS 46.64174314 -36.65147102
OS 46.6611589 -36.67920782
OS 46.67918782 -36.71110514
OS 46.69444306 -36.74716298
OS 46.69444306 -36.74854982
OS 46.6958299 -36.7513235
OS 46.69860358 -36.75687086
OS 46.69999042 -36.7651919
OS 46.70415094 -36.77489978
OS 46.70692462 -36.7859945
OS 46.7096983 -36.79847606
OS 46.71385882 -36.8137313
OS 46.71801934 -36.82898654
OS 46.72079302 -36.84701546
OS 46.72772722 -36.88584698
OS 46.73188774 -36.92883902
OS 46.73327458 -36.97599158
OS 46.73327458 -36.97737842
OS 46.73327458 -36.9801521
OS 46.73327458 -36.9870863
OS 46.73327458 -36.9940205
OS 46.73188774 -37.00372838
OS 46.73188774 -37.0148231
OS 46.7305009 -37.04117306
OS 46.72634038 -37.07168354
OS 46.72217986 -37.10358086
OS 46.71524566 -37.13686502
OS 46.70692462 -37.17014918
OS 46.70692462 -37.17153602
OS 46.70553778 -37.1743097
OS 46.70415094 -37.17847022
OS 46.7027641 -37.18401758
OS 46.69721674 -37.19927282
OS 46.6888957 -37.21868858
OS 46.68057466 -37.24087802
OS 46.66947994 -37.26306746
OS 46.65561154 -37.28664374
OS 46.64174314 -37.30883318
OS 46.6403563 -37.31160686
OS 46.63480894 -37.31854106
OS 46.6264879 -37.32824894
OS 46.61539318 -37.3407305
OS 46.60291162 -37.3545989
OS 46.58765638 -37.3684673
OS 46.57240114 -37.38372254
OS 46.55437222 -37.3962041
OS 46.55159854 -37.39759094
OS 46.54605118 -37.40175146
OS 46.5363433 -37.40729882
OS 46.5224749 -37.41423302
OS 46.50583282 -37.42255406
OS 46.48641706 -37.42948826
OS 46.46422762 -37.4378093
OS 46.4392645 -37.4447435
OS 46.43649082 -37.4447435
OS 46.4323303 -37.44613034
OS 46.42816978 -37.44751718
OS 46.41430138 -37.44890402
OS 46.39488562 -37.4516777
OS 46.37269618 -37.45445138
OS 46.34634622 -37.45722506
OS 46.31722258 -37.4586119
OS 46.28532526 -37.45999874
OS 45.9400021 -37.45999874
OS 45.9400021 -36.50030546
OS 46.30890154 -36.50030546
OS 46.33386466 -36.5016923
OE
OB 46.28948578 -36.61402634 H
OS 46.06759138 -36.61402634
OS 46.06759138 -37.34627786
OS 46.29503314 -37.34627786
OS 46.30474102 -37.34489102
OS 46.32554362 -37.34350418
OS 46.3491199 -37.34211734
OS 46.37408302 -37.33934366
OS 46.39904614 -37.33518314
OS 46.41984874 -37.32963578
OS 46.42262242 -37.32824894
OS 46.42955662 -37.3268621
OS 46.4392645 -37.32270158
OS 46.45174606 -37.31715422
OS 46.46561446 -37.30883318
OS 46.47948286 -37.30051214
OS 46.49335126 -37.29080426
OS 46.50721966 -37.27970954
OS 46.5086065 -37.27693586
OS 46.51415386 -37.2713885
OS 46.5224749 -37.26168062
OS 46.53218278 -37.24781222
OS 46.5432775 -37.2297833
OS 46.55575906 -37.2089807
OS 46.56685378 -37.18540442
OS 46.57656166 -37.15905446
OS 46.57656166 -37.15766762
OS 46.5779485 -37.15489394
OS 46.57933534 -37.15073342
OS 46.58072218 -37.14518606
OS 46.58210902 -37.13825186
OS 46.5848827 -37.12854398
OS 46.58765638 -37.1188361
OS 46.59043006 -37.10774138
OS 46.59459058 -37.08000458
OS 46.5987511 -37.04810726
OS 46.60152478 -37.01204942
OS 46.60291162 -36.9732179
OS 46.60291162 -36.97183106
OS 46.60291162 -36.9662837
OS 46.60291162 -36.9593495
OS 46.60152478 -36.94825478
OS 46.60152478 -36.93577322
OS 46.60013794 -36.92190482
OS 46.5987511 -36.90526274
OS 46.59736426 -36.88862066
OS 46.59043006 -36.85117598
OS 46.58210902 -36.81234446
OS 46.56962746 -36.77628662
OS 46.56130642 -36.7582577
OS 46.55298538 -36.74300246
OS 46.55298538 -36.74161562
OS 46.5502117 -36.73884194
OS 46.54743802 -36.73468142
OS 46.54466434 -36.72913406
OS 46.53356962 -36.71526566
OS 46.51970122 -36.69862358
OS 46.5016723 -36.68059466
OS 46.4808697 -36.66256574
OS 46.45729342 -36.6473105
OS 46.4323303 -36.63482894
OS 46.42955662 -36.6334421
OS 46.42262242 -36.63205526
OS 46.41014086 -36.62789474
OS 46.39211194 -36.62373422
OS 46.3699225 -36.62096054
OS 46.3421857 -36.61680002
OS 46.32554362 -36.61541318
OS 46.3075147 -36.61541318
OS 46.28948578 -36.61402634
OE
OB 47.23531066 -36.60015794 H
OS 47.23531066 -36.60154478
OS 47.23392382 -36.60431846
OS 47.23392382 -36.60986582
OS 47.23115014 -36.61541318
OS 47.2297633 -36.62512106
OS 47.22698962 -36.63482894
OS 47.22144226 -36.65840522
OS 47.21450806 -36.68614202
OS 47.20480018 -36.7166525
OS 47.1950923 -36.74993666
OS 47.18261074 -36.78460766
OS 47.07859774 -37.06474934
OS 47.4031183 -37.06474934
OS 47.30326582 -36.80124974
OS 47.30326582 -36.7998629
OS 47.30187898 -36.79570238
OS 47.2991053 -36.78876818
OS 47.29633162 -36.78044714
OS 47.2921711 -36.77073926
OS 47.28801058 -36.7582577
OS 47.28385006 -36.7443893
OS 47.2783027 -36.7305209
OS 47.26720798 -36.69862358
OS 47.25611326 -36.66533942
OS 47.24501854 -36.63205526
OS 47.23531066 -36.60015794
OE
SE
S P 0
OB 53.57408132 -38.30725892 I
OS 53.5861006 -38.30910804
OS 53.60089356 -38.31188172
OS 53.61753564 -38.31650452
OS 53.63417772 -38.32205188
OS 53.6508198 -38.32944836
OS 53.65174436 -38.32944836
OS 53.65266892 -38.33037292
OS 53.65821628 -38.3331466
OS 53.66653732 -38.33869396
OS 53.67578292 -38.34516588
OS 53.68687764 -38.35441148
OS 53.69797236 -38.36458164
OS 53.70906708 -38.37660092
OS 53.71831268 -38.39046932
OS 53.71923724 -38.39231844
OS 53.72201092 -38.39694124
OS 53.72570916 -38.40526228
OS 53.73033196 -38.41543244
OS 53.73495476 -38.42745172
OS 53.738653 -38.44132012
OS 53.74142668 -38.45703764
OS 53.74235124 -38.47275516
OS 53.74235124 -38.47460428
OS 53.74235124 -38.48015164
OS 53.74142668 -38.48754812
OS 53.73957756 -38.49771828
OS 53.73680388 -38.50973756
OS 53.73218108 -38.5226814
OS 53.72663372 -38.53562524
OS 53.71923724 -38.54856908
OS 53.71831268 -38.5504182
OS 53.715539 -38.55411644
OS 53.70999164 -38.56058836
OS 53.70259516 -38.56798484
OS 53.69334956 -38.57630588
OS 53.68225484 -38.58555148
OS 53.669311 -38.59387252
OS 53.65359348 -38.60219356
OS 53.65451804 -38.60219356
OS 53.65636716 -38.60311812
OS 53.65914084 -38.60404268
OS 53.66283908 -38.60496724
OS 53.67300924 -38.60866548
OS 53.68595308 -38.61421284
OS 53.70074604 -38.62160932
OS 53.715539 -38.63085492
OS 53.7294074 -38.6428742
OS 53.74235124 -38.6567426
OS 53.7432758 -38.65859172
OS 53.74697404 -38.66413908
OS 53.7525214 -38.67338468
OS 53.75806876 -38.68540396
OS 53.76361612 -38.70019692
OS 53.76916348 -38.71776356
OS 53.77286172 -38.73810388
OS 53.77378628 -38.76029332
OS 53.77378628 -38.76121788
OS 53.77378628 -38.76399156
OS 53.77378628 -38.76861436
OS 53.77286172 -38.77416172
OS 53.77193716 -38.7815582
OS 53.77008804 -38.78987924
OS 53.76823892 -38.79912484
OS 53.7663898 -38.809295
OS 53.75899332 -38.83148444
OS 53.75344596 -38.84350372
OS 53.7478986 -38.85459844
OS 53.74050212 -38.86661772
OS 53.73218108 -38.878637
OS 53.72293548 -38.89065628
OS 53.71184076 -38.901751
OS 53.7109162 -38.90267556
OS 53.70906708 -38.90452468
OS 53.70536884 -38.90729836
OS 53.70074604 -38.9109966
OS 53.69519868 -38.9156194
OS 53.6878022 -38.9202422
OS 53.67948116 -38.92578956
OS 53.669311 -38.93041236
OS 53.65914084 -38.93595972
OS 53.64712156 -38.94150708
OS 53.63510228 -38.94612988
OS 53.62123388 -38.95075268
OS 53.60644092 -38.95445092
OS 53.5907234 -38.9572246
OS 53.57500588 -38.95907372
OS 53.55743924 -38.95999828
OS 53.5491182 -38.95999828
OS 53.54357084 -38.95907372
OS 53.53617436 -38.95814916
OS 53.52785332 -38.9572246
OS 53.51860772 -38.95537548
OS 53.50843756 -38.95352636
OS 53.48624812 -38.947979
OS 53.46313412 -38.9387334
OS 53.45111484 -38.93318604
OS 53.44002012 -38.92671412
OS 53.4289254 -38.91839308
OS 53.41783068 -38.91007204
OS 53.41690612 -38.90914748
OS 53.415057 -38.90729836
OS 53.41228332 -38.90452468
OS 53.40950964 -38.90082644
OS 53.40488684 -38.89620364
OS 53.40026404 -38.88973172
OS 53.39471668 -38.8832598
OS 53.38916932 -38.87493876
OS 53.38362196 -38.86569316
OS 53.3780746 -38.85644756
OS 53.36790444 -38.83425812
OS 53.3595834 -38.80837044
OS 53.35680972 -38.79450204
OS 53.3549606 -38.77970908
OS 53.4335482 -38.76953892
OS 53.4335482 -38.77046348
OS 53.43447276 -38.7723126
OS 53.43539732 -38.77601084
OS 53.43632188 -38.78063364
OS 53.43724644 -38.786181
OS 53.43909556 -38.79265292
OS 53.44371836 -38.80652132
OS 53.45019028 -38.8231634
OS 53.45851132 -38.83888092
OS 53.46775692 -38.85367388
OS 53.47885164 -38.86661772
OS 53.48070076 -38.86754228
OS 53.484399 -38.87124052
OS 53.49179548 -38.87586332
OS 53.50104108 -38.88048612
OS 53.5121358 -38.88603348
OS 53.5260042 -38.89065628
OS 53.54172172 -38.89435452
OS 53.5583638 -38.89527908
OS 53.56391116 -38.89527908
OS 53.5676094 -38.89435452
OS 53.57777956 -38.89342996
OS 53.5907234 -38.89065628
OS 53.60551636 -38.88603348
OS 53.62123388 -38.87956156
OS 53.6369514 -38.87031596
OS 53.65174436 -38.85737212
OS 53.65359348 -38.855523
OS 53.65821628 -38.84997564
OS 53.66376364 -38.8416546
OS 53.67116012 -38.83055988
OS 53.6785566 -38.81669148
OS 53.68410396 -38.80097396
OS 53.68872676 -38.78248276
OS 53.69057588 -38.76214244
OS 53.69057588 -38.76121788
OS 53.69057588 -38.75936876
OS 53.69057588 -38.75659508
OS 53.68965132 -38.75289684
OS 53.68872676 -38.74272668
OS 53.68595308 -38.7307074
OS 53.68225484 -38.71591444
OS 53.67578292 -38.70112148
OS 53.66653732 -38.68632852
OS 53.65451804 -38.67246012
OS 53.65266892 -38.670611
OS 53.64804612 -38.66691276
OS 53.64064964 -38.6613654
OS 53.63047948 -38.65489348
OS 53.61753564 -38.64842156
OS 53.60181812 -38.6428742
OS 53.58425148 -38.63917596
OS 53.56483572 -38.63732684
OS 53.55651468 -38.63732684
OS 53.55004276 -38.6382514
OS 53.54172172 -38.63917596
OS 53.53247612 -38.64102508
OS 53.5213814 -38.6428742
OS 53.50936212 -38.64564788
OS 53.51860772 -38.57630588
OS 53.52323052 -38.57630588
OS 53.52692876 -38.57723044
OS 53.53894804 -38.57723044
OS 53.5491182 -38.57538132
OS 53.56113748 -38.5735322
OS 53.57500588 -38.57075852
OS 53.5907234 -38.56613572
OS 53.60551636 -38.5596638
OS 53.62123388 -38.55134276
OS 53.62215844 -38.55134276
OS 53.623083 -38.5504182
OS 53.6277058 -38.54671996
OS 53.63417772 -38.54024804
OS 53.6415742 -38.531927
OS 53.64897068 -38.51990772
OS 53.6554426 -38.50603932
OS 53.6600654 -38.4903218
OS 53.66191452 -38.4810762
OS 53.66191452 -38.47090604
OS 53.66191452 -38.46998148
OS 53.66191452 -38.46905692
OS 53.66191452 -38.46350956
OS 53.6600654 -38.45611308
OS 53.65821628 -38.44594292
OS 53.65451804 -38.4348482
OS 53.64989524 -38.42282892
OS 53.64249876 -38.41080964
OS 53.6323286 -38.39971492
OS 53.63140404 -38.39879036
OS 53.62678124 -38.39509212
OS 53.62030932 -38.39046932
OS 53.61198828 -38.38492196
OS 53.60089356 -38.38029916
OS 53.58794972 -38.37567636
OS 53.57315676 -38.37197812
OS 53.55651468 -38.37105356
OS 53.5491182 -38.37105356
OS 53.54079716 -38.37290268
OS 53.52970244 -38.3747518
OS 53.51768316 -38.37845004
OS 53.50566388 -38.38307284
OS 53.49272004 -38.39046932
OS 53.48070076 -38.39971492
OS 53.4797762 -38.40063948
OS 53.47607796 -38.40526228
OS 53.4705306 -38.4117342
OS 53.46405868 -38.4209798
OS 53.45758676 -38.43299908
OS 53.45111484 -38.44779204
OS 53.44556748 -38.46535868
OS 53.44186924 -38.485699
OS 53.36328164 -38.4718306
OS 53.36328164 -38.47090604
OS 53.3642062 -38.46813236
OS 53.36513076 -38.46443412
OS 53.36605532 -38.45888676
OS 53.36790444 -38.45241484
OS 53.37067812 -38.44501836
OS 53.37622548 -38.42745172
OS 53.38547108 -38.4071114
OS 53.3965658 -38.38677108
OS 53.4104342 -38.36735532
OS 53.42800084 -38.34978868
OS 53.4289254 -38.34886412
OS 53.43077452 -38.34793956
OS 53.4335482 -38.34609044
OS 53.43724644 -38.34331676
OS 53.44186924 -38.33961852
OS 53.44834116 -38.33592028
OS 53.45481308 -38.33222204
OS 53.46313412 -38.32759924
OS 53.48162532 -38.32020276
OS 53.5028902 -38.31280628
OS 53.52785332 -38.30818348
OS 53.54079716 -38.30633436
OS 53.56391116 -38.30633436
OS 53.57408132 -38.30725892
OE
OB 54.07889108 -38.30725892 I
OS 54.09091036 -38.30910804
OS 54.10477876 -38.31188172
OS 54.11957172 -38.31557996
OS 54.13528924 -38.32020276
OS 54.1500822 -38.32759924
OS 54.15100676 -38.32759924
OS 54.15193132 -38.3285238
OS 54.15655412 -38.33129748
OS 54.1639506 -38.33592028
OS 54.1731962 -38.3423922
OS 54.18336636 -38.3516378
OS 54.19446108 -38.36180796
OS 54.20463124 -38.37382724
OS 54.2148014 -38.38769564
OS 54.21572596 -38.38954476
OS 54.2194242 -38.39416756
OS 54.22312244 -38.4024886
OS 54.22959436 -38.41450788
OS 54.23514172 -38.42837628
OS 54.2425382 -38.4440938
OS 54.24901012 -38.462585
OS 54.25455748 -38.48292532
OS 54.25455748 -38.48384988
OS 54.25548204 -38.485699
OS 54.2564066 -38.48847268
OS 54.25733116 -38.49309548
OS 54.25825572 -38.49864284
OS 54.25918028 -38.50511476
OS 54.2610294 -38.5134358
OS 54.26195396 -38.5226814
OS 54.26380308 -38.53285156
OS 54.26472764 -38.54394628
OS 54.2656522 -38.55689012
OS 54.26750132 -38.56983396
OS 54.26842588 -38.58462692
OS 54.26842588 -38.59941988
OS 54.26935044 -38.61606196
OS 54.26935044 -38.6336286
OS 54.26935044 -38.63455316
OS 54.26935044 -38.6382514
OS 54.26935044 -38.64472332
OS 54.26935044 -38.6521198
OS 54.26842588 -38.66228996
OS 54.26842588 -38.67338468
OS 54.26750132 -38.68540396
OS 54.26657676 -38.6983478
OS 54.26380308 -38.72793372
OS 54.25918028 -38.7584442
OS 54.25363292 -38.78803012
OS 54.24993468 -38.80189852
OS 54.24531188 -38.81576692
OS 54.24531188 -38.81669148
OS 54.24438732 -38.8185406
OS 54.2425382 -38.82223884
OS 54.24068908 -38.82686164
OS 54.23883996 -38.83333356
OS 54.23514172 -38.83980548
OS 54.22774524 -38.855523
OS 54.21849964 -38.87216508
OS 54.20648036 -38.89065628
OS 54.19261196 -38.90729836
OS 54.17596988 -38.92301588
OS 54.17504532 -38.92301588
OS 54.17412076 -38.924865
OS 54.17134708 -38.92671412
OS 54.16764884 -38.92856324
OS 54.16302604 -38.93133692
OS 54.15840324 -38.93503516
OS 54.14453484 -38.94150708
OS 54.12789276 -38.947979
OS 54.108477 -38.95445092
OS 54.085363 -38.95814916
OS 54.06039988 -38.95999828
OS 54.05115428 -38.95999828
OS 54.04468236 -38.95907372
OS 54.03728588 -38.95814916
OS 54.02804028 -38.95630004
OS 54.01787012 -38.95445092
OS 54.0067754 -38.95167724
OS 53.99568068 -38.947979
OS 53.9836614 -38.94428076
OS 53.97164212 -38.9387334
OS 53.95962284 -38.93226148
OS 53.94760356 -38.924865
OS 53.93558428 -38.9156194
OS 53.92448956 -38.90544924
OS 53.9143194 -38.89435452
OS 53.91339484 -38.89342996
OS 53.91154572 -38.89065628
OS 53.90877204 -38.88603348
OS 53.90414924 -38.878637
OS 53.89952644 -38.87031596
OS 53.89490364 -38.85922124
OS 53.88843172 -38.8462774
OS 53.88288436 -38.83148444
OS 53.877337 -38.81484236
OS 53.87178964 -38.7954266
OS 53.86624228 -38.77416172
OS 53.86161948 -38.75012316
OS 53.85699668 -38.72423548
OS 53.854223 -38.69649868
OS 53.85237388 -38.6659882
OS 53.85144932 -38.6336286
OS 53.85144932 -38.63270404
OS 53.85144932 -38.6290058
OS 53.85144932 -38.62253388
OS 53.85144932 -38.6151374
OS 53.85237388 -38.60496724
OS 53.85237388 -38.59387252
OS 53.85329844 -38.58185324
OS 53.854223 -38.56798484
OS 53.85699668 -38.53932348
OS 53.86161948 -38.508813
OS 53.86716684 -38.47830252
OS 53.87086508 -38.46443412
OS 53.87456332 -38.45056572
OS 53.87456332 -38.44964116
OS 53.87548788 -38.44779204
OS 53.877337 -38.4440938
OS 53.87918612 -38.439471
OS 53.88103524 -38.43299908
OS 53.88473348 -38.42652716
OS 53.89212996 -38.41080964
OS 53.90137556 -38.39416756
OS 53.91339484 -38.37660092
OS 53.92726324 -38.35903428
OS 53.94390532 -38.34424132
OS 53.94482988 -38.34424132
OS 53.94575444 -38.3423922
OS 53.94852812 -38.34054308
OS 53.95222636 -38.33869396
OS 53.95684916 -38.33499572
OS 53.96239652 -38.33222204
OS 53.97626492 -38.32482556
OS 53.992907 -38.31835364
OS 54.01232276 -38.31188172
OS 54.03543676 -38.30818348
OS 54.06039988 -38.30633436
OS 54.06872092 -38.30633436
OS 54.07889108 -38.30725892
OE
OB 53.23846604 -38.94890356 I
OS 53.14878372 -38.94890356
OS 53.14878372 -38.85922124
OS 53.23846604 -38.85922124
OS 53.23846604 -38.94890356
OE
OB 53.00177868 -38.39231844 I
OS 52.74567556 -38.39231844
OS 52.71146684 -38.56521116
OS 52.7123914 -38.5642866
OS 52.71424052 -38.56336204
OS 52.7170142 -38.56151292
OS 52.721637 -38.55873924
OS 52.72718436 -38.55596556
OS 52.73365628 -38.55226732
OS 52.74844924 -38.54487084
OS 52.76694044 -38.53747436
OS 52.78728076 -38.53100244
OS 52.8094702 -38.52637964
OS 52.82056492 -38.52453052
OS 52.84090524 -38.52453052
OS 52.8464526 -38.52545508
OS 52.85384908 -38.52637964
OS 52.86217012 -38.5273042
OS 52.87141572 -38.52915332
OS 52.88158588 -38.531927
OS 52.90377532 -38.53839892
OS 52.9157946 -38.54302172
OS 52.92781388 -38.54949364
OS 52.93983316 -38.55596556
OS 52.95185244 -38.56336204
OS 52.96294716 -38.57260764
OS 52.97404188 -38.5827778
OS 52.97496644 -38.58370236
OS 52.97681556 -38.58555148
OS 52.97958924 -38.58832516
OS 52.98328748 -38.59294796
OS 52.98791028 -38.59941988
OS 52.99253308 -38.6058918
OS 52.99808044 -38.61421284
OS 53.0036278 -38.62345844
OS 53.0082506 -38.6336286
OS 53.01379796 -38.64472332
OS 53.01842076 -38.65766716
OS 53.02304356 -38.670611
OS 53.0267418 -38.6844794
OS 53.02951548 -38.70019692
OS 53.0313646 -38.71591444
OS 53.03228916 -38.73255652
OS 53.03228916 -38.73348108
OS 53.03228916 -38.73625476
OS 53.03228916 -38.74087756
OS 53.0313646 -38.74734948
OS 53.03044004 -38.75474596
OS 53.02951548 -38.763067
OS 53.02766636 -38.77323716
OS 53.02581724 -38.78340732
OS 53.02026988 -38.80744588
OS 53.01102428 -38.832409
OS 53.00547692 -38.84535284
OS 52.99808044 -38.85737212
OS 52.99068396 -38.87031596
OS 52.98143836 -38.88233524
OS 52.9805138 -38.8832598
OS 52.97866468 -38.88603348
OS 52.97496644 -38.88973172
OS 52.97034364 -38.89435452
OS 52.96387172 -38.89990188
OS 52.95647524 -38.90729836
OS 52.94722964 -38.91377028
OS 52.93705948 -38.92116676
OS 52.92596476 -38.92856324
OS 52.91302092 -38.93503516
OS 52.89915252 -38.94150708
OS 52.88435956 -38.947979
OS 52.86864204 -38.9526018
OS 52.8510754 -38.95630004
OS 52.8325842 -38.95907372
OS 52.81316844 -38.95999828
OS 52.8048474 -38.95999828
OS 52.79837548 -38.95907372
OS 52.790979 -38.95814916
OS 52.78265796 -38.9572246
OS 52.7724878 -38.95630004
OS 52.76231764 -38.95352636
OS 52.73920364 -38.947979
OS 52.71608964 -38.93965796
OS 52.70407036 -38.9341106
OS 52.69205108 -38.92763868
OS 52.68095636 -38.9202422
OS 52.66986164 -38.91192116
OS 52.66893708 -38.9109966
OS 52.66708796 -38.91007204
OS 52.66523884 -38.9063738
OS 52.6615406 -38.90267556
OS 52.6569178 -38.89805276
OS 52.652295 -38.8925054
OS 52.64674764 -38.88510892
OS 52.64212484 -38.87678788
OS 52.63657748 -38.86846684
OS 52.63103012 -38.85829668
OS 52.62085996 -38.83610724
OS 52.61253892 -38.81021956
OS 52.60976524 -38.79635116
OS 52.60791612 -38.7815582
OS 52.69020196 -38.77508628
OS 52.69020196 -38.77601084
OS 52.69020196 -38.77785996
OS 52.69112652 -38.78063364
OS 52.69205108 -38.78525644
OS 52.69482476 -38.7954266
OS 52.698523 -38.809295
OS 52.70407036 -38.8231634
OS 52.71146684 -38.83888092
OS 52.72071244 -38.85274932
OS 52.73180716 -38.86569316
OS 52.73365628 -38.86661772
OS 52.73735452 -38.87031596
OS 52.744751 -38.87493876
OS 52.75492116 -38.88048612
OS 52.76601588 -38.88603348
OS 52.77988428 -38.89065628
OS 52.7956018 -38.89435452
OS 52.81316844 -38.89527908
OS 52.8187158 -38.89527908
OS 52.82241404 -38.89435452
OS 52.83350876 -38.89342996
OS 52.8464526 -38.88973172
OS 52.86217012 -38.88510892
OS 52.87788764 -38.87771244
OS 52.89452972 -38.86661772
OS 52.9019262 -38.8601458
OS 52.90932268 -38.85274932
OS 52.91024724 -38.85182476
OS 52.9111718 -38.8509002
OS 52.91302092 -38.84812652
OS 52.9157946 -38.84535284
OS 52.92226652 -38.83518268
OS 52.929663 -38.82223884
OS 52.93613492 -38.80652132
OS 52.94260684 -38.78710556
OS 52.94722964 -38.76399156
OS 52.94907876 -38.75197228
OS 52.94907876 -38.73902844
OS 52.94907876 -38.73810388
OS 52.94907876 -38.73625476
OS 52.94907876 -38.73255652
OS 52.9481542 -38.72793372
OS 52.9481542 -38.72238636
OS 52.94722964 -38.71591444
OS 52.94445596 -38.70112148
OS 52.93983316 -38.68355484
OS 52.93336124 -38.6659882
OS 52.92411564 -38.64934612
OS 52.9111718 -38.6336286
OS 52.9111718 -38.63270404
OS 52.90932268 -38.63177948
OS 52.90469988 -38.62715668
OS 52.89637884 -38.62068476
OS 52.88528412 -38.61328828
OS 52.87049116 -38.60681636
OS 52.85384908 -38.60034444
OS 52.83443332 -38.59572164
OS 52.8233386 -38.59387252
OS 52.80577196 -38.59387252
OS 52.79837548 -38.59479708
OS 52.78912988 -38.59572164
OS 52.77803516 -38.59849532
OS 52.76694044 -38.601269
OS 52.75492116 -38.6058918
OS 52.74290188 -38.61143916
OS 52.74197732 -38.61236372
OS 52.73827908 -38.61421284
OS 52.73273172 -38.61883564
OS 52.72533524 -38.62345844
OS 52.71793876 -38.62993036
OS 52.71054228 -38.6382514
OS 52.70222124 -38.64657244
OS 52.69574932 -38.6567426
OS 52.62178452 -38.64657244
OS 52.68373004 -38.31742908
OS 53.00177868 -38.31742908
OS 53.00177868 -38.39231844
OE
OB 53.23846604 -38.57445676 I
OS 53.14878372 -38.57445676
OS 53.14878372 -38.48477444
OS 53.23846604 -38.48477444
OS 53.23846604 -38.57445676
OE
OB 54.48199924 -38.57445676 I
OS 54.39231692 -38.57445676
OS 54.39231692 -38.48477444
OS 54.48199924 -38.48477444
OS 54.48199924 -38.57445676
OE
OB 56.14990548 -38.3100326 I
OS 56.165623 -38.31095716
OS 56.18226508 -38.31188172
OS 56.1979826 -38.31373084
OS 56.211851 -38.31557996
OS 56.21370012 -38.31557996
OS 56.22017204 -38.31742908
OS 56.22849308 -38.3192782
OS 56.2395878 -38.32205188
OS 56.25160708 -38.32667468
OS 56.26455092 -38.33222204
OS 56.27841932 -38.33869396
OS 56.2904386 -38.34609044
OS 56.29228772 -38.347015
OS 56.29598596 -38.34978868
OS 56.30153332 -38.35533604
OS 56.3089298 -38.36180796
OS 56.31725084 -38.370129
OS 56.32557188 -38.38122372
OS 56.33481748 -38.393243
OS 56.34221396 -38.4071114
OS 56.34313852 -38.40896052
OS 56.34498764 -38.41358332
OS 56.34868588 -38.42190436
OS 56.35238412 -38.43299908
OS 56.3551578 -38.44594292
OS 56.35885604 -38.46073588
OS 56.36070516 -38.47737796
OS 56.36162972 -38.4949446
OS 56.36162972 -38.49586916
OS 56.36162972 -38.49864284
OS 56.36162972 -38.50234108
OS 56.36070516 -38.508813
OS 56.3597806 -38.51528492
OS 56.35885604 -38.52360596
OS 56.35700692 -38.53285156
OS 56.3551578 -38.54302172
OS 56.34868588 -38.5642866
OS 56.34498764 -38.57538132
OS 56.33944028 -38.5874006
OS 56.33296836 -38.59941988
OS 56.32649644 -38.6105146
OS 56.3181754 -38.62160932
OS 56.3089298 -38.63270404
OS 56.30800524 -38.6336286
OS 56.30615612 -38.63547772
OS 56.30338244 -38.6382514
OS 56.29875964 -38.64102508
OS 56.29321228 -38.64564788
OS 56.2858158 -38.65027068
OS 56.2765702 -38.65581804
OS 56.26640004 -38.66044084
OS 56.25438076 -38.6659882
OS 56.24051236 -38.67153556
OS 56.2257194 -38.67615836
OS 56.20815276 -38.6798566
OS 56.18966156 -38.68355484
OS 56.16932124 -38.68632852
OS 56.14620724 -38.68817764
OS 56.12216868 -38.6891022
OS 55.95852156 -38.6891022
OS 55.95852156 -38.94890356
OS 55.87346204 -38.94890356
OS 55.87346204 -38.30910804
OS 56.13603708 -38.30910804
OS 56.14990548 -38.3100326
OE
OB 57.07723916 -38.94890356 I
OS 56.99587788 -38.94890356
OS 56.99587788 -38.41358332
OS 56.80911676 -38.94890356
OS 56.73330284 -38.94890356
OS 56.54839084 -38.40433772
OS 56.54839084 -38.94890356
OS 56.46702956 -38.94890356
OS 56.46702956 -38.30910804
OS 56.59369428 -38.30910804
OS 56.74532212 -38.763067
OS 56.74532212 -38.76399156
OS 56.74624668 -38.76584068
OS 56.74717124 -38.76861436
OS 56.74902036 -38.77323716
OS 56.7527186 -38.78433188
OS 56.7573414 -38.79820028
OS 56.7619642 -38.8139178
OS 56.76751156 -38.82963532
OS 56.77213436 -38.84442828
OS 56.7758326 -38.85737212
OS 56.77675716 -38.855523
OS 56.77768172 -38.8509002
OS 56.7804554 -38.84257916
OS 56.78415364 -38.83148444
OS 56.78877644 -38.81669148
OS 56.79524836 -38.79912484
OS 56.80172028 -38.77878452
OS 56.81004132 -38.75474596
OS 56.96351828 -38.30910804
OS 57.07723916 -38.30910804
OS 57.07723916 -38.94890356
OE
OB 55.3150278 -38.30725892 I
OS 55.32704708 -38.30910804
OS 55.34184004 -38.31188172
OS 55.35848212 -38.31650452
OS 55.3751242 -38.32205188
OS 55.39176628 -38.32944836
OS 55.39269084 -38.32944836
OS 55.3936154 -38.33037292
OS 55.39916276 -38.3331466
OS 55.4074838 -38.33869396
OS 55.4167294 -38.34516588
OS 55.42782412 -38.35441148
OS 55.43891884 -38.36458164
OS 55.45001356 -38.37660092
OS 55.45925916 -38.39046932
OS 55.46018372 -38.39231844
OS 55.4629574 -38.39694124
OS 55.46665564 -38.40526228
OS 55.47127844 -38.41543244
OS 55.47590124 -38.42745172
OS 55.47959948 -38.44132012
OS 55.48237316 -38.45703764
OS 55.48329772 -38.47275516
OS 55.48329772 -38.47460428
OS 55.48329772 -38.48015164
OS 55.48237316 -38.48754812
OS 55.48052404 -38.49771828
OS 55.47775036 -38.50973756
OS 55.47312756 -38.5226814
OS 55.4675802 -38.53562524
OS 55.46018372 -38.54856908
OS 55.45925916 -38.5504182
OS 55.45648548 -38.55411644
OS 55.45093812 -38.56058836
OS 55.44354164 -38.56798484
OS 55.43429604 -38.57630588
OS 55.42320132 -38.58555148
OS 55.41025748 -38.59387252
OS 55.39453996 -38.60219356
OS 55.39546452 -38.60219356
OS 55.39731364 -38.60311812
OS 55.40008732 -38.60404268
OS 55.40378556 -38.60496724
OS 55.41395572 -38.60866548
OS 55.42689956 -38.61421284
OS 55.44169252 -38.62160932
OS 55.45648548 -38.63085492
OS 55.47035388 -38.6428742
OS 55.48329772 -38.6567426
OS 55.48422228 -38.65859172
OS 55.48792052 -38.66413908
OS 55.49346788 -38.67338468
OS 55.49901524 -38.68540396
OS 55.5045626 -38.70019692
OS 55.51010996 -38.71776356
OS 55.5138082 -38.73810388
OS 55.51473276 -38.76029332
OS 55.51473276 -38.76121788
OS 55.51473276 -38.76399156
OS 55.51473276 -38.76861436
OS 55.5138082 -38.77416172
OS 55.51288364 -38.7815582
OS 55.51103452 -38.78987924
OS 55.5091854 -38.79912484
OS 55.50733628 -38.809295
OS 55.4999398 -38.83148444
OS 55.49439244 -38.84350372
OS 55.48884508 -38.85459844
OS 55.4814486 -38.86661772
OS 55.47312756 -38.878637
OS 55.46388196 -38.89065628
OS 55.45278724 -38.901751
OS 55.45186268 -38.90267556
OS 55.45001356 -38.90452468
OS 55.44631532 -38.90729836
OS 55.44169252 -38.9109966
OS 55.43614516 -38.9156194
OS 55.42874868 -38.9202422
OS 55.42042764 -38.92578956
OS 55.41025748 -38.93041236
OS 55.40008732 -38.93595972
OS 55.38806804 -38.94150708
OS 55.37604876 -38.94612988
OS 55.36218036 -38.95075268
OS 55.3473874 -38.95445092
OS 55.33166988 -38.9572246
OS 55.31595236 -38.95907372
OS 55.29838572 -38.95999828
OS 55.29006468 -38.95999828
OS 55.28451732 -38.95907372
OS 55.27712084 -38.95814916
OS 55.2687998 -38.9572246
OS 55.2595542 -38.95537548
OS 55.24938404 -38.95352636
OS 55.2271946 -38.947979
OS 55.2040806 -38.9387334
OS 55.19206132 -38.93318604
OS 55.1809666 -38.92671412
OS 55.16987188 -38.91839308
OS 55.15877716 -38.91007204
OS 55.1578526 -38.90914748
OS 55.15600348 -38.90729836
OS 55.1532298 -38.90452468
OS 55.15045612 -38.90082644
OS 55.14583332 -38.89620364
OS 55.14121052 -38.88973172
OS 55.13566316 -38.8832598
OS 55.1301158 -38.87493876
OS 55.12456844 -38.86569316
OS 55.11902108 -38.85644756
OS 55.10885092 -38.83425812
OS 55.10052988 -38.80837044
OS 55.0977562 -38.79450204
OS 55.09590708 -38.77970908
OS 55.17449468 -38.76953892
OS 55.17449468 -38.77046348
OS 55.17541924 -38.7723126
OS 55.1763438 -38.77601084
OS 55.17726836 -38.78063364
OS 55.17819292 -38.786181
OS 55.18004204 -38.79265292
OS 55.18466484 -38.80652132
OS 55.19113676 -38.8231634
OS 55.1994578 -38.83888092
OS 55.2087034 -38.85367388
OS 55.21979812 -38.86661772
OS 55.22164724 -38.86754228
OS 55.22534548 -38.87124052
OS 55.23274196 -38.87586332
OS 55.24198756 -38.88048612
OS 55.25308228 -38.88603348
OS 55.26695068 -38.89065628
OS 55.2826682 -38.89435452
OS 55.29931028 -38.89527908
OS 55.30485764 -38.89527908
OS 55.30855588 -38.89435452
OS 55.31872604 -38.89342996
OS 55.33166988 -38.89065628
OS 55.34646284 -38.88603348
OS 55.36218036 -38.87956156
OS 55.37789788 -38.87031596
OS 55.39269084 -38.85737212
OS 55.39453996 -38.855523
OS 55.39916276 -38.84997564
OS 55.40471012 -38.8416546
OS 55.4121066 -38.83055988
OS 55.41950308 -38.81669148
OS 55.42505044 -38.80097396
OS 55.42967324 -38.78248276
OS 55.43152236 -38.76214244
OS 55.43152236 -38.76121788
OS 55.43152236 -38.75936876
OS 55.43152236 -38.75659508
OS 55.4305978 -38.75289684
OS 55.42967324 -38.74272668
OS 55.42689956 -38.7307074
OS 55.42320132 -38.71591444
OS 55.4167294 -38.70112148
OS 55.4074838 -38.68632852
OS 55.39546452 -38.67246012
OS 55.3936154 -38.670611
OS 55.3889926 -38.66691276
OS 55.38159612 -38.6613654
OS 55.37142596 -38.65489348
OS 55.35848212 -38.64842156
OS 55.3427646 -38.6428742
OS 55.32519796 -38.63917596
OS 55.3057822 -38.63732684
OS 55.29746116 -38.63732684
OS 55.29098924 -38.6382514
OS 55.2826682 -38.63917596
OS 55.2734226 -38.64102508
OS 55.26232788 -38.6428742
OS 55.2503086 -38.64564788
OS 55.2595542 -38.57630588
OS 55.264177 -38.57630588
OS 55.26787524 -38.57723044
OS 55.27989452 -38.57723044
OS 55.29006468 -38.57538132
OS 55.30208396 -38.5735322
OS 55.31595236 -38.57075852
OS 55.33166988 -38.56613572
OS 55.34646284 -38.5596638
OS 55.36218036 -38.55134276
OS 55.36310492 -38.55134276
OS 55.36402948 -38.5504182
OS 55.36865228 -38.54671996
OS 55.3751242 -38.54024804
OS 55.38252068 -38.531927
OS 55.38991716 -38.51990772
OS 55.39638908 -38.50603932
OS 55.40101188 -38.4903218
OS 55.402861 -38.4810762
OS 55.402861 -38.47090604
OS 55.402861 -38.46998148
OS 55.402861 -38.46905692
OS 55.402861 -38.46350956
OS 55.40101188 -38.45611308
OS 55.39916276 -38.44594292
OS 55.39546452 -38.4348482
OS 55.39084172 -38.42282892
OS 55.38344524 -38.41080964
OS 55.37327508 -38.39971492
OS 55.37235052 -38.39879036
OS 55.36772772 -38.39509212
OS 55.3612558 -38.39046932
OS 55.35293476 -38.38492196
OS 55.34184004 -38.38029916
OS 55.3288962 -38.37567636
OS 55.31410324 -38.37197812
OS 55.29746116 -38.37105356
OS 55.29006468 -38.37105356
OS 55.28174364 -38.37290268
OS 55.27064892 -38.3747518
OS 55.25862964 -38.37845004
OS 55.24661036 -38.38307284
OS 55.23366652 -38.39046932
OS 55.22164724 -38.39971492
OS 55.22072268 -38.40063948
OS 55.21702444 -38.40526228
OS 55.21147708 -38.4117342
OS 55.20500516 -38.4209798
OS 55.19853324 -38.43299908
OS 55.19206132 -38.44779204
OS 55.18651396 -38.46535868
OS 55.18281572 -38.485699
OS 55.10422812 -38.4718306
OS 55.10422812 -38.47090604
OS 55.10515268 -38.46813236
OS 55.10607724 -38.46443412
OS 55.1070018 -38.45888676
OS 55.10885092 -38.45241484
OS 55.1116246 -38.44501836
OS 55.11717196 -38.42745172
OS 55.12641756 -38.4071114
OS 55.13751228 -38.38677108
OS 55.15138068 -38.36735532
OS 55.16894732 -38.34978868
OS 55.16987188 -38.34886412
OS 55.171721 -38.34793956
OS 55.17449468 -38.34609044
OS 55.17819292 -38.34331676
OS 55.18281572 -38.33961852
OS 55.18928764 -38.33592028
OS 55.19575956 -38.33222204
OS 55.2040806 -38.32759924
OS 55.2225718 -38.32020276
OS 55.24383668 -38.31280628
OS 55.2687998 -38.30818348
OS 55.28174364 -38.30633436
OS 55.30485764 -38.30633436
OS 55.3150278 -38.30725892
OE
OB 54.48199924 -38.94890356 I
OS 54.39231692 -38.94890356
OS 54.39231692 -38.85922124
OS 54.48199924 -38.85922124
OS 54.48199924 -38.94890356
OE
OB 54.9914318 -38.39231844 I
OS 54.73532868 -38.39231844
OS 54.70111996 -38.56521116
OS 54.70204452 -38.5642866
OS 54.70389364 -38.56336204
OS 54.70666732 -38.56151292
OS 54.71129012 -38.55873924
OS 54.71683748 -38.55596556
OS 54.7233094 -38.55226732
OS 54.73810236 -38.54487084
OS 54.75659356 -38.53747436
OS 54.77693388 -38.53100244
OS 54.79912332 -38.52637964
OS 54.81021804 -38.52453052
OS 54.83055836 -38.52453052
OS 54.83610572 -38.52545508
OS 54.8435022 -38.52637964
OS 54.85182324 -38.5273042
OS 54.86106884 -38.52915332
OS 54.871239 -38.531927
OS 54.89342844 -38.53839892
OS 54.90544772 -38.54302172
OS 54.917467 -38.54949364
OS 54.92948628 -38.55596556
OS 54.94150556 -38.56336204
OS 54.95260028 -38.57260764
OS 54.963695 -38.5827778
OS 54.96461956 -38.58370236
OS 54.96646868 -38.58555148
OS 54.96924236 -38.58832516
OS 54.9729406 -38.59294796
OS 54.9775634 -38.59941988
OS 54.9821862 -38.6058918
OS 54.98773356 -38.61421284
OS 54.99328092 -38.62345844
OS 54.99790372 -38.6336286
OS 55.00345108 -38.64472332
OS 55.00807388 -38.65766716
OS 55.01269668 -38.670611
OS 55.01639492 -38.6844794
OS 55.0191686 -38.70019692
OS 55.02101772 -38.71591444
OS 55.02194228 -38.73255652
OS 55.02194228 -38.73348108
OS 55.02194228 -38.73625476
OS 55.02194228 -38.74087756
OS 55.02101772 -38.74734948
OS 55.02009316 -38.75474596
OS 55.0191686 -38.763067
OS 55.01731948 -38.77323716
OS 55.01547036 -38.78340732
OS 55.009923 -38.80744588
OS 55.0006774 -38.832409
OS 54.99513004 -38.84535284
OS 54.98773356 -38.85737212
OS 54.98033708 -38.87031596
OS 54.97109148 -38.88233524
OS 54.97016692 -38.8832598
OS 54.9683178 -38.88603348
OS 54.96461956 -38.88973172
OS 54.95999676 -38.89435452
OS 54.95352484 -38.89990188
OS 54.94612836 -38.90729836
OS 54.93688276 -38.91377028
OS 54.9267126 -38.92116676
OS 54.91561788 -38.92856324
OS 54.90267404 -38.93503516
OS 54.88880564 -38.94150708
OS 54.87401268 -38.947979
OS 54.85829516 -38.9526018
OS 54.84072852 -38.95630004
OS 54.82223732 -38.95907372
OS 54.80282156 -38.95999828
OS 54.79450052 -38.95999828
OS 54.7880286 -38.95907372
OS 54.78063212 -38.95814916
OS 54.77231108 -38.9572246
OS 54.76214092 -38.95630004
OS 54.75197076 -38.95352636
OS 54.72885676 -38.947979
OS 54.70574276 -38.93965796
OS 54.69372348 -38.9341106
OS 54.6817042 -38.92763868
OS 54.67060948 -38.9202422
OS 54.65951476 -38.91192116
OS 54.6585902 -38.9109966
OS 54.65674108 -38.91007204
OS 54.65489196 -38.9063738
OS 54.65119372 -38.90267556
OS 54.64657092 -38.89805276
OS 54.64194812 -38.8925054
OS 54.63640076 -38.88510892
OS 54.63177796 -38.87678788
OS 54.6262306 -38.86846684
OS 54.62068324 -38.85829668
OS 54.61051308 -38.83610724
OS 54.60219204 -38.81021956
OS 54.59941836 -38.79635116
OS 54.59756924 -38.7815582
OS 54.67985508 -38.77508628
OS 54.67985508 -38.77601084
OS 54.67985508 -38.77785996
OS 54.68077964 -38.78063364
OS 54.6817042 -38.78525644
OS 54.68447788 -38.7954266
OS 54.68817612 -38.809295
OS 54.69372348 -38.8231634
OS 54.70111996 -38.83888092
OS 54.71036556 -38.85274932
OS 54.72146028 -38.86569316
OS 54.7233094 -38.86661772
OS 54.72700764 -38.87031596
OS 54.73440412 -38.87493876
OS 54.74457428 -38.88048612
OS 54.755669 -38.88603348
OS 54.7695374 -38.89065628
OS 54.78525492 -38.89435452
OS 54.80282156 -38.89527908
OS 54.80836892 -38.89527908
OS 54.81206716 -38.89435452
OS 54.82316188 -38.89342996
OS 54.83610572 -38.88973172
OS 54.85182324 -38.88510892
OS 54.86754076 -38.87771244
OS 54.88418284 -38.86661772
OS 54.89157932 -38.8601458
OS 54.8989758 -38.85274932
OS 54.89990036 -38.85182476
OS 54.90082492 -38.8509002
OS 54.90267404 -38.84812652
OS 54.90544772 -38.84535284
OS 54.91191964 -38.83518268
OS 54.91931612 -38.82223884
OS 54.92578804 -38.80652132
OS 54.93225996 -38.78710556
OS 54.93688276 -38.76399156
OS 54.93873188 -38.75197228
OS 54.93873188 -38.73902844
OS 54.93873188 -38.73810388
OS 54.93873188 -38.73625476
OS 54.93873188 -38.73255652
OS 54.93780732 -38.72793372
OS 54.93780732 -38.72238636
OS 54.93688276 -38.71591444
OS 54.93410908 -38.70112148
OS 54.92948628 -38.68355484
OS 54.92301436 -38.6659882
OS 54.91376876 -38.64934612
OS 54.90082492 -38.6336286
OS 54.90082492 -38.63270404
OS 54.8989758 -38.63177948
OS 54.894353 -38.62715668
OS 54.88603196 -38.62068476
OS 54.87493724 -38.61328828
OS 54.86014428 -38.60681636
OS 54.8435022 -38.60034444
OS 54.82408644 -38.59572164
OS 54.81299172 -38.59387252
OS 54.79542508 -38.59387252
OS 54.7880286 -38.59479708
OS 54.778783 -38.59572164
OS 54.76768828 -38.59849532
OS 54.75659356 -38.601269
OS 54.74457428 -38.6058918
OS 54.732555 -38.61143916
OS 54.73163044 -38.61236372
OS 54.7279322 -38.61421284
OS 54.72238484 -38.61883564
OS 54.71498836 -38.62345844
OS 54.70759188 -38.62993036
OS 54.7001954 -38.6382514
OS 54.69187436 -38.64657244
OS 54.68540244 -38.6567426
OS 54.61143764 -38.64657244
OS 54.67338316 -38.31742908
OS 54.9914318 -38.31742908
OS 54.9914318 -38.39231844
OE
OB 49.95350436 -38.72331092 I
OS 50.040413 -38.72331092
OS 50.040413 -38.7954266
OS 49.95350436 -38.7954266
OS 49.95350436 -38.94890356
OS 49.87491676 -38.94890356
OS 49.87491676 -38.7954266
OS 49.5966242 -38.7954266
OS 49.5966242 -38.72331092
OS 49.88970972 -38.30910804
OS 49.95350436 -38.30910804
OS 49.95350436 -38.72331092
OE
OB 50.1467374 -38.95999828 I
OS 50.08386732 -38.95999828
OS 50.26970388 -38.29801332
OS 50.33257396 -38.29801332
OS 50.1467374 -38.95999828
OE
OB 49.35346492 -38.30725892 I
OS 49.3608614 -38.30818348
OS 49.370107 -38.30910804
OS 49.38027716 -38.31095716
OS 49.39044732 -38.31280628
OS 49.41448588 -38.3192782
OS 49.43852444 -38.3285238
OS 49.45054372 -38.33407116
OS 49.462563 -38.34054308
OS 49.47365772 -38.34886412
OS 49.48382788 -38.35810972
OS 49.48475244 -38.35903428
OS 49.48660156 -38.35995884
OS 49.48845068 -38.36365708
OS 49.49214892 -38.36735532
OS 49.49677172 -38.37197812
OS 49.50139452 -38.37845004
OS 49.50601732 -38.38492196
OS 49.51156468 -38.393243
OS 49.52081028 -38.41080964
OS 49.53005588 -38.43299908
OS 49.53375412 -38.4440938
OS 49.53560324 -38.45703764
OS 49.53745236 -38.46998148
OS 49.53837692 -38.48384988
OS 49.53837692 -38.485699
OS 49.53837692 -38.4903218
OS 49.53745236 -38.49771828
OS 49.5365278 -38.50788844
OS 49.53467868 -38.51898316
OS 49.53098044 -38.531927
OS 49.5272822 -38.5457954
OS 49.52173484 -38.5596638
OS 49.52081028 -38.56151292
OS 49.51896116 -38.56613572
OS 49.51526292 -38.5735322
OS 49.50971556 -38.58370236
OS 49.50231908 -38.59479708
OS 49.49307348 -38.60866548
OS 49.48197876 -38.62253388
OS 49.46903492 -38.6382514
OS 49.4671858 -38.64010052
OS 49.462563 -38.64564788
OS 49.4579402 -38.65027068
OS 49.4533174 -38.65489348
OS 49.44777004 -38.66044084
OS 49.44037356 -38.66783732
OS 49.43297708 -38.6752338
OS 49.42373148 -38.68355484
OS 49.41448588 -38.69280044
OS 49.40339116 -38.7029706
OS 49.39137188 -38.71314076
OS 49.37842804 -38.72516004
OS 49.36363508 -38.73717932
OS 49.34884212 -38.75012316
OS 49.34791756 -38.75104772
OS 49.34606844 -38.75289684
OS 49.3423702 -38.75567052
OS 49.3377474 -38.75936876
OS 49.33220004 -38.76491612
OS 49.32572812 -38.77046348
OS 49.31093516 -38.78248276
OS 49.29521764 -38.79635116
OS 49.28042468 -38.81021956
OS 49.26748084 -38.82223884
OS 49.26193348 -38.82686164
OS 49.25731068 -38.83148444
OS 49.25638612 -38.832409
OS 49.25361244 -38.83518268
OS 49.2499142 -38.83888092
OS 49.2452914 -38.84442828
OS 49.2406686 -38.8509002
OS 49.23512124 -38.85737212
OS 49.22402652 -38.87308964
OS 49.53930148 -38.87308964
OS 49.53930148 -38.94890356
OS 49.11492844 -38.94890356
OS 49.11492844 -38.947979
OS 49.11492844 -38.94428076
OS 49.11492844 -38.9387334
OS 49.115853 -38.93133692
OS 49.11677756 -38.92301588
OS 49.11862668 -38.91377028
OS 49.1204758 -38.90452468
OS 49.12417404 -38.89435452
OS 49.12417404 -38.89342996
OS 49.1250986 -38.8925054
OS 49.12694772 -38.88695804
OS 49.13064596 -38.878637
OS 49.13619332 -38.86754228
OS 49.1435898 -38.85459844
OS 49.1528354 -38.83980548
OS 49.16300556 -38.82501252
OS 49.1759494 -38.809295
OS 49.1759494 -38.80837044
OS 49.17779852 -38.80744588
OS 49.18242132 -38.80189852
OS 49.19074236 -38.79357748
OS 49.20276164 -38.7815582
OS 49.21663004 -38.7676898
OS 49.23419668 -38.75104772
OS 49.25546156 -38.73255652
OS 49.27857556 -38.71314076
OS 49.27950012 -38.7122162
OS 49.28319836 -38.70944252
OS 49.28874572 -38.70481972
OS 49.29521764 -38.69927236
OS 49.30353868 -38.69187588
OS 49.31370884 -38.68355484
OS 49.323879 -38.67430924
OS 49.33589828 -38.66413908
OS 49.35901228 -38.64194964
OS 49.38212628 -38.6197602
OS 49.393221 -38.60866548
OS 49.40339116 -38.59757076
OS 49.41263676 -38.5874006
OS 49.42003324 -38.57723044
OS 49.42003324 -38.57630588
OS 49.42188236 -38.57538132
OS 49.42373148 -38.57260764
OS 49.4255806 -38.5689094
OS 49.43205252 -38.55873924
OS 49.439449 -38.54671996
OS 49.44592092 -38.531927
OS 49.45239284 -38.51620948
OS 49.45609108 -38.49864284
OS 49.4579402 -38.48200076
OS 49.4579402 -38.4810762
OS 49.4579402 -38.48015164
OS 49.45701564 -38.47460428
OS 49.45609108 -38.46535868
OS 49.4533174 -38.45518852
OS 49.44961916 -38.44224468
OS 49.44314724 -38.42930084
OS 49.4348262 -38.416357
OS 49.42373148 -38.40341316
OS 49.42188236 -38.40156404
OS 49.41725956 -38.3978658
OS 49.41078764 -38.393243
OS 49.40061748 -38.38677108
OS 49.38767364 -38.38122372
OS 49.37288068 -38.37567636
OS 49.35531404 -38.37197812
OS 49.33589828 -38.37105356
OS 49.33035092 -38.37105356
OS 49.32665268 -38.37197812
OS 49.31555796 -38.37290268
OS 49.30261412 -38.37567636
OS 49.28874572 -38.3793746
OS 49.2730282 -38.38584652
OS 49.25823524 -38.39416756
OS 49.24436684 -38.40526228
OS 49.24251772 -38.4071114
OS 49.23881948 -38.4117342
OS 49.23327212 -38.41913068
OS 49.22772476 -38.4302254
OS 49.22125284 -38.44316924
OS 49.21570548 -38.45981132
OS 49.21200724 -38.47830252
OS 49.21015812 -38.4995674
OS 49.1297214 -38.49124636
OS 49.1297214 -38.4903218
OS 49.13064596 -38.48754812
OS 49.13064596 -38.48292532
OS 49.13157052 -38.4764534
OS 49.13341964 -38.46905692
OS 49.13526876 -38.46073588
OS 49.13804244 -38.45056572
OS 49.14081612 -38.44039556
OS 49.1482126 -38.41820612
OS 49.15930732 -38.39601668
OS 49.16577924 -38.38492196
OS 49.17410028 -38.37382724
OS 49.18242132 -38.36365708
OS 49.19166692 -38.35441148
OS 49.19259148 -38.35348692
OS 49.1944406 -38.35256236
OS 49.19721428 -38.34978868
OS 49.20183708 -38.347015
OS 49.20738444 -38.34331676
OS 49.21385636 -38.33961852
OS 49.22125284 -38.33499572
OS 49.23049844 -38.33037292
OS 49.2406686 -38.32575012
OS 49.25176332 -38.32112732
OS 49.2637826 -38.31742908
OS 49.27672644 -38.31373084
OS 49.29059484 -38.31095716
OS 49.3053878 -38.30818348
OS 49.32110532 -38.30725892
OS 49.3377474 -38.30633436
OS 49.346993 -38.30633436
OS 49.35346492 -38.30725892
OE
OB 48.67576244 -38.94890356 I
OS 48.59717484 -38.94890356
OS 48.59717484 -38.4487166
OS 48.59625028 -38.44964116
OS 48.59162748 -38.4533394
OS 48.58608012 -38.45888676
OS 48.57683452 -38.46535868
OS 48.56666436 -38.47367972
OS 48.55372052 -38.48292532
OS 48.53892756 -38.49309548
OS 48.52228548 -38.50326564
OS 48.52136092 -38.50326564
OS 48.52043636 -38.5041902
OS 48.514889 -38.50788844
OS 48.5056434 -38.51251124
OS 48.49454868 -38.5180586
OS 48.48160484 -38.52453052
OS 48.46773644 -38.53100244
OS 48.45386804 -38.53747436
OS 48.43999964 -38.54302172
OS 48.43999964 -38.4672078
OS 48.4409242 -38.4672078
OS 48.44277332 -38.46535868
OS 48.44647156 -38.46443412
OS 48.45109436 -38.46166044
OS 48.45664172 -38.45888676
OS 48.46311364 -38.45518852
OS 48.47883116 -38.44594292
OS 48.49732236 -38.43577276
OS 48.51581356 -38.42282892
OS 48.53522932 -38.40803596
OS 48.55464508 -38.39231844
OS 48.55556964 -38.39139388
OS 48.5564942 -38.39046932
OS 48.55926788 -38.38769564
OS 48.56296612 -38.38492196
OS 48.57128716 -38.37567636
OS 48.58238188 -38.36458164
OS 48.5934766 -38.3516378
OS 48.60549588 -38.33684484
OS 48.61566604 -38.32205188
OS 48.62491164 -38.30633436
OS 48.67576244 -38.30633436
OS 48.67576244 -38.94890356
OE
OB 48.9032042 -38.95999828 I
OS 48.84033412 -38.95999828
OS 49.02617068 -38.29801332
OS 49.08904076 -38.29801332
OS 48.9032042 -38.95999828
OE
OB 50.59699812 -38.30725892 I
OS 50.6043946 -38.30818348
OS 50.6136402 -38.30910804
OS 50.62381036 -38.31095716
OS 50.63398052 -38.31280628
OS 50.65801908 -38.3192782
OS 50.68205764 -38.3285238
OS 50.69407692 -38.33407116
OS 50.7060962 -38.34054308
OS 50.71719092 -38.34886412
OS 50.72736108 -38.35810972
OS 50.72828564 -38.35903428
OS 50.73013476 -38.35995884
OS 50.73198388 -38.36365708
OS 50.73568212 -38.36735532
OS 50.74030492 -38.37197812
OS 50.74492772 -38.37845004
OS 50.74955052 -38.38492196
OS 50.75509788 -38.393243
OS 50.76434348 -38.41080964
OS 50.77358908 -38.43299908
OS 50.77728732 -38.4440938
OS 50.77913644 -38.45703764
OS 50.78098556 -38.46998148
OS 50.78191012 -38.48384988
OS 50.78191012 -38.485699
OS 50.78191012 -38.4903218
OS 50.78098556 -38.49771828
OS 50.780061 -38.50788844
OS 50.77821188 -38.51898316
OS 50.77451364 -38.531927
OS 50.7708154 -38.5457954
OS 50.76526804 -38.5596638
OS 50.76434348 -38.56151292
OS 50.76249436 -38.56613572
OS 50.75879612 -38.5735322
OS 50.75324876 -38.58370236
OS 50.74585228 -38.59479708
OS 50.73660668 -38.60866548
OS 50.72551196 -38.62253388
OS 50.71256812 -38.6382514
OS 50.710719 -38.64010052
OS 50.7060962 -38.64564788
OS 50.7014734 -38.65027068
OS 50.6968506 -38.65489348
OS 50.69130324 -38.66044084
OS 50.68390676 -38.66783732
OS 50.67651028 -38.6752338
OS 50.66726468 -38.68355484
OS 50.65801908 -38.69280044
OS 50.64692436 -38.7029706
OS 50.63490508 -38.71314076
OS 50.62196124 -38.72516004
OS 50.60716828 -38.73717932
OS 50.59237532 -38.75012316
OS 50.59145076 -38.75104772
OS 50.58960164 -38.75289684
OS 50.5859034 -38.75567052
OS 50.5812806 -38.75936876
OS 50.57573324 -38.76491612
OS 50.56926132 -38.77046348
OS 50.55446836 -38.78248276
OS 50.53875084 -38.79635116
OS 50.52395788 -38.81021956
OS 50.51101404 -38.82223884
OS 50.50546668 -38.82686164
OS 50.50084388 -38.83148444
OS 50.49991932 -38.832409
OS 50.49714564 -38.83518268
OS 50.4934474 -38.83888092
OS 50.4888246 -38.84442828
OS 50.4842018 -38.8509002
OS 50.47865444 -38.85737212
OS 50.46755972 -38.87308964
OS 50.78283468 -38.87308964
OS 50.78283468 -38.94890356
OS 50.35846164 -38.94890356
OS 50.35846164 -38.947979
OS 50.35846164 -38.94428076
OS 50.35846164 -38.9387334
OS 50.3593862 -38.93133692
OS 50.36031076 -38.92301588
OS 50.36215988 -38.91377028
OS 50.364009 -38.90452468
OS 50.36770724 -38.89435452
OS 50.36770724 -38.89342996
OS 50.3686318 -38.8925054
OS 50.37048092 -38.88695804
OS 50.37417916 -38.878637
OS 50.37972652 -38.86754228
OS 50.387123 -38.85459844
OS 50.3963686 -38.83980548
OS 50.40653876 -38.82501252
OS 50.4194826 -38.809295
OS 50.4194826 -38.80837044
OS 50.42133172 -38.80744588
OS 50.42595452 -38.80189852
OS 50.43427556 -38.79357748
OS 50.44629484 -38.7815582
OS 50.46016324 -38.7676898
OS 50.47772988 -38.75104772
OS 50.49899476 -38.73255652
OS 50.52210876 -38.71314076
OS 50.52303332 -38.7122162
OS 50.52673156 -38.70944252
OS 50.53227892 -38.70481972
OS 50.53875084 -38.69927236
OS 50.54707188 -38.69187588
OS 50.55724204 -38.68355484
OS 50.5674122 -38.67430924
OS 50.57943148 -38.66413908
OS 50.60254548 -38.64194964
OS 50.62565948 -38.6197602
OS 50.6367542 -38.60866548
OS 50.64692436 -38.59757076
OS 50.65616996 -38.5874006
OS 50.66356644 -38.57723044
OS 50.66356644 -38.57630588
OS 50.66541556 -38.57538132
OS 50.66726468 -38.57260764
OS 50.6691138 -38.5689094
OS 50.67558572 -38.55873924
OS 50.6829822 -38.54671996
OS 50.68945412 -38.531927
OS 50.69592604 -38.51620948
OS 50.69962428 -38.49864284
OS 50.7014734 -38.48200076
OS 50.7014734 -38.4810762
OS 50.7014734 -38.48015164
OS 50.70054884 -38.47460428
OS 50.69962428 -38.46535868
OS 50.6968506 -38.45518852
OS 50.69315236 -38.44224468
OS 50.68668044 -38.42930084
OS 50.6783594 -38.416357
OS 50.66726468 -38.40341316
OS 50.66541556 -38.40156404
OS 50.66079276 -38.3978658
OS 50.65432084 -38.393243
OS 50.64415068 -38.38677108
OS 50.63120684 -38.38122372
OS 50.61641388 -38.37567636
OS 50.59884724 -38.37197812
OS 50.57943148 -38.37105356
OS 50.57388412 -38.37105356
OS 50.57018588 -38.37197812
OS 50.55909116 -38.37290268
OS 50.54614732 -38.37567636
OS 50.53227892 -38.3793746
OS 50.5165614 -38.38584652
OS 50.50176844 -38.39416756
OS 50.48790004 -38.40526228
OS 50.48605092 -38.4071114
OS 50.48235268 -38.4117342
OS 50.47680532 -38.41913068
OS 50.47125796 -38.4302254
OS 50.46478604 -38.44316924
OS 50.45923868 -38.45981132
OS 50.45554044 -38.47830252
OS 50.45369132 -38.4995674
OS 50.3732546 -38.49124636
OS 50.3732546 -38.4903218
OS 50.37417916 -38.48754812
OS 50.37417916 -38.48292532
OS 50.37510372 -38.4764534
OS 50.37695284 -38.46905692
OS 50.37880196 -38.46073588
OS 50.38157564 -38.45056572
OS 50.38434932 -38.44039556
OS 50.3917458 -38.41820612
OS 50.40284052 -38.39601668
OS 50.40931244 -38.38492196
OS 50.41763348 -38.37382724
OS 50.42595452 -38.36365708
OS 50.43520012 -38.35441148
OS 50.43612468 -38.35348692
OS 50.4379738 -38.35256236
OS 50.44074748 -38.34978868
OS 50.44537028 -38.347015
OS 50.45091764 -38.34331676
OS 50.45738956 -38.33961852
OS 50.46478604 -38.33499572
OS 50.47403164 -38.33037292
OS 50.4842018 -38.32575012
OS 50.49529652 -38.32112732
OS 50.5073158 -38.31742908
OS 50.52025964 -38.31373084
OS 50.53412804 -38.31095716
OS 50.548921 -38.30818348
OS 50.56463852 -38.30725892
OS 50.5812806 -38.30633436
OS 50.5905262 -38.30633436
OS 50.59699812 -38.30725892
OE
OB 51.0944114 -38.30725892 I
OS 51.10643068 -38.30910804
OS 51.12029908 -38.31188172
OS 51.13509204 -38.31557996
OS 51.15080956 -38.32020276
OS 51.16560252 -38.32759924
OS 51.16652708 -38.32759924
OS 51.16745164 -38.3285238
OS 51.17207444 -38.33129748
OS 51.17947092 -38.33592028
OS 51.18871652 -38.3423922
OS 51.19888668 -38.3516378
OS 51.2099814 -38.36180796
OS 51.22015156 -38.37382724
OS 51.23032172 -38.38769564
OS 51.23124628 -38.38954476
OS 51.23494452 -38.39416756
OS 51.23864276 -38.4024886
OS 51.24511468 -38.41450788
OS 51.25066204 -38.42837628
OS 51.25805852 -38.4440938
OS 51.26453044 -38.462585
OS 51.2700778 -38.48292532
OS 51.2700778 -38.48384988
OS 51.27100236 -38.485699
OS 51.27192692 -38.48847268
OS 51.27285148 -38.49309548
OS 51.27377604 -38.49864284
OS 51.2747006 -38.50511476
OS 51.27654972 -38.5134358
OS 51.27747428 -38.5226814
OS 51.2793234 -38.53285156
OS 51.28024796 -38.54394628
OS 51.28117252 -38.55689012
OS 51.28302164 -38.56983396
OS 51.2839462 -38.58462692
OS 51.2839462 -38.59941988
OS 51.28487076 -38.61606196
OS 51.28487076 -38.6336286
OS 51.28487076 -38.63455316
OS 51.28487076 -38.6382514
OS 51.28487076 -38.64472332
OS 51.28487076 -38.6521198
OS 51.2839462 -38.66228996
OS 51.2839462 -38.67338468
OS 51.28302164 -38.68540396
OS 51.28209708 -38.6983478
OS 51.2793234 -38.72793372
OS 51.2747006 -38.7584442
OS 51.26915324 -38.78803012
OS 51.265455 -38.80189852
OS 51.2608322 -38.81576692
OS 51.2608322 -38.81669148
OS 51.25990764 -38.8185406
OS 51.25805852 -38.82223884
OS 51.2562094 -38.82686164
OS 51.25436028 -38.83333356
OS 51.25066204 -38.83980548
OS 51.24326556 -38.855523
OS 51.23401996 -38.87216508
OS 51.22200068 -38.89065628
OS 51.20813228 -38.90729836
OS 51.1914902 -38.92301588
OS 51.19056564 -38.92301588
OS 51.18964108 -38.924865
OS 51.1868674 -38.92671412
OS 51.18316916 -38.92856324
OS 51.17854636 -38.93133692
OS 51.17392356 -38.93503516
OS 51.16005516 -38.94150708
OS 51.14341308 -38.947979
OS 51.12399732 -38.95445092
OS 51.10088332 -38.95814916
OS 51.0759202 -38.95999828
OS 51.0666746 -38.95999828
OS 51.06020268 -38.95907372
OS 51.0528062 -38.95814916
OS 51.0435606 -38.95630004
OS 51.03339044 -38.95445092
OS 51.02229572 -38.95167724
OS 51.011201 -38.947979
OS 50.99918172 -38.94428076
OS 50.98716244 -38.9387334
OS 50.97514316 -38.93226148
OS 50.96312388 -38.924865
OS 50.9511046 -38.9156194
OS 50.94000988 -38.90544924
OS 50.92983972 -38.89435452
OS 50.92891516 -38.89342996
OS 50.92706604 -38.89065628
OS 50.92429236 -38.88603348
OS 50.91966956 -38.878637
OS 50.91504676 -38.87031596
OS 50.91042396 -38.85922124
OS 50.90395204 -38.8462774
OS 50.89840468 -38.83148444
OS 50.89285732 -38.81484236
OS 50.88730996 -38.7954266
OS 50.8817626 -38.77416172
OS 50.8771398 -38.75012316
OS 50.872517 -38.72423548
OS 50.86974332 -38.69649868
OS 50.8678942 -38.6659882
OS 50.86696964 -38.6336286
OS 50.86696964 -38.63270404
OS 50.86696964 -38.6290058
OS 50.86696964 -38.62253388
OS 50.86696964 -38.6151374
OS 50.8678942 -38.60496724
OS 50.8678942 -38.59387252
OS 50.86881876 -38.58185324
OS 50.86974332 -38.56798484
OS 50.872517 -38.53932348
OS 50.8771398 -38.508813
OS 50.88268716 -38.47830252
OS 50.8863854 -38.46443412
OS 50.89008364 -38.45056572
OS 50.89008364 -38.44964116
OS 50.8910082 -38.44779204
OS 50.89285732 -38.4440938
OS 50.89470644 -38.439471
OS 50.89655556 -38.43299908
OS 50.9002538 -38.42652716
OS 50.90765028 -38.41080964
OS 50.91689588 -38.39416756
OS 50.92891516 -38.37660092
OS 50.94278356 -38.35903428
OS 50.95942564 -38.34424132
OS 50.9603502 -38.34424132
OS 50.96127476 -38.3423922
OS 50.96404844 -38.34054308
OS 50.96774668 -38.33869396
OS 50.97236948 -38.33499572
OS 50.97791684 -38.33222204
OS 50.99178524 -38.32482556
OS 51.00842732 -38.31835364
OS 51.02784308 -38.31188172
OS 51.05095708 -38.30818348
OS 51.0759202 -38.30633436
OS 51.08424124 -38.30633436
OS 51.0944114 -38.30725892
OE
OB 51.59182468 -38.30725892 I
OS 51.59922116 -38.30818348
OS 51.60846676 -38.30910804
OS 51.61863692 -38.31095716
OS 51.62880708 -38.31280628
OS 51.65284564 -38.3192782
OS 51.6768842 -38.3285238
OS 51.68890348 -38.33407116
OS 51.70092276 -38.34054308
OS 51.71201748 -38.34886412
OS 51.72218764 -38.35810972
OS 51.7231122 -38.35903428
OS 51.72496132 -38.35995884
OS 51.72681044 -38.36365708
OS 51.73050868 -38.36735532
OS 51.73513148 -38.37197812
OS 51.73975428 -38.37845004
OS 51.74437708 -38.38492196
OS 51.74992444 -38.393243
OS 51.75917004 -38.41080964
OS 51.76841564 -38.43299908
OS 51.77211388 -38.4440938
OS 51.773963 -38.45703764
OS 51.77581212 -38.46998148
OS 51.77673668 -38.48384988
OS 51.77673668 -38.485699
OS 51.77673668 -38.4903218
OS 51.77581212 -38.49771828
OS 51.77488756 -38.50788844
OS 51.77303844 -38.51898316
OS 51.7693402 -38.531927
OS 51.76564196 -38.5457954
OS 51.7600946 -38.5596638
OS 51.75917004 -38.56151292
OS 51.75732092 -38.56613572
OS 51.75362268 -38.5735322
OS 51.74807532 -38.58370236
OS 51.74067884 -38.59479708
OS 51.73143324 -38.60866548
OS 51.72033852 -38.62253388
OS 51.70739468 -38.6382514
OS 51.70554556 -38.64010052
OS 51.70092276 -38.64564788
OS 51.69629996 -38.65027068
OS 51.69167716 -38.65489348
OS 51.6861298 -38.66044084
OS 51.67873332 -38.66783732
OS 51.67133684 -38.6752338
OS 51.66209124 -38.68355484
OS 51.65284564 -38.69280044
OS 51.64175092 -38.7029706
OS 51.62973164 -38.71314076
OS 51.6167878 -38.72516004
OS 51.60199484 -38.73717932
OS 51.58720188 -38.75012316
OS 51.58627732 -38.75104772
OS 51.5844282 -38.75289684
OS 51.58072996 -38.75567052
OS 51.57610716 -38.75936876
OS 51.5705598 -38.76491612
OS 51.56408788 -38.77046348
OS 51.54929492 -38.78248276
OS 51.5335774 -38.79635116
OS 51.51878444 -38.81021956
OS 51.5058406 -38.82223884
OS 51.50029324 -38.82686164
OS 51.49567044 -38.83148444
OS 51.49474588 -38.832409
OS 51.4919722 -38.83518268
OS 51.48827396 -38.83888092
OS 51.48365116 -38.84442828
OS 51.47902836 -38.8509002
OS 51.473481 -38.85737212
OS 51.46238628 -38.87308964
OS 51.77766124 -38.87308964
OS 51.77766124 -38.94890356
OS 51.3532882 -38.94890356
OS 51.3532882 -38.947979
OS 51.3532882 -38.94428076
OS 51.3532882 -38.9387334
OS 51.35421276 -38.93133692
OS 51.35513732 -38.92301588
OS 51.35698644 -38.91377028
OS 51.35883556 -38.90452468
OS 51.3625338 -38.89435452
OS 51.3625338 -38.89342996
OS 51.36345836 -38.8925054
OS 51.36530748 -38.88695804
OS 51.36900572 -38.878637
OS 51.37455308 -38.86754228
OS 51.38194956 -38.85459844
OS 51.39119516 -38.83980548
OS 51.40136532 -38.82501252
OS 51.41430916 -38.809295
OS 51.41430916 -38.80837044
OS 51.41615828 -38.80744588
OS 51.42078108 -38.80189852
OS 51.42910212 -38.79357748
OS 51.4411214 -38.7815582
OS 51.4549898 -38.7676898
OS 51.47255644 -38.75104772
OS 51.49382132 -38.73255652
OS 51.51693532 -38.71314076
OS 51.51785988 -38.7122162
OS 51.52155812 -38.70944252
OS 51.52710548 -38.70481972
OS 51.5335774 -38.69927236
OS 51.54189844 -38.69187588
OS 51.5520686 -38.68355484
OS 51.56223876 -38.67430924
OS 51.57425804 -38.66413908
OS 51.59737204 -38.64194964
OS 51.62048604 -38.6197602
OS 51.63158076 -38.60866548
OS 51.64175092 -38.59757076
OS 51.65099652 -38.5874006
OS 51.658393 -38.57723044
OS 51.658393 -38.57630588
OS 51.66024212 -38.57538132
OS 51.66209124 -38.57260764
OS 51.66394036 -38.5689094
OS 51.67041228 -38.55873924
OS 51.67780876 -38.54671996
OS 51.68428068 -38.531927
OS 51.6907526 -38.51620948
OS 51.69445084 -38.49864284
OS 51.69629996 -38.48200076
OS 51.69629996 -38.4810762
OS 51.69629996 -38.48015164
OS 51.6953754 -38.47460428
OS 51.69445084 -38.46535868
OS 51.69167716 -38.45518852
OS 51.68797892 -38.44224468
OS 51.681507 -38.42930084
OS 51.67318596 -38.416357
OS 51.66209124 -38.40341316
OS 51.66024212 -38.40156404
OS 51.65561932 -38.3978658
OS 51.6491474 -38.393243
OS 51.63897724 -38.38677108
OS 51.6260334 -38.38122372
OS 51.61124044 -38.37567636
OS 51.5936738 -38.37197812
OS 51.57425804 -38.37105356
OS 51.56871068 -38.37105356
OS 51.56501244 -38.37197812
OS 51.55391772 -38.37290268
OS 51.54097388 -38.37567636
OS 51.52710548 -38.3793746
OS 51.51138796 -38.38584652
OS 51.496595 -38.39416756
OS 51.4827266 -38.40526228
OS 51.48087748 -38.4071114
OS 51.47717924 -38.4117342
OS 51.47163188 -38.41913068
OS 51.46608452 -38.4302254
OS 51.4596126 -38.44316924
OS 51.45406524 -38.45981132
OS 51.450367 -38.47830252
OS 51.44851788 -38.4995674
OS 51.36808116 -38.49124636
OS 51.36808116 -38.4903218
OS 51.36900572 -38.48754812
OS 51.36900572 -38.48292532
OS 51.36993028 -38.4764534
OS 51.3717794 -38.46905692
OS 51.37362852 -38.46073588
OS 51.3764022 -38.45056572
OS 51.37917588 -38.44039556
OS 51.38657236 -38.41820612
OS 51.39766708 -38.39601668
OS 51.404139 -38.38492196
OS 51.41246004 -38.37382724
OS 51.42078108 -38.36365708
OS 51.43002668 -38.35441148
OS 51.43095124 -38.35348692
OS 51.43280036 -38.35256236
OS 51.43557404 -38.34978868
OS 51.44019684 -38.347015
OS 51.4457442 -38.34331676
OS 51.45221612 -38.33961852
OS 51.4596126 -38.33499572
OS 51.4688582 -38.33037292
OS 51.47902836 -38.32575012
OS 51.49012308 -38.32112732
OS 51.50214236 -38.31742908
OS 51.5150862 -38.31373084
OS 51.5289546 -38.31095716
OS 51.54374756 -38.30818348
OS 51.55946508 -38.30725892
OS 51.57610716 -38.30633436
OS 51.58535276 -38.30633436
OS 51.59182468 -38.30725892
OE
OB 52.08184148 -38.30725892 I
OS 52.09386076 -38.30910804
OS 52.10865372 -38.31188172
OS 52.1252958 -38.31650452
OS 52.14193788 -38.32205188
OS 52.15857996 -38.32944836
OS 52.15950452 -38.32944836
OS 52.16042908 -38.33037292
OS 52.16597644 -38.3331466
OS 52.17429748 -38.33869396
OS 52.18354308 -38.34516588
OS 52.1946378 -38.35441148
OS 52.20573252 -38.36458164
OS 52.21682724 -38.37660092
OS 52.22607284 -38.39046932
OS 52.2269974 -38.39231844
OS 52.22977108 -38.39694124
OS 52.23346932 -38.40526228
OS 52.23809212 -38.41543244
OS 52.24271492 -38.42745172
OS 52.24641316 -38.44132012
OS 52.24918684 -38.45703764
OS 52.2501114 -38.47275516
OS 52.2501114 -38.47460428
OS 52.2501114 -38.48015164
OS 52.24918684 -38.48754812
OS 52.24733772 -38.49771828
OS 52.24456404 -38.50973756
OS 52.23994124 -38.5226814
OS 52.23439388 -38.53562524
OS 52.2269974 -38.54856908
OS 52.22607284 -38.5504182
OS 52.22329916 -38.55411644
OS 52.2177518 -38.56058836
OS 52.21035532 -38.56798484
OS 52.20110972 -38.57630588
OS 52.190015 -38.58555148
OS 52.17707116 -38.59387252
OS 52.16135364 -38.60219356
OS 52.1622782 -38.60219356
OS 52.16412732 -38.60311812
OS 52.166901 -38.60404268
OS 52.17059924 -38.60496724
OS 52.1807694 -38.60866548
OS 52.19371324 -38.61421284
OS 52.2085062 -38.62160932
OS 52.22329916 -38.63085492
OS 52.23716756 -38.6428742
OS 52.2501114 -38.6567426
OS 52.25103596 -38.65859172
OS 52.2547342 -38.66413908
OS 52.26028156 -38.67338468
OS 52.26582892 -38.68540396
OS 52.27137628 -38.70019692
OS 52.27692364 -38.71776356
OS 52.28062188 -38.73810388
OS 52.28154644 -38.76029332
OS 52.28154644 -38.76121788
OS 52.28154644 -38.76399156
OS 52.28154644 -38.76861436
OS 52.28062188 -38.77416172
OS 52.27969732 -38.7815582
OS 52.2778482 -38.78987924
OS 52.27599908 -38.79912484
OS 52.27414996 -38.809295
OS 52.26675348 -38.83148444
OS 52.26120612 -38.84350372
OS 52.25565876 -38.85459844
OS 52.24826228 -38.86661772
OS 52.23994124 -38.878637
OS 52.23069564 -38.89065628
OS 52.21960092 -38.901751
OS 52.21867636 -38.90267556
OS 52.21682724 -38.90452468
OS 52.213129 -38.90729836
OS 52.2085062 -38.9109966
OS 52.20295884 -38.9156194
OS 52.19556236 -38.9202422
OS 52.18724132 -38.92578956
OS 52.17707116 -38.93041236
OS 52.166901 -38.93595972
OS 52.15488172 -38.94150708
OS 52.14286244 -38.94612988
OS 52.12899404 -38.95075268
OS 52.11420108 -38.95445092
OS 52.09848356 -38.9572246
OS 52.08276604 -38.95907372
OS 52.0651994 -38.95999828
OS 52.05687836 -38.95999828
OS 52.051331 -38.95907372
OS 52.04393452 -38.95814916
OS 52.03561348 -38.9572246
OS 52.02636788 -38.95537548
OS 52.01619772 -38.95352636
OS 51.99400828 -38.947979
OS 51.97089428 -38.9387334
OS 51.958875 -38.93318604
OS 51.94778028 -38.92671412
OS 51.93668556 -38.91839308
OS 51.92559084 -38.91007204
OS 51.92466628 -38.90914748
OS 51.92281716 -38.90729836
OS 51.92004348 -38.90452468
OS 51.9172698 -38.90082644
OS 51.912647 -38.89620364
OS 51.9080242 -38.88973172
OS 51.90247684 -38.8832598
OS 51.89692948 -38.87493876
OS 51.89138212 -38.86569316
OS 51.88583476 -38.85644756
OS 51.8756646 -38.83425812
OS 51.86734356 -38.80837044
OS 51.86456988 -38.79450204
OS 51.86272076 -38.77970908
OS 51.94130836 -38.76953892
OS 51.94130836 -38.77046348
OS 51.94223292 -38.7723126
OS 51.94315748 -38.77601084
OS 51.94408204 -38.78063364
OS 51.9450066 -38.786181
OS 51.94685572 -38.79265292
OS 51.95147852 -38.80652132
OS 51.95795044 -38.8231634
OS 51.96627148 -38.83888092
OS 51.97551708 -38.85367388
OS 51.9866118 -38.86661772
OS 51.98846092 -38.86754228
OS 51.99215916 -38.87124052
OS 51.99955564 -38.87586332
OS 52.00880124 -38.88048612
OS 52.01989596 -38.88603348
OS 52.03376436 -38.89065628
OS 52.04948188 -38.89435452
OS 52.06612396 -38.89527908
OS 52.07167132 -38.89527908
OS 52.07536956 -38.89435452
OS 52.08553972 -38.89342996
OS 52.09848356 -38.89065628
OS 52.11327652 -38.88603348
OS 52.12899404 -38.87956156
OS 52.14471156 -38.87031596
OS 52.15950452 -38.85737212
OS 52.16135364 -38.855523
OS 52.16597644 -38.84997564
OS 52.1715238 -38.8416546
OS 52.17892028 -38.83055988
OS 52.18631676 -38.81669148
OS 52.19186412 -38.80097396
OS 52.19648692 -38.78248276
OS 52.19833604 -38.76214244
OS 52.19833604 -38.76121788
OS 52.19833604 -38.75936876
OS 52.19833604 -38.75659508
OS 52.19741148 -38.75289684
OS 52.19648692 -38.74272668
OS 52.19371324 -38.7307074
OS 52.190015 -38.71591444
OS 52.18354308 -38.70112148
OS 52.17429748 -38.68632852
OS 52.1622782 -38.67246012
OS 52.16042908 -38.670611
OS 52.15580628 -38.66691276
OS 52.1484098 -38.6613654
OS 52.13823964 -38.65489348
OS 52.1252958 -38.64842156
OS 52.10957828 -38.6428742
OS 52.09201164 -38.63917596
OS 52.07259588 -38.63732684
OS 52.06427484 -38.63732684
OS 52.05780292 -38.6382514
OS 52.04948188 -38.63917596
OS 52.04023628 -38.64102508
OS 52.02914156 -38.6428742
OS 52.01712228 -38.64564788
OS 52.02636788 -38.57630588
OS 52.03099068 -38.57630588
OS 52.03468892 -38.57723044
OS 52.0467082 -38.57723044
OS 52.05687836 -38.57538132
OS 52.06889764 -38.5735322
OS 52.08276604 -38.57075852
OS 52.09848356 -38.56613572
OS 52.11327652 -38.5596638
OS 52.12899404 -38.55134276
OS 52.1299186 -38.55134276
OS 52.13084316 -38.5504182
OS 52.13546596 -38.54671996
OS 52.14193788 -38.54024804
OS 52.14933436 -38.531927
OS 52.15673084 -38.51990772
OS 52.16320276 -38.50603932
OS 52.16782556 -38.4903218
OS 52.16967468 -38.4810762
OS 52.16967468 -38.47090604
OS 52.16967468 -38.46998148
OS 52.16967468 -38.46905692
OS 52.16967468 -38.46350956
OS 52.16782556 -38.45611308
OS 52.16597644 -38.44594292
OS 52.1622782 -38.4348482
OS 52.1576554 -38.42282892
OS 52.15025892 -38.41080964
OS 52.14008876 -38.39971492
OS 52.1391642 -38.39879036
OS 52.1345414 -38.39509212
OS 52.12806948 -38.39046932
OS 52.11974844 -38.38492196
OS 52.10865372 -38.38029916
OS 52.09570988 -38.37567636
OS 52.08091692 -38.37197812
OS 52.06427484 -38.37105356
OS 52.05687836 -38.37105356
OS 52.04855732 -38.37290268
OS 52.0374626 -38.3747518
OS 52.02544332 -38.37845004
OS 52.01342404 -38.38307284
OS 52.0004802 -38.39046932
OS 51.98846092 -38.39971492
OS 51.98753636 -38.40063948
OS 51.98383812 -38.40526228
OS 51.97829076 -38.4117342
OS 51.97181884 -38.4209798
OS 51.96534692 -38.43299908
OS 51.958875 -38.44779204
OS 51.95332764 -38.46535868
OS 51.9496294 -38.485699
OS 51.8710418 -38.4718306
OS 51.8710418 -38.47090604
OS 51.87196636 -38.46813236
OS 51.87289092 -38.46443412
OS 51.87381548 -38.45888676
OS 51.8756646 -38.45241484
OS 51.87843828 -38.44501836
OS 51.88398564 -38.42745172
OS 51.89323124 -38.4071114
OS 51.90432596 -38.38677108
OS 51.91819436 -38.36735532
OS 51.935761 -38.34978868
OS 51.93668556 -38.34886412
OS 51.93853468 -38.34793956
OS 51.94130836 -38.34609044
OS 51.9450066 -38.34331676
OS 51.9496294 -38.33961852
OS 51.95610132 -38.33592028
OS 51.96257324 -38.33222204
OS 51.97089428 -38.32759924
OS 51.98938548 -38.32020276
OS 52.01065036 -38.31280628
OS 52.03561348 -38.30818348
OS 52.04855732 -38.30633436
OS 52.07167132 -38.30633436
OS 52.08184148 -38.30725892
OE
OB 51.07499564 -38.37105356 H
OS 51.06944828 -38.37105356
OS 51.06575004 -38.37197812
OS 51.05557988 -38.37382724
OS 51.0435606 -38.37660092
OS 51.0296922 -38.38214828
OS 51.01489924 -38.39046932
OS 51.00750276 -38.39601668
OS 51.00010628 -38.40156404
OS 50.99363436 -38.40896052
OS 50.98716244 -38.41728156
OS 50.98716244 -38.41820612
OS 50.98531332 -38.42005524
OS 50.9834642 -38.42375348
OS 50.98069052 -38.42837628
OS 50.97791684 -38.43577276
OS 50.9742186 -38.4440938
OS 50.97144492 -38.45426396
OS 50.96774668 -38.46628324
OS 50.96404844 -38.48015164
OS 50.9603502 -38.49586916
OS 50.95665196 -38.5134358
OS 50.95387828 -38.53285156
OS 50.9511046 -38.555041
OS 50.94925548 -38.57907956
OS 50.94833092 -38.60496724
OS 50.94740636 -38.6336286
OS 50.94740636 -38.63547772
OS 50.94740636 -38.64010052
OS 50.94740636 -38.64842156
OS 50.94833092 -38.65951628
OS 50.94833092 -38.67153556
OS 50.94925548 -38.68632852
OS 50.95018004 -38.70204604
OS 50.95202916 -38.71868812
OS 50.95665196 -38.75474596
OS 50.95942564 -38.7723126
OS 50.96312388 -38.78895468
OS 50.96682212 -38.8046722
OS 50.97236948 -38.81946516
OS 50.97791684 -38.832409
OS 50.98438876 -38.84350372
OS 50.98438876 -38.84442828
OS 50.98623788 -38.84535284
OS 50.99086068 -38.85182476
OS 50.99918172 -38.8601458
OS 51.00935188 -38.8693914
OS 51.02322028 -38.878637
OS 51.0389378 -38.88695804
OS 51.05650444 -38.89342996
OS 51.06575004 -38.89435452
OS 51.0759202 -38.89527908
OS 51.08146756 -38.89527908
OS 51.0851658 -38.89435452
OS 51.0944114 -38.8925054
OS 51.10735524 -38.88880716
OS 51.12122364 -38.88233524
OS 51.13694116 -38.87308964
OS 51.14433764 -38.86754228
OS 51.15173412 -38.8601458
OS 51.1591306 -38.85274932
OS 51.16652708 -38.84350372
OS 51.16652708 -38.84257916
OS 51.1683762 -38.84073004
OS 51.17022532 -38.83795636
OS 51.17207444 -38.83333356
OS 51.17577268 -38.82686164
OS 51.17854636 -38.8185406
OS 51.1822446 -38.809295
OS 51.18594284 -38.79820028
OS 51.18871652 -38.78433188
OS 51.19241476 -38.76953892
OS 51.196113 -38.75197228
OS 51.19888668 -38.73348108
OS 51.2007358 -38.71129164
OS 51.20258492 -38.68817764
OS 51.20443404 -38.66228996
OS 51.20443404 -38.6336286
OS 51.20443404 -38.63270404
OS 51.20443404 -38.63177948
OS 51.20443404 -38.62715668
OS 51.20443404 -38.61883564
OS 51.20350948 -38.60774092
OS 51.20350948 -38.59572164
OS 51.20258492 -38.58092868
OS 51.20166036 -38.56521116
OS 51.19981124 -38.54764452
OS 51.19518844 -38.51251124
OS 51.19241476 -38.4949446
OS 51.18871652 -38.47830252
OS 51.18501828 -38.462585
OS 51.17947092 -38.44779204
OS 51.17392356 -38.4348482
OS 51.16745164 -38.42375348
OS 51.16745164 -38.42282892
OS 51.16560252 -38.42190436
OS 51.1637534 -38.41913068
OS 51.16097972 -38.41543244
OS 51.15265868 -38.4071114
OS 51.14248852 -38.39694124
OS 51.12862012 -38.38769564
OS 51.1129026 -38.3793746
OS 51.10458156 -38.37567636
OS 51.09533596 -38.37290268
OS 51.0851658 -38.37197812
OS 51.07499564 -38.37105356
OE
OB 54.05947532 -38.37105356 H
OS 54.05392796 -38.37105356
OS 54.05022972 -38.37197812
OS 54.04005956 -38.37382724
OS 54.02804028 -38.37660092
OS 54.01417188 -38.38214828
OS 53.99937892 -38.39046932
OS 53.99198244 -38.39601668
OS 53.98458596 -38.40156404
OS 53.97811404 -38.40896052
OS 53.97164212 -38.41728156
OS 53.97164212 -38.41820612
OS 53.969793 -38.42005524
OS 53.96794388 -38.42375348
OS 53.9651702 -38.42837628
OS 53.96239652 -38.43577276
OS 53.95869828 -38.4440938
OS 53.9559246 -38.45426396
OS 53.95222636 -38.46628324
OS 53.94852812 -38.48015164
OS 53.94482988 -38.49586916
OS 53.94113164 -38.5134358
OS 53.93835796 -38.53285156
OS 53.93558428 -38.555041
OS 53.93373516 -38.57907956
OS 53.9328106 -38.60496724
OS 53.93188604 -38.6336286
OS 53.93188604 -38.63547772
OS 53.93188604 -38.64010052
OS 53.93188604 -38.64842156
OS 53.9328106 -38.65951628
OS 53.9328106 -38.67153556
OS 53.93373516 -38.68632852
OS 53.93465972 -38.70204604
OS 53.93650884 -38.71868812
OS 53.94113164 -38.75474596
OS 53.94390532 -38.7723126
OS 53.94760356 -38.78895468
OS 53.9513018 -38.8046722
OS 53.95684916 -38.81946516
OS 53.96239652 -38.832409
OS 53.96886844 -38.84350372
OS 53.96886844 -38.84442828
OS 53.97071756 -38.84535284
OS 53.97534036 -38.85182476
OS 53.9836614 -38.8601458
OS 53.99383156 -38.8693914
OS 54.00769996 -38.878637
OS 54.02341748 -38.88695804
OS 54.04098412 -38.89342996
OS 54.05022972 -38.89435452
OS 54.06039988 -38.89527908
OS 54.06594724 -38.89527908
OS 54.06964548 -38.89435452
OS 54.07889108 -38.8925054
OS 54.09183492 -38.88880716
OS 54.10570332 -38.88233524
OS 54.12142084 -38.87308964
OS 54.12881732 -38.86754228
OS 54.1362138 -38.8601458
OS 54.14361028 -38.85274932
OS 54.15100676 -38.84350372
OS 54.15100676 -38.84257916
OS 54.15285588 -38.84073004
OS 54.154705 -38.83795636
OS 54.15655412 -38.83333356
OS 54.16025236 -38.82686164
OS 54.16302604 -38.8185406
OS 54.16672428 -38.809295
OS 54.17042252 -38.79820028
OS 54.1731962 -38.78433188
OS 54.17689444 -38.76953892
OS 54.18059268 -38.75197228
OS 54.18336636 -38.73348108
OS 54.18521548 -38.71129164
OS 54.1870646 -38.68817764
OS 54.18891372 -38.66228996
OS 54.18891372 -38.6336286
OS 54.18891372 -38.63270404
OS 54.18891372 -38.63177948
OS 54.18891372 -38.62715668
OS 54.18891372 -38.61883564
OS 54.18798916 -38.60774092
OS 54.18798916 -38.59572164
OS 54.1870646 -38.58092868
OS 54.18614004 -38.56521116
OS 54.18429092 -38.54764452
OS 54.17966812 -38.51251124
OS 54.17689444 -38.4949446
OS 54.1731962 -38.47830252
OS 54.16949796 -38.462585
OS 54.1639506 -38.44779204
OS 54.15840324 -38.4348482
OS 54.15193132 -38.42375348
OS 54.15193132 -38.42282892
OS 54.1500822 -38.42190436
OS 54.14823308 -38.41913068
OS 54.1454594 -38.41543244
OS 54.13713836 -38.4071114
OS 54.1269682 -38.39694124
OS 54.1130998 -38.38769564
OS 54.09738228 -38.3793746
OS 54.08906124 -38.37567636
OS 54.07981564 -38.37290268
OS 54.06964548 -38.37197812
OS 54.05947532 -38.37105356
OE
OB 49.87491676 -38.43669732 H
OS 49.67336268 -38.72331092
OS 49.87491676 -38.72331092
OS 49.87491676 -38.43669732
OE
OB 56.14158444 -38.38492196 H
OS 55.95852156 -38.38492196
OS 55.95852156 -38.61328828
OS 56.13048972 -38.61328828
OS 56.13696164 -38.61236372
OS 56.14343356 -38.61236372
OS 56.15083004 -38.61143916
OS 56.16839668 -38.60959004
OS 56.18781244 -38.6058918
OS 56.2072282 -38.60034444
OS 56.22479484 -38.59294796
OS 56.23311588 -38.58832516
OS 56.2395878 -38.5827778
OS 56.24143692 -38.58092868
OS 56.24513516 -38.57723044
OS 56.25068252 -38.56983396
OS 56.25715444 -38.56058836
OS 56.26362636 -38.54856908
OS 56.26917372 -38.53377612
OS 56.27287196 -38.51713404
OS 56.27472108 -38.49771828
OS 56.27472108 -38.49679372
OS 56.27472108 -38.49586916
OS 56.27472108 -38.49124636
OS 56.27379652 -38.48292532
OS 56.2719474 -38.47367972
OS 56.27009828 -38.46350956
OS 56.26640004 -38.45149028
OS 56.26085268 -38.44039556
OS 56.25438076 -38.42930084
OS 56.2534562 -38.42837628
OS 56.25068252 -38.42467804
OS 56.24605972 -38.42005524
OS 56.24051236 -38.41358332
OS 56.23219132 -38.4071114
OS 56.22294572 -38.40156404
OS 56.21277556 -38.39601668
OS 56.20075628 -38.39139388
OS 56.19983172 -38.39139388
OS 56.19613348 -38.39046932
OS 56.19058612 -38.38954476
OS 56.18318964 -38.38769564
OS 56.17209492 -38.38677108
OS 56.15822652 -38.38584652
OS 56.14158444 -38.38492196
OE
SE

### steps/pcb/layers/top_solder/features
UNITS=MM
#Layer_Color=8388736
#
#Feature symbol names
#
$0 r99.9998
$1 r1999.99854
$2 r2190.0007
$3 r5699.99876
$4 r1662.00074
$5 r1623.9998
$6 r1899.99874

#
#Feature attribute names
#
@0 .nomenclature
@1 .string
@2 .string_angle
@3 .geometry
@4 .pad_usage

#
#Feature attribute text strings
#
&0 SMD_RoundX1000.0005Y1000.0005
&1 Pad_Simple_X2090.0009Y2090.0009H1090.0004C2106.0004
&2 Pad_Simple_X5299.9996Y5299.9996H2999.9991C4015.9991
&3 Pad_Simple_X1562.0009Y1562.0009H961.9996C1977.9996
&4 Pad_Simple_X1524.0000Y1524.0000H762.0000C1778.0000
&5 Pad_Simple_X0.0000Y0.0000H3700.0002C4716.0002
&6 Pad_Simple_X1799.9989Y1799.9989H1200.0001C2216.0001

#
#Layer features
#
L -9.5600012 -24.45999934 40.4400004 -24.45999934 0 P 0
L -9.5600012 -35.9599992 -9.5600012 -24.45999934 0 P 0
L -9.5600012 -35.9599992 28.439999 -35.9599992 0 P 0
L -9.5600012 -39.45999982 -9.5600012 -35.9599992 0 P 0
L -9.5600012 -39.45999982 28.439999 -39.45999982 0 P 0
L -9.5600012 -42.96000044 -9.5600012 -39.45999982 0 P 0
L -9.5600012 -42.96000044 28.439999 -42.96000044 0 P 0
L -10.0600002 -23.96000034 62.93999858 -23.96000034 0 P 0
L -10.0600002 -43.45999944 -10.0600002 -23.96000034 0 P 0
L -10.0600002 -43.45999944 62.93999858 -43.45999944 0 P 0
L 28.439999 -35.96000174 45.44000056 -35.9599992 0 P 0
L 28.439999 -39.45999982 28.439999 -35.9599992 0 P 0
L 28.439999 -39.46000236 45.44000056 -39.45999982 0 P 0
L 28.439999 -42.96000044 28.439999 -39.45999982 0 P 0
L 28.439999 -42.96000298 45.44000056 -42.96000044 0 P 0
L 40.4400004 -24.45999934 62.43999958 -24.45999934 0 P 0
L 40.4400004 -35.9599992 40.4400004 -24.45999934 0 P 0
L 45.44000056 -35.9599992 62.43999958 -35.9599992 0 P 0
L 45.44000056 -39.45999982 62.43999958 -39.45999982 0 P 0
L 45.44000056 -42.96000044 45.44000056 -35.9599992 0 P 0
L 45.44000056 -42.96000044 62.43999958 -42.96000044 0 P 0
L 62.43999958 -35.9599992 62.43999958 -24.45999934 0 P 0
L 62.43999958 -42.96000044 62.43999958 -35.9599992 0 P 0
L 62.93999858 -43.45999944 62.93999858 -23.96000034 0 P 0
P -2.20000068 -2.69999968 1 P 0 0 ;3=0,4=0
P -2.37499906 43.52500058 1 P 0 0 ;3=0,4=0
P 0 0 2 P 0 0 ;3=1,4=0
P 0 40.64 2 P 0 0 ;3=1,4=0
P 2.0779994 43.3299997 2 P 0 0 ;3=1,4=0
P 4.39999882 2.00000108 0 P 0 0 ;3=5,4=0
P 4.39999882 38.599999 0 P 0 0 ;3=5,4=0
P 4.8300005 7.63999996 6 P 0 0 ;3=6,4=0
P 4.8300005 7.63999996 5 P 0 0 ;3=4,4=0
P 4.8300005 12.71999996 6 P 0 0 ;3=6,4=0
P 4.8300005 12.71999996 5 P 0 0 ;3=4,4=0
P 4.8300005 17.79999996 6 P 0 0 ;3=6,4=0
P 4.8300005 17.79999996 5 P 0 0 ;3=4,4=0
P 4.8300005 33.03999996 5 P 0 0 ;3=4,4=0
P 4.8300005 33.03999996 6 P 0 0 ;3=6,4=0
P 5.1259994 43.3299997 2 P 0 0 ;3=1,4=0
P 8.1739994 43.3299997 2 P 0 0 ;3=1,4=0
P 11.2219994 43.3299997 2 P 0 0 ;3=1,4=0
P 14.2699994 43.3299997 2 P 0 0 ;3=1,4=0
P 20.24000016 42.13999954 3 P 0 0 ;3=2,4=0
P 20.43999976 -1.26000002 3 P 0 0 ;3=2,4=0
P 35.50000012 -1.00000054 0 P 0 0 ;3=5,4=0
P 36.20000126 40.10000108 0 P 0 0 ;3=5,4=0
P 37.8500005 7.63999996 6 P 0 0 ;3=6,4=0
P 37.8500005 7.63999996 4 P 0 0 ;3=3,4=0
P 37.8500005 12.71999996 6 P 0 0 ;3=6,4=0
P 37.8500005 12.71999996 4 P 0 0 ;3=3,4=0
P 37.8500005 17.79999996 6 P 0 0 ;3=6,4=0
P 37.8500005 17.79999996 4 P 0 0 ;3=3,4=0
P 37.8500005 22.87999996 4 P 0 0 ;3=3,4=0
P 37.8500005 22.87999996 6 P 0 0 ;3=6,4=0
P 37.8500005 33.03999996 4 P 0 0 ;3=3,4=0
P 37.8500005 33.03999996 6 P 0 0 ;3=6,4=0
P 40.64 0 2 P 0 0 ;3=1,4=0
P 40.64 40.64 2 P 0 0 ;3=1,4=0
P 40.67999992 20.33999996 2 P 0 0 ;3=1,4=0
P 43.12499884 43.52500058 1 P 0 0 ;3=0,4=0
S P 0
OB 23.88042214 44.95700432 I
OS 23.88422198 44.95573686
OS 23.91970832 44.9544694
OS 23.9235107 44.95320194
OS 23.928578 44.95193448
OS 23.93491276 44.94939956
OS 23.9399826 44.9481321
OS 23.9577245 44.94559972
OS 23.97103156 44.94243234
OS 23.9818037 44.93673004
OS 23.988141 44.93419512
OS 23.99637568 44.93102774
OS 24.00081052 44.92785782
OS 24.00714782 44.92405798
OS 24.01348512 44.92152306
OS 24.02172234 44.91835314
OS 24.02362226 44.91645322
OS 24.02615718 44.91518576
OS 24.0400967 44.90884846
OS 24.04896892 44.90377862
OS 24.05530368 44.89997878
OS 24.06163844 44.89744386
OS 24.06670828 44.8961764
OS 24.07367804 44.8904741
OS 24.07811542 44.88603672
OS 24.08065034 44.88476926
OS 24.08635264 44.8790695
OS 24.0876201 44.87653458
OS 24.08952002 44.87463466
OS 24.09205494 44.8733672
OS 24.0990247 44.86639744
OS 24.10029216 44.86386252
OS 24.10219462 44.86196006
OS 24.104727 44.8606926
OS 24.11169676 44.85372284
OS 24.11296422 44.85118792
OS 24.11486414 44.849288
OS 24.11739906 44.84802054
OS 24.12310136 44.84231824
OS 24.12436882 44.83978332
OS 24.1275362 44.8366134
OS 24.13007112 44.83534848
OS 24.1345085 44.8309111
OS 24.13577596 44.82837618
OS 24.14337818 44.8207765
OS 24.1459131 44.8144392
OS 24.14908048 44.80620198
OS 24.1522504 44.80176714
OS 24.1585877 44.79542984
OS 24.16238754 44.78909254
OS 24.16872484 44.78275524
OS 24.17315714 44.77071564
OS 24.1750596 44.7662808
OS 24.1813969 44.7561462
OS 24.18266436 44.74727398
OS 24.18392928 44.74220414
OS 24.18519674 44.73460192
OS 24.19406896 44.71559002
OS 24.19596888 44.70355296
OS 24.20103872 44.6908809
OS 24.20230618 44.68581106
OS 24.20357364 44.67820884
OS 24.2048411 44.65032726
OS 24.20610856 44.61611092
OS 24.20737602 44.54007602
OS 24.20800848 41.48280756
OS 24.20800848 41.4815401
OS 24.20737602 38.81332344
OS 24.20800848 38.80888606
OS 24.20674102 38.80508368
OS 24.20737602 38.7841744
OS 24.20674102 38.76453258
OS 24.20800848 38.7607302
OS 24.20674102 38.7556629
OS 24.20547356 38.74679068
OS 24.20674102 38.74172084
OS 24.20737602 38.73475108
OS 24.20610856 38.72841378
OS 24.2048411 38.72334648
OS 24.20357364 38.6903976
OS 24.20103872 38.6840603
OS 24.19216904 38.67519062
OS 24.18583174 38.6726557
OS 24.15034794 38.67138824
OS 24.1465481 38.67012078
OS 24.14147826 38.66885332
OS 24.12943866 38.67075324
OS 24.12627128 38.67138824
OS 24.1224689 38.67012078
OS 24.11359668 38.66885332
OS 24.10092716 38.67012078
OS 24.08825256 38.66885332
OS 24.06227344 38.66948832
OS 24.05276876 38.66885332
OS 24.04896892 38.67012078
OS 24.04199916 38.67075324
OS 24.0343944 38.66948832
OS 24.02742464 38.66885332
OS 24.02362226 38.67012078
OS 24.01348512 38.6726557
OS 23.9818037 38.67392316
OS 23.97483394 38.67962546
OS 23.9697641 38.6846953
OS 23.96722918 38.6910326
OS 23.96596172 38.72651386
OS 23.96469426 38.73031624
OS 23.9634268 38.73918592
OS 23.96469426 38.7429883
OS 23.96596172 38.75059306
OS 23.96469426 38.75439544
OS 23.9634268 38.76326512
OS 23.96469426 38.76833242
OS 23.9640618 38.7905117
OS 23.96469426 38.80508368
OS 23.9634268 38.80888606
OS 23.9640618 38.8259955
OS 23.96279434 44.54767824
OS 23.96215934 44.55211562
OS 23.9634268 44.555918
OS 23.96215934 44.57746228
OS 23.96089188 44.58126212
OS 23.95962696 44.62181576
OS 23.95709204 44.62815052
OS 23.95328966 44.63702274
OS 23.9520222 44.64209258
OS 23.94695236 44.65095972
OS 23.94188252 44.65602956
OS 23.94061506 44.65856448
OS 23.93491276 44.66553424
OS 23.93237784 44.6668017
OS 23.92667808 44.672504
OS 23.92541062 44.67503892
OS 23.92224324 44.67820884
OS 23.91970832 44.6794763
OS 23.91273856 44.6851786
OS 23.90956864 44.68834598
OS 23.90323388 44.6908809
OS 23.89626158 44.69278082
OS 23.88042214 44.70102058
OS 23.8753523 44.7022855
OS 23.86521516 44.70355296
OS 23.86141278 44.70481788
OS 23.8525431 44.70862026
OS 23.84747326 44.70988772
OS 23.83099882 44.71115518
OS 23.80121986 44.71305764
OS 23.74925908 44.71432256
OS 23.25756334 44.71559002
OS 23.24932612 44.71622502
OS 23.24552374 44.71495756
OS 23.222712 44.71622502
OS 23.21890962 44.71495756
OS 23.20370518 44.71622502
OS 23.1999028 44.71749248
OS 23.16948884 44.71875994
OS 23.16315154 44.72256232
OS 23.15618178 44.72826462
OS 23.15491432 44.73079954
OS 23.1523794 44.7371343
OS 23.1517444 44.75804612
OS 23.1523794 44.76501334
OS 23.15111194 44.76881572
OS 23.14921202 44.77705294
OS 23.14857956 44.78655762
OS 23.14984448 44.79036
OS 23.14921202 44.8138042
OS 23.14984448 44.82457634
OS 23.14857956 44.82837618
OS 23.14921202 44.85942514
OS 23.14857956 44.87019728
OS 23.14984448 44.87399966
OS 23.14921202 44.8961764
OS 23.15047694 44.90124624
OS 23.1517444 44.907581
OS 23.1523794 44.91455076
OS 23.15111194 44.91708568
OS 23.1523794 44.92088806
OS 23.15364686 44.94116488
OS 23.1580817 44.94686718
OS 23.16061662 44.9481321
OS 23.16315154 44.95193448
OS 23.16948884 44.9544694
OS 23.20433764 44.95637186
OS 23.20940748 44.95763932
OS 23.22144454 44.95827178
OS 23.22524692 44.95700432
OS 23.24805866 44.95827178
OS 23.25186104 44.95700432
OS 23.26833548 44.95827178
OS 23.88042214 44.95700432
OE
SE
S P 0
OB 24.62937416 40.45695998 I
OS 24.65915312 40.45505752
OS 24.67182518 40.45379006
OS 24.67816248 40.4525226
OS 24.68449978 40.44998768
OS 24.692737 40.4468203
OS 24.70160922 40.44555538
OS 24.70667652 40.44428792
OS 24.71491374 40.44112054
OS 24.72251596 40.4360507
OS 24.73645802 40.43098086
OS 24.74089286 40.42781348
OS 24.74723016 40.42147618
OS 24.74976254 40.42020872
OS 24.76813944 40.40183436
OS 24.76940436 40.39929944
OS 24.7738392 40.39612952
OS 24.7808115 40.38915976
OS 24.78207896 40.38662484
OS 24.7865138 40.38346
OS 24.80488816 40.3650831
OS 24.80615562 40.36254818
OS 24.81249292 40.35621342
OS 24.81376038 40.3536785
OS 24.8162953 40.3473412
OS 24.81946268 40.33910398
OS 24.82516752 40.3295993
OS 24.8276999 40.31946216
OS 24.82959982 40.30869002
OS 24.83213474 40.30235526
OS 24.83530212 40.2941155
OS 24.83656958 40.28524582
OS 24.83783704 40.26877138
OS 24.8391045 40.25609932
OS 24.84037196 40.2244179
OS 24.8391045 40.22061552
OS 24.83783704 40.18513172
OS 24.83656958 40.18132934
OS 24.83530212 40.16865728
OS 24.83023228 40.15725268
OS 24.8276999 40.147113
OS 24.82643244 40.13824332
OS 24.82136514 40.12937364
OS 24.8162953 40.1179665
OS 24.81312792 40.10972928
OS 24.80488816 40.10149206
OS 24.80362324 40.09895714
OS 24.79918586 40.09325484
OS 24.79665094 40.09198738
OS 24.77827658 40.07361302
OS 24.77700912 40.0710781
OS 24.77510666 40.06917818
OS 24.77257174 40.06791072
OS 24.76687198 40.06220842
OS 24.76560452 40.0596735
OS 24.76243714 40.05650612
OS 24.75990222 40.05523866
OS 24.75293246 40.04953382
OS 24.74976254 40.04636644
OS 24.74342778 40.04383152
OS 24.73519056 40.04066414
OS 24.73075318 40.03749422
OS 24.71427874 40.029892
OS 24.692737 40.01975486
OS 24.6813324 40.0184874
OS 24.67753002 40.01721994
OS 24.6686578 40.0134201
OS 24.65978812 40.01088518
OS 24.6509159 40.00961772
OS 24.62620678 40.00771526
OS 24.60529496 40.0070828
OS 24.60149258 40.00835026
OS 24.57298108 40.01025018
OS 24.56664378 40.01151764
OS 24.55650664 40.01532002
OS 24.5457345 40.0184874
OS 24.54066466 40.01975486
OS 24.53115998 40.02165732
OS 24.51532054 40.029892
OS 24.50708332 40.03305938
OS 24.50264848 40.03496184
OS 24.49947856 40.03812922
OS 24.4988461 40.04002914
OS 24.49631118 40.0412966
OS 24.49377626 40.04383152
OS 24.49124134 40.04509898
OS 24.48553904 40.05080128
OS 24.48427158 40.0533362
OS 24.48237166 40.05523866
OS 24.47983674 40.05650612
OS 24.4741319 40.06220842
OS 24.47286444 40.06474334
OS 24.46969706 40.06791072
OS 24.46716468 40.06917818
OS 24.46272984 40.07361302
OS 24.46146238 40.07614794
OS 24.458295 40.07931786
OS 24.45576008 40.08058278
OS 24.45005524 40.08628508
OS 24.44879032 40.08882
OS 24.4456204 40.09198738
OS 24.44308548 40.09325484
OS 24.43865064 40.09768968
OS 24.43738318 40.1002246
OS 24.42977842 40.10782936
OS 24.42851096 40.11036428
OS 24.42597858 40.11669904
OS 24.42280866 40.1249388
OS 24.42090874 40.12683872
OS 24.41964128 40.12937364
OS 24.41710636 40.13190856
OS 24.41267152 40.14394816
OS 24.4101366 40.15028038
OS 24.4044343 40.15978506
OS 24.40190192 40.16865728
OS 24.39999946 40.18069688
OS 24.3930297 40.19780632
OS 24.38922732 40.2358225
OS 24.39049478 40.23962488
OS 24.39239724 40.26306908
OS 24.39366216 40.26813638
OS 24.39746454 40.27827606
OS 24.40063446 40.28651328
OS 24.40253438 40.29855288
OS 24.40380184 40.30362018
OS 24.41330398 40.32199708
OS 24.4164739 40.33023176
OS 24.42090874 40.33720406
OS 24.42724604 40.35114358
OS 24.4335808 40.36254818
OS 24.43865064 40.37395532
OS 24.44372048 40.382825
OS 24.44879032 40.3878923
OS 24.45005524 40.39042722
OS 24.45322516 40.39486206
OS 24.45576008 40.39612952
OS 24.458295 40.39866444
OS 24.46082738 40.3999319
OS 24.46589722 40.40753666
OS 24.46843214 40.40880412
OS 24.47539936 40.41450642
OS 24.47983674 40.41894126
OS 24.49567618 40.4246461
OS 24.4988461 40.42781348
OS 24.50138102 40.42908094
OS 24.50201348 40.4297134
OS 24.50264848 40.4303484
OS 24.51468808 40.43478324
OS 24.52102284 40.43731816
OS 24.5286276 40.442388
OS 24.53559482 40.44428792
OS 24.54446704 40.44555538
OS 24.55650664 40.44998768
OS 24.56727878 40.4531576
OS 24.57234608 40.45442506
OS 24.59959266 40.45632498
OS 24.61479964 40.45759244
OS 24.62557178 40.45822744
OS 24.62937416 40.45695998
OE
SE
S P 0
OB 24.63190908 41.19830724 I
OS 24.65788566 41.19640732
OS 24.66422296 41.19513986
OS 24.6743601 41.19133748
OS 24.68513224 41.1881701
OS 24.69020208 41.18690264
OS 24.69780684 41.18563518
OS 24.70667652 41.18056534
OS 24.71808112 41.1754955
OS 24.72441842 41.17296058
OS 24.72695334 41.17169312
OS 24.73582302 41.1653609
OS 24.74089286 41.16409344
OS 24.74913008 41.16092352
OS 24.75609984 41.15395376
OS 24.75863476 41.1526863
OS 24.76116968 41.15015138
OS 24.7637046 41.14888392
OS 24.76813944 41.14444908
OS 24.76940436 41.14191416
OS 24.77257174 41.13874678
OS 24.77510666 41.13747932
OS 24.77954404 41.13304448
OS 24.7808115 41.13050956
OS 24.78524634 41.12607218
OS 24.78778126 41.12480726
OS 24.79094864 41.12163734
OS 24.7922161 41.11910242
OS 24.79475102 41.1165675
OS 24.79601848 41.11403512
OS 24.80108832 41.10896528
OS 24.80362324 41.10263052
OS 24.80488816 41.09756068
OS 24.810593 41.09059092
OS 24.81502784 41.08615608
OS 24.82009768 41.07728386
OS 24.82516752 41.07221402
OS 24.8276999 41.06334434
OS 24.82896482 41.0519372
OS 24.83403466 41.04053514
OS 24.83530212 41.0354653
OS 24.83656958 41.02659308
OS 24.83783704 41.01392102
OS 24.8391045 40.98984182
OS 24.84037196 40.96956754
OS 24.8391045 40.95689548
OS 24.83720458 40.92711144
OS 24.83593712 40.91570938
OS 24.83466966 40.91063954
OS 24.83213474 40.90430224
OS 24.82896482 40.89606502
OS 24.8276999 40.89099772
OS 24.8276999 40.88973026
OS 24.82643244 40.87959058
OS 24.82073014 40.87262082
OS 24.81122546 40.8593163
OS 24.80742308 40.85551392
OS 24.80615562 40.852979
OS 24.80108832 40.84030694
OS 24.79538348 40.83333718
OS 24.7922161 40.83016726
OS 24.79094864 40.82763234
OS 24.78524634 40.82193004
OS 24.78271142 40.82066258
OS 24.77954404 40.8174952
OS 24.77827658 40.81496028
OS 24.77257174 40.80925798
OS 24.77003936 40.80799052
OS 24.76687198 40.80482314
OS 24.76560452 40.80229076
OS 24.76116968 40.79785338
OS 24.75863476 40.79658592
OS 24.75103 40.7889837
OS 24.74469524 40.78644878
OS 24.73645802 40.78327886
OS 24.72885326 40.7769441
OS 24.72568588 40.77377418
OS 24.71681366 40.76870688
OS 24.71174382 40.76363704
OS 24.69653938 40.76110212
OS 24.68449978 40.75666728
OS 24.67879748 40.75476482
OS 24.67372764 40.75349736
OS 24.66485542 40.7522299
OS 24.64077876 40.75096244
OS 24.63190908 40.74969498
OS 24.58502068 40.75096244
OS 24.5812183 40.7522299
OS 24.56474386 40.75349736
OS 24.55587164 40.75729974
OS 24.54953434 40.75983466
OS 24.54446704 40.76110212
OS 24.5336949 40.76300204
OS 24.52736014 40.76553696
OS 24.51785546 40.77123926
OS 24.50581586 40.77567664
OS 24.50138102 40.77884402
OS 24.49631118 40.78391386
OS 24.49377626 40.78518132
OS 24.4868065 40.79088362
OS 24.48237166 40.79531846
OS 24.46653222 40.8010233
OS 24.4639973 40.80355568
OS 24.46272984 40.80608806
OS 24.45512508 40.8111579
OS 24.45005524 40.81622774
OS 24.44879032 40.81876266
OS 24.44118556 40.82636488
OS 24.43865064 40.83270218
OS 24.43675072 40.83967194
OS 24.43484826 40.8415744
OS 24.4335808 40.84410932
OS 24.42724604 40.85044408
OS 24.42597858 40.852979
OS 24.42027374 40.85994876
OS 24.4158389 40.86438614
OS 24.4101366 40.88022558
OS 24.4044343 40.88973026
OS 24.40316938 40.89859994
OS 24.40190192 40.90366978
OS 24.39999946 40.91951176
OS 24.398732 40.92457906
OS 24.39556462 40.93154882
OS 24.3930297 40.9404185
OS 24.39176224 40.94929072
OS 24.39049478 40.96196278
OS 24.39176224 40.99110928
OS 24.3930297 40.99491166
OS 24.39429716 41.00251642
OS 24.399367 41.01392102
OS 24.40063446 41.01899086
OS 24.40190192 41.03166292
OS 24.40380184 41.04370252
OS 24.40696922 41.0519372
OS 24.41203652 41.06334434
OS 24.41330398 41.06841418
OS 24.41457144 41.07728386
OS 24.4158389 41.0823537
OS 24.4215412 41.08932346
OS 24.42344366 41.09122592
OS 24.42471112 41.0937583
OS 24.43041342 41.1007306
OS 24.4342158 41.10453044
OS 24.43611572 41.10516544
OS 24.43738318 41.10769782
OS 24.4456204 41.11593504
OS 24.44815532 41.1172025
OS 24.45449262 41.12480726
OS 24.458295 41.1286071
OS 24.46019492 41.1292421
OS 24.46146238 41.13177702
OS 24.46969706 41.14001424
OS 24.47223198 41.1412817
OS 24.47539936 41.14571654
OS 24.4811042 41.15141884
OS 24.48363658 41.1526863
OS 24.49124134 41.16029106
OS 24.49757864 41.16282598
OS 24.50581586 41.16599082
OS 24.5102507 41.16916074
OS 24.51532054 41.17422804
OS 24.51785546 41.1754955
OS 24.52482522 41.18120034
OS 24.53432736 41.18690264
OS 24.54700196 41.1881701
OS 24.5508018 41.18943756
OS 24.55967402 41.1932374
OS 24.56854624 41.19577232
OS 24.57741592 41.19703978
OS 24.60086012 41.19894224
OS 24.6281067 41.1995747
OS 24.63190908 41.19830724
OE
SE
S P 0
OB 24.63824384 41.93965704 I
OS 24.65154836 41.93775458
OS 24.6566182 41.93648712
OS 24.66358796 41.93331974
OS 24.67246018 41.93078482
OS 24.6870347 41.9288849
OS 24.69463692 41.92761744
OS 24.69970676 41.92634998
OS 24.71301128 41.91938022
OS 24.72505088 41.91494284
OS 24.73202064 41.910508
OS 24.73455556 41.90797308
OS 24.75039754 41.90227078
OS 24.75863476 41.89403356
OS 24.76116968 41.8927661
OS 24.76433706 41.89086618
OS 24.76560452 41.88833126
OS 24.7922161 41.86171968
OS 24.79348356 41.85918476
OS 24.80108832 41.85158
OS 24.80552316 41.8395404
OS 24.81186046 41.82940326
OS 24.81502784 41.82243604
OS 24.81819522 41.81419628
OS 24.82453252 41.80405914
OS 24.82896482 41.793287
OS 24.83213474 41.78504978
OS 24.83530212 41.77808002
OS 24.83656958 41.7692078
OS 24.8391045 41.734994
OS 24.84037196 41.70837988
OS 24.8391045 41.70458004
OS 24.83720458 41.66719378
OS 24.83466966 41.6519868
OS 24.83023228 41.6412172
OS 24.8276999 41.63107752
OS 24.82643244 41.62220784
OS 24.82136514 41.61333562
OS 24.8162953 41.60193102
OS 24.81312792 41.59369126
OS 24.80488816 41.58545404
OS 24.80362324 41.58292166
OS 24.7979184 41.5759519
OS 24.79475102 41.57278452
OS 24.79094864 41.5639123
OS 24.78968118 41.55884246
OS 24.78397888 41.5518727
OS 24.78144396 41.55060524
OS 24.77827658 41.54743786
OS 24.77700912 41.54490294
OS 24.77510666 41.54300302
OS 24.7687719 41.5404681
OS 24.76053468 41.53729818
OS 24.75609984 41.5341308
OS 24.74976254 41.5277935
OS 24.74723016 41.52652604
OS 24.74025786 41.52082628
OS 24.73709048 41.5176589
OS 24.7212485 41.5119566
OS 24.71934858 41.51005414
OS 24.70794398 41.5049843
OS 24.70287668 41.50371684
OS 24.69210454 41.50181692
OS 24.68576724 41.499282
OS 24.67753002 41.49611462
OS 24.66485542 41.49484716
OS 24.65978812 41.4935797
OS 24.62493932 41.49167978
OS 24.60656242 41.49104478
OS 24.60276004 41.49231224
OS 24.56854624 41.4935797
OS 24.56474386 41.49484716
OS 24.55206926 41.49611462
OS 24.53812974 41.50245192
OS 24.52989252 41.5056193
OS 24.5229253 41.51005414
OS 24.50898324 41.51639144
OS 24.49757864 41.52272874
OS 24.4861715 41.5277935
OS 24.47730182 41.53286334
OS 24.47223198 41.53793318
OS 24.46969706 41.53920064
OS 24.46272984 41.54490294
OS 24.46146238 41.54743786
OS 24.45576008 41.55314016
OS 24.45322516 41.55440762
OS 24.4513227 41.55631008
OS 24.45005524 41.55884246
OS 24.44435294 41.5645473
OS 24.44181802 41.56581476
OS 24.43865064 41.56898214
OS 24.43738318 41.57151706
OS 24.43168088 41.57848682
OS 24.42851096 41.5816542
OS 24.42597858 41.58798896
OS 24.42471112 41.5930588
OS 24.41964128 41.60193102
OS 24.41457144 41.61333562
OS 24.41203652 41.6285426
OS 24.40316938 41.64755196
OS 24.40190192 41.65642164
OS 24.399367 41.66656132
OS 24.39429716 41.67796592
OS 24.3930297 41.68303576
OS 24.39176224 41.69190544
OS 24.38922732 41.71978448
OS 24.39049478 41.72358686
OS 24.39239724 41.7470336
OS 24.39366216 41.75336836
OS 24.39809954 41.7641405
OS 24.40063446 41.77047526
OS 24.40190192 41.77934748
OS 24.40380184 41.7875847
OS 24.41330398 41.80595906
OS 24.4164739 41.81419628
OS 24.42090874 41.82116858
OS 24.42597858 41.83257064
OS 24.43104588 41.84144286
OS 24.43484826 41.84524524
OS 24.43611572 41.84777762
OS 24.43865064 41.85031254
OS 24.4399181 41.85284746
OS 24.44181802 41.85474992
OS 24.44435294 41.85601738
OS 24.4513227 41.86298714
OS 24.45259016 41.86552206
OS 24.45449262 41.86742198
OS 24.45702754 41.86868944
OS 24.4639973 41.8756592
OS 24.46526476 41.87819412
OS 24.46716468 41.88009404
OS 24.46969706 41.8813615
OS 24.47539936 41.8870638
OS 24.47666682 41.88959872
OS 24.47983674 41.8927661
OS 24.48237166 41.89403356
OS 24.48934142 41.89973586
OS 24.4925088 41.90290578
OS 24.4988461 41.90543816
OS 24.50391594 41.90670562
OS 24.51785546 41.91557784
OS 24.52989252 41.92001268
OS 24.53559482 41.9231826
OS 24.53686228 41.9231826
OS 24.54826942 41.9282499
OS 24.56094148 41.92951736
OS 24.57234608 41.93078482
OS 24.5812183 41.9345872
OS 24.5875556 41.93712212
OS 24.5926229 41.93838958
OS 24.60719488 41.9402895
OS 24.634444 41.9409245
OS 24.63824384 41.93965704
OE
SE
S P 0
OB 24.66739034 42.66959716 I
OS 24.67119272 42.6683297
OS 24.68893462 42.66706224
OS 24.70287668 42.66072748
OS 24.7092089 42.65819256
OS 24.72061604 42.6518578
OS 24.73202064 42.64678796
OS 24.74342778 42.64045066
OS 24.75483238 42.63538336
OS 24.76623952 42.62904606
OS 24.7687719 42.62524368
OS 24.77130682 42.62397622
OS 24.77827658 42.61827392
OS 24.78397888 42.6100367
OS 24.7865138 42.60876924
OS 24.78841372 42.60686678
OS 24.79094864 42.60053456
OS 24.7928511 42.59356226
OS 24.79601848 42.58912742
OS 24.80235578 42.58279012
OS 24.80362324 42.58025774
OS 24.80932554 42.57328544
OS 24.81249292 42.57011806
OS 24.81376038 42.56758314
OS 24.8162953 42.56124584
OS 24.81946268 42.55300862
OS 24.82516752 42.54350648
OS 24.8276999 42.53336934
OS 24.82959982 42.5225972
OS 24.83530212 42.50802268
OS 24.83783704 42.49028078
OS 24.83973696 42.45416452
OS 24.84037196 42.44085746
OS 24.8391045 42.43705508
OS 24.83783704 42.40157382
OS 24.83656958 42.39777144
OS 24.83530212 42.38382938
OS 24.82896482 42.36988986
OS 24.82579998 42.36165518
OS 24.82136514 42.35468542
OS 24.81502784 42.34074336
OS 24.80869054 42.32933876
OS 24.80362324 42.31793162
OS 24.7985534 42.30906194
OS 24.79348356 42.30399464
OS 24.7922161 42.30145972
OS 24.7865138 42.29448996
OS 24.78397888 42.2932225
OS 24.77954404 42.28878766
OS 24.77827658 42.28625274
OS 24.7738392 42.28181536
OS 24.76750698 42.27801552
OS 24.76116968 42.27167822
OS 24.75609984 42.27041076
OS 24.74786262 42.26724338
OS 24.7396254 42.25900362
OS 24.73075318 42.25393632
OS 24.72568588 42.24886648
OS 24.71934858 42.24633156
OS 24.71491374 42.2456991
OS 24.71427874 42.24506664
OS 24.70287668 42.24379918
OS 24.6863997 42.23619442
OS 24.67626256 42.23366204
OS 24.65852066 42.23239458
OS 24.65218336 42.22985966
OS 24.64394868 42.22668974
OS 24.63697892 42.22478982
OS 24.63190908 42.22352236
OS 24.62303686 42.2222549
OS 24.61796702 42.22098744
OS 24.60149258 42.2222549
OS 24.5976902 42.22352236
OS 24.58945298 42.22542228
OS 24.58311822 42.2279572
OS 24.56854624 42.23239458
OS 24.55587164 42.23366204
OS 24.5457345 42.2349295
OS 24.52419276 42.24506664
OS 24.515953 42.24823148
OS 24.51405308 42.25013394
OS 24.51151816 42.2514014
OS 24.50391594 42.25647124
OS 24.49694364 42.25837116
OS 24.4925088 42.26027108
OS 24.48553904 42.26597592
OS 24.48237166 42.2691433
OS 24.47983674 42.27041076
OS 24.4741319 42.27611306
OS 24.47286444 42.27864798
OS 24.46969706 42.28181536
OS 24.46716468 42.28308282
OS 24.46272984 42.2875202
OS 24.46146238 42.29005512
OS 24.458295 42.2932225
OS 24.45576008 42.29448996
OS 24.45005524 42.30019226
OS 24.44879032 42.30272718
OS 24.4456204 42.30589202
OS 24.44308548 42.30715948
OS 24.43865064 42.31159686
OS 24.43738318 42.31413178
OS 24.42977842 42.321734
OS 24.42851096 42.32426892
OS 24.42597858 42.33060622
OS 24.42471112 42.33567606
OS 24.4158389 42.34834812
OS 24.41393898 42.35531788
OS 24.41140406 42.36165518
OS 24.40570176 42.37242478
OS 24.40316938 42.38129446
OS 24.398732 42.40854358
OS 24.39683208 42.41297842
OS 24.39429716 42.41931572
OS 24.3930297 42.42438302
OS 24.39176224 42.4332527
OS 24.39049478 42.4459273
OS 24.39176224 42.4750738
OS 24.3930297 42.47887618
OS 24.39429716 42.48774586
OS 24.40063446 42.50168538
OS 24.40190192 42.51815982
OS 24.4050693 42.53146688
OS 24.41203652 42.54477394
OS 24.41520644 42.55300862
OS 24.41773882 42.55934592
OS 24.42090874 42.5625133
OS 24.4221762 42.56504822
OS 24.42597858 42.57392044
OS 24.42914596 42.58215766
OS 24.43738318 42.59039488
OS 24.43865064 42.5929298
OS 24.45702754 42.61130416
OS 24.45956246 42.61257162
OS 24.46146238 42.61447154
OS 24.46272984 42.61700646
OS 24.48237166 42.63664828
OS 24.48490404 42.63791574
OS 24.49124134 42.64425304
OS 24.49757864 42.64678796
OS 24.50581586 42.64995534
OS 24.51912292 42.65692764
OS 24.52925752 42.65946002
OS 24.5387622 42.66136248
OS 24.54953434 42.66579478
OS 24.55460418 42.66706224
OS 24.56727878 42.6683297
OS 24.58375322 42.66959716
OS 24.61163226 42.67086462
OS 24.66739034 42.66959716
OE
SE
S P 0
OB 31.31417664 44.95700432 I
OS 31.31797902 44.95573686
OS 31.35219536 44.9544694
OS 31.35599774 44.95320194
OS 31.36233504 44.95193448
OS 31.3686698 44.94939956
OS 31.3737371 44.9481321
OS 31.39148154 44.94559972
OS 31.40478606 44.94243234
OS 31.42062804 44.93546258
OS 31.42949772 44.93419512
OS 31.43456756 44.93292766
OS 31.44280478 44.92976028
OS 31.4447047 44.92785782
OS 31.44723962 44.92659036
OS 31.45611184 44.92279052
OS 31.46434906 44.9196206
OS 31.47131882 44.91518576
OS 31.4852558 44.90884846
OS 31.4915931 44.90504608
OS 31.49666294 44.89997878
OS 31.49919786 44.89871132
OS 31.50870254 44.89174156
OS 31.509335 44.8898391
OS 31.51186992 44.88857164
OS 31.52454452 44.88350434
OS 31.5270769 44.88223688
OS 31.53468166 44.87463466
OS 31.53721658 44.8733672
OS 31.54165142 44.87019728
OS 31.54291888 44.8676649
OS 31.54545126 44.86512998
OS 31.54608626 44.86322752
OS 31.54861864 44.86196006
OS 31.60501172 44.80556698
OS 31.60627918 44.80303206
OS 31.61388394 44.79542984
OS 31.61641886 44.78909254
OS 31.61768632 44.7840227
OS 31.626556 44.77008318
OS 31.62782346 44.76501334
OS 31.63669568 44.74854144
OS 31.64049806 44.73966922
OS 31.64303298 44.73333446
OS 31.64810028 44.72446224
OS 31.65190266 44.71559002
OS 31.65380512 44.70355296
OS 31.6576075 44.69341582
OS 31.66077488 44.68644606
OS 31.66204234 44.68137622
OS 31.6633098 44.672504
OS 31.66457726 44.6674367
OS 31.66647464 44.64525742
OS 31.6677421 44.64019012
OS 31.6734444 44.62181576
OS 31.67534686 44.60597378
OS 31.67661432 44.58316458
OS 31.67724678 44.57999466
OS 31.67597932 44.57619482
OS 31.67471186 44.54704578
OS 31.6734444 44.5432434
OS 31.67217694 44.53437372
OS 31.66964456 44.52803642
OS 31.66710964 44.51916674
OS 31.66584218 44.5140969
OS 31.66394226 44.49192016
OS 31.6626748 44.4843154
OS 31.66140734 44.47798064
OS 31.65887242 44.47164334
OS 31.65570504 44.46467358
OS 31.65317012 44.4558039
OS 31.6512702 44.44503176
OS 31.64873528 44.43869446
OS 31.64683536 44.43679454
OS 31.64049806 44.42285502
OS 31.63732814 44.41461526
OS 31.6328933 44.40891296
OS 31.63162584 44.40637804
OS 31.62909092 44.40004582
OS 31.62592354 44.39180606
OS 31.61895378 44.3848363
OS 31.61768632 44.38230138
OS 31.6088141 44.37089678
OS 31.60627918 44.36836186
OS 31.60184688 44.35632226
OS 31.5986795 44.35188742
OS 31.59360966 44.34681758
OS 31.5923422 44.34428266
OS 31.58980728 44.34175028
OS 31.58917482 44.33985036
OS 31.5866399 44.3385829
OS 31.52327706 44.27522006
OS 31.52074214 44.2739526
OS 31.51440484 44.2676153
OS 31.50806754 44.26508038
OS 31.49983032 44.261913
OS 31.49412802 44.2562107
OS 31.4915931 44.25494324
OS 31.48905818 44.25240832
OS 31.48272342 44.24860594
OS 31.47638866 44.24226864
OS 31.46054668 44.23656634
OS 31.45864422 44.23466642
OS 31.45611184 44.23339896
OS 31.44723962 44.22959658
OS 31.4383674 44.22832912
OS 31.4333001 44.22706166
OS 31.42506288 44.22389428
OS 31.41682566 44.21945944
OS 31.40795598 44.21692452
OS 31.39908376 44.21565706
OS 31.38704416 44.21122222
OS 31.38134186 44.2093223
OS 31.37246964 44.20805484
OS 31.32431632 44.20551992
OS 31.22420222 44.20425246
OS 30.54495034 44.202985
OS 30.54114796 44.20171754
OS 30.4993294 44.20045008
OS 30.49552702 44.19918262
OS 30.48538734 44.19791516
OS 30.47651766 44.19411278
OS 30.46637798 44.19157786
OS 30.45877576 44.19031294
OS 30.44230132 44.18270818
OS 30.43343164 44.18017326
OS 30.42455942 44.1789058
OS 30.4163222 44.17573842
OS 30.40681752 44.17003358
OS 30.39478046 44.16559874
OS 30.3878107 44.16116644
OS 30.37386864 44.15482914
OS 30.36246404 44.14849184
OS 30.3510569 44.14342454
OS 30.34218976 44.1383547
OS 30.33965484 44.13581978
OS 30.33711992 44.13455232
OS 30.33331754 44.13074994
OS 30.33078262 44.12948248
OS 30.32634778 44.12504764
OS 30.32508032 44.12251272
OS 30.32191294 44.11934534
OS 30.31937802 44.11807788
OS 30.31367572 44.11237558
OS 30.31240826 44.10984066
OS 30.3105058 44.1079382
OS 30.30797088 44.10667074
OS 30.30226858 44.10097098
OS 30.30100112 44.09843606
OS 30.29783374 44.09526868
OS 30.29529882 44.09400122
OS 30.28959652 44.08829892
OS 30.28832906 44.085764
OS 30.28516168 44.08259408
OS 30.28262676 44.08132662
OS 30.27819192 44.07689178
OS 30.27692446 44.07435686
OS 30.27312208 44.07055448
OS 30.27185462 44.0680221
OS 30.26805478 44.06421972
OS 30.2636174 44.05218012
OS 30.25918256 44.04521036
OS 30.25284526 44.03127084
OS 30.25031034 44.02493354
OS 30.24397558 44.01606386
OS 30.2395382 44.00402426
OS 30.23320344 43.99388458
OS 30.23003352 43.98691482
OS 30.22686614 43.97868014
OS 30.22433376 43.97234284
OS 30.22243384 43.97044292
OS 30.22116638 43.967908
OS 30.21863146 43.9615707
OS 30.217364 43.95270102
OS 30.21609654 43.94763118
OS 30.21292916 43.93939396
OS 30.20975924 43.92862182
OS 30.20849178 43.91594976
OS 30.20722432 43.89947532
OS 30.2053244 43.87603112
OS 30.2046894 43.8627266
OS 30.20595686 43.85892422
OS 30.20785932 43.82914272
OS 30.20912678 43.81520066
OS 30.21039424 43.80759844
OS 30.21419408 43.7974613
OS 30.21609654 43.79049154
OS 30.217364 43.7854217
OS 30.21926392 43.77591702
OS 30.22179884 43.76957972
OS 30.22876606 43.75374028
OS 30.23130098 43.7385333
OS 30.23637082 43.72966362
OS 30.2401732 43.7207914
OS 30.24270812 43.7144541
OS 30.2465105 43.70811934
OS 30.25284526 43.70178204
OS 30.25664764 43.69544474
OS 30.26298494 43.68910998
OS 30.26551986 43.68277522
OS 30.26868724 43.674538
OS 30.27185462 43.67010062
OS 30.27692446 43.66503332
OS 30.27819192 43.6624984
OS 30.29656628 43.6441215
OS 30.2991012 43.64285404
OS 30.30100112 43.64095412
OS 30.30226858 43.6384192
OS 30.30923834 43.63144944
OS 30.31177326 43.63018198
OS 30.31367572 43.62827952
OS 30.31494064 43.6257446
OS 30.32191294 43.61877738
OS 30.32444786 43.61750992
OS 30.32634778 43.61561
OS 30.32761524 43.61307508
OS 30.33331754 43.60737278
OS 30.33585246 43.60610532
OS 30.34218976 43.59976802
OS 30.34472468 43.59850056
OS 30.3510569 43.59596564
OS 30.35612674 43.59469818
OS 30.3630965 43.58899588
OS 30.36753388 43.58456104
OS 30.3700688 43.58329358
OS 30.37703856 43.57759128
OS 30.38020594 43.57442136
OS 30.38654324 43.57188644
OS 30.39858284 43.5674516
OS 30.40048276 43.56555168
OS 30.40301768 43.56428676
OS 30.41188736 43.56048438
OS 30.42075704 43.55921692
OS 30.4277268 43.557317
OS 30.4340641 43.55478208
OS 30.44990608 43.54780978
OS 30.46194568 43.54590986
OS 30.48032004 43.54020756
OS 30.4929921 43.5389401
OS 30.5278409 43.53703764
OS 30.57853422 43.53577272
OS 34.741485 43.53450526
OS 34.79090832 43.5332378
OS 34.81372006 43.53197034
OS 34.83843172 43.53006788
OS 34.84476648 43.52753296
OS 34.8536387 43.52500058
OS 34.86250838 43.52373312
OS 34.88215274 43.52183066
OS 34.8897575 43.5205632
OS 34.8948248 43.51929574
OS 34.9011621 43.51676082
OS 34.90812932 43.51359344
OS 34.918269 43.51105852
OS 34.92777368 43.5091586
OS 34.93411098 43.50662368
OS 34.9360109 43.50472122
OS 34.94995042 43.498389
OS 34.95818764 43.49521908
OS 34.9600901 43.49331916
OS 34.96262502 43.4920517
OS 34.976562 43.4857144
OS 34.98796914 43.47937964
OS 34.99050406 43.47684472
OS 34.99747382 43.47494226
OS 35.00380858 43.47240734
OS 35.00824596 43.46923996
OS 35.01331326 43.46417012
OS 35.01584818 43.46290266
OS 35.0183831 43.46036774
OS 35.02091802 43.45910028
OS 35.0240854 43.45466544
OS 35.0297877 43.44896314
OS 35.03232262 43.44769568
OS 35.03865738 43.44136092
OS 35.0411923 43.44009346
OS 35.0475296 43.43755854
OS 35.05259944 43.43629108
OS 35.0595692 43.43058878
OS 35.06400404 43.42615394
OS 35.06653896 43.42488648
OS 35.07224126 43.41918418
OS 35.07350872 43.41664926
OS 35.07667864 43.41221442
OS 35.07921102 43.41094696
OS 35.08238094 43.40524212
OS 35.08681324 43.39320252
OS 35.093783 43.38623276
OS 35.09505046 43.38370038
OS 35.10328768 43.37546316
OS 35.1058226 43.3741957
OS 35.11089244 43.36659348
OS 35.1178622 43.35962118
OS 35.12356704 43.34378174
OS 35.12673442 43.34061182
OS 35.12800188 43.3380769
OS 35.13307172 43.3266723
OS 35.1356041 43.32033754
OS 35.1419414 43.31146786
OS 35.14320632 43.30639802
OS 35.14574124 43.30006072
OS 35.15461346 43.28105136
OS 35.15714838 43.263312
OS 35.1590483 43.25253986
OS 35.16348314 43.23796534
OS 35.1647506 43.22909312
OS 35.16665306 43.20564892
OS 35.16792052 43.17270004
OS 35.16855298 43.1340514
OS 35.16728552 43.13024902
OS 35.16601806 43.08716046
OS 35.1647506 43.08336062
OS 35.16348314 43.0630838
OS 35.16094822 43.0567465
OS 35.1584133 43.04787428
OS 35.15588092 43.03013238
OS 35.15397846 43.02063024
OS 35.15144354 43.01429294
OS 35.14954362 43.01239302
OS 35.14447378 42.99972096
OS 35.14130894 42.99148374
OS 35.13940648 42.98958128
OS 35.13813902 42.98704636
OS 35.1356041 42.98451144
OS 35.12926934 42.968037
OS 35.12166458 42.96043478
OS 35.12039712 42.95789986
OS 35.11469482 42.9509301
OS 35.1127949 42.94903018
OS 35.11152744 42.94649526
OS 35.10772506 42.93762304
OS 35.10265522 42.92875336
OS 35.09631792 42.92241606
OS 35.09505046 42.91988114
OS 35.07541118 42.90024186
OS 35.07350872 42.89960686
OS 35.07224126 42.89707194
OS 35.06400404 42.88883472
OS 35.06210412 42.88820226
OS 35.06083666 42.88566734
OS 35.03992484 42.86475552
OS 35.03738992 42.86348806
OS 35.03422254 42.85905322
OS 35.02852024 42.85335092
OS 35.02598532 42.85208346
OS 35.0183831 42.84448124
OS 35.01204834 42.84194632
OS 35.00380858 42.83877894
OS 34.99620636 42.8337091
OS 34.9892366 42.83054172
OS 34.98099684 42.8273718
OS 34.97402708 42.82293696
OS 34.96262502 42.81786712
OS 34.94868296 42.8102649
OS 34.93474344 42.8039276
OS 34.91573408 42.79505538
OS 34.89799472 42.79252046
OS 34.88722258 42.79062054
OS 34.87264806 42.7861857
OS 34.86757822 42.78491824
OS 34.83399688 42.78301832
OS 34.78203864 42.78175086
OS 32.13219634 42.7804834
OS 32.13156134 42.77985094
OS 32.12775896 42.7811184
OS 32.10748214 42.77985094
OS 32.0441193 42.77858348
OS 32.04031692 42.77731602
OS 32.01117296 42.77604856
OS 32.00737058 42.7747811
OS 32.00103328 42.77224618
OS 31.99216106 42.76971126
OS 31.979489 42.76844634
OS 31.97441916 42.76717888
OS 31.96428456 42.76591142
OS 31.94780758 42.75830666
OS 31.94274028 42.7570392
OS 31.93196814 42.75513928
OS 31.92373092 42.75196936
OS 31.90978886 42.7456346
OS 31.90472156 42.74436714
OS 31.89458442 42.74309968
OS 31.88317728 42.73676238
OS 31.8743076 42.73296
OS 31.86607038 42.72979262
OS 31.85846562 42.72345786
OS 31.8565657 42.72155794
OS 31.85403078 42.72029048
OS 31.85149586 42.71775556
OS 31.8495934 42.71712056
OS 31.84832594 42.71458564
OS 31.84009126 42.70634842
OS 31.83755634 42.70508096
OS 31.83122158 42.6987462
OS 31.82488428 42.69621128
OS 31.81664706 42.69304136
OS 31.81221222 42.68987398
OS 31.80587492 42.68353668
OS 31.80334 42.68226922
OS 31.79637024 42.67529946
OS 31.79510278 42.67276454
OS 31.79066794 42.66959716
OS 31.78623056 42.66516232
OS 31.7849631 42.66262994
OS 31.78116326 42.65882756
OS 31.7805308 42.65692764
OS 31.77863088 42.65629264
OS 31.77736342 42.65375772
OS 31.7748285 42.64742042
OS 31.77165858 42.6391832
OS 31.76342136 42.63094598
OS 31.7621539 42.62841106
OS 31.7564516 42.6214413
OS 31.75328422 42.61827392
OS 31.7507493 42.61193662
OS 31.74758192 42.60370194
OS 31.74251208 42.59609718
OS 31.73680978 42.58279012
OS 31.73173994 42.57392044
OS 31.72413772 42.557446
OS 31.71780042 42.54350648
OS 31.71653296 42.53843664
OS 31.71463304 42.5225972
OS 31.71209812 42.49725054
OS 31.71083066 42.48964578
OS 31.7095632 42.48331102
OS 31.70829574 42.47824372
OS 31.70639582 42.47127142
OS 31.70512836 42.46620412
OS 31.70259344 42.4509946
OS 31.70132598 42.43832254
OS 31.70259344 42.42945032
OS 31.70449336 42.41741326
OS 31.70576082 42.4110785
OS 31.70702828 42.40600866
OS 31.7101982 42.39523652
OS 31.71146566 42.39016668
OS 31.71273312 42.38129446
OS 31.71399804 42.3686224
OS 31.7159005 42.35658534
OS 31.71716796 42.3515155
OS 31.72097034 42.34137836
OS 31.72413772 42.33314114
OS 31.72540264 42.3280713
OS 31.72730256 42.31729916
OS 31.72983748 42.31096186
OS 31.73173994 42.30906194
OS 31.73554232 42.30019226
OS 31.7387097 42.29195504
OS 31.74060962 42.2875202
OS 31.74694692 42.2811829
OS 31.74821438 42.27864798
OS 31.7507493 42.27611306
OS 31.75455168 42.26977576
OS 31.7564516 42.26787584
OS 31.75835406 42.26724338
OS 31.75961898 42.26470846
OS 31.7621539 42.25837116
OS 31.76532382 42.25013394
OS 31.77229358 42.24316672
OS 31.77356104 42.2406318
OS 31.78876548 42.22542228
OS 31.78940048 42.22352236
OS 31.7919354 42.2222549
OS 31.81284468 42.20134562
OS 31.81347968 42.19944316
OS 31.81601206 42.1981757
OS 31.83122158 42.18297126
OS 31.8337565 42.1817038
OS 31.84009126 42.1753665
OS 31.85403078 42.17029666
OS 31.861633 42.16269444
OS 31.86416792 42.16142698
OS 31.87557506 42.15255476
OS 31.88697966 42.14748746
OS 31.8983868 42.14115016
OS 31.90092172 42.13861524
OS 31.90598648 42.13734778
OS 31.91232378 42.13481286
OS 31.93386806 42.12467572
OS 31.9452752 42.1234108
OS 31.95160996 42.12087588
OS 31.96428456 42.1170735
OS 31.96935186 42.11580604
OS 32.0099055 42.11453858
OS 32.01370534 42.11327112
OS 32.0561589 42.11263866
OS 32.05932628 42.11327112
OS 32.06312866 42.11200366
OS 33.01357634 42.1107362
OS 33.01737618 42.10946874
OS 33.0553949 42.10820128
OS 33.05919474 42.10693382
OS 33.06616704 42.1050339
OS 33.07440426 42.10186652
OS 33.09214616 42.0993316
OS 33.1022833 42.09806414
OS 33.10861806 42.09552922
OS 33.12256012 42.08919192
OS 33.1314298 42.08792446
OS 33.13966702 42.08602454
OS 33.14600432 42.08348962
OS 33.14790424 42.08158716
OS 33.15043916 42.08032224
OS 33.1618463 42.0752524
OS 33.17008098 42.07208248
OS 33.1719809 42.07018256
OS 33.17451582 42.0689151
OS 33.18085312 42.06511526
OS 33.18909034 42.06194788
OS 33.19542764 42.05941296
OS 33.19859502 42.05624558
OS 33.20112994 42.05497812
OS 33.21000216 42.05117574
OS 33.21633692 42.04864082
OS 33.22330922 42.04293852
OS 33.22647406 42.0397686
OS 33.22900898 42.03850114
OS 33.23471128 42.03279884
OS 33.23597874 42.03026392
OS 33.23914612 42.02709654
OS 33.24168104 42.02582908
OS 33.2486508 42.02012678
OS 33.25182072 42.01695686
OS 33.26576024 42.01188956
OS 33.28160222 41.99605012
OS 33.28350214 41.98908036
OS 33.28603452 41.98274306
OS 33.29300428 41.9757733
OS 33.29427174 41.97323838
OS 33.29997658 41.96626862
OS 33.3025115 41.96500116
OS 33.30948126 41.9580314
OS 33.31011372 41.95612894
OS 33.31264864 41.95486148
OS 33.3196184 41.94789172
OS 33.32088586 41.9453568
OS 33.32849062 41.93775458
OS 33.33102554 41.93141982
OS 33.33419292 41.9231826
OS 33.3373603 41.91874522
OS 33.3436976 41.91241046
OS 33.34749744 41.90607316
OS 33.35319974 41.8991034
OS 33.3551022 41.89339856
OS 33.35636966 41.88453142
OS 33.35763712 41.87692666
OS 33.36397188 41.86805698
OS 33.3671418 41.85981722
OS 33.37094164 41.84968008
OS 33.37347656 41.84334278
OS 33.37537902 41.83764048
OS 33.37664648 41.83257064
OS 33.3785464 41.79772184
OS 33.38044632 41.7223194
OS 33.3791814 41.71851702
OS 33.3785464 41.68493568
OS 33.3791814 41.67289608
OS 33.37791394 41.66909624
OS 33.37601148 41.63424744
OS 33.37474402 41.62791014
OS 33.3722091 41.62157284
OS 33.36904172 41.6108007
OS 33.36777426 41.60573086
OS 33.3665068 41.59686118
OS 33.36143696 41.58798896
OS 33.35636966 41.5765869
OS 33.3487649 41.56264484
OS 33.3436976 41.55124024
OS 33.33609284 41.53729818
OS 33.332293 41.5284285
OS 33.3259557 41.5170239
OS 33.3196184 41.51068914
OS 33.31835094 41.50815422
OS 33.31138118 41.50118446
OS 33.30884626 41.499917
OS 33.30567888 41.49547962
OS 33.30124404 41.49104478
OS 33.29870912 41.48977732
OS 33.2955392 41.48660994
OS 33.29427174 41.48407502
OS 33.28856944 41.47837272
OS 33.28603452 41.47710526
OS 33.2841346 41.4752028
OS 33.28286968 41.47266788
OS 33.27589992 41.46569812
OS 33.273365 41.4644332
OS 33.27146254 41.46253328
OS 33.27019508 41.45999836
OS 33.25182072 41.44162146
OS 33.2492858 41.440354
OS 33.24738334 41.43845408
OS 33.24611842 41.43591916
OS 33.24041358 41.43021686
OS 33.23787866 41.4289494
OS 33.23027644 41.42134464
OS 33.22394168 41.41880972
OS 33.21570446 41.41564234
OS 33.21126962 41.41247496
OS 33.21000216 41.40994004
OS 33.20746724 41.40867258
OS 33.1960601 41.3998029
OS 33.19225772 41.39600052
OS 33.17641828 41.39029822
OS 33.17451582 41.3883983
OS 33.16311376 41.38332846
OS 33.15804392 41.382061
OS 33.14600432 41.38016108
OS 33.12762742 41.37065386
OS 33.11495536 41.36558656
OS 33.10355076 41.36051672
OS 33.08771132 41.3586168
OS 33.07376926 41.35734934
OS 33.06236466 41.35608188
OS 33.04589022 41.35354696
OS 33.04082292 41.3522795
OS 33.03512062 41.35037704
OS 33.02244602 41.34910958
OS 32.97429016 41.3465772
OS 32.92803422 41.3459422
OS 32.92613176 41.3465772
OS 32.92233446 41.34531228
OS 31.37183718 41.34467728
OS 31.3686698 41.34531228
OS 31.36486996 41.34404482
OS 31.3091068 41.34277736
OS 31.30530442 41.3415099
OS 31.27996284 41.34024244
OS 31.2685557 41.3351726
OS 31.2622184 41.33263768
OS 31.2508138 41.32630038
OS 31.2394092 41.32123308
OS 31.22546968 41.31362832
OS 31.21406508 41.30855848
OS 31.20012302 41.30095626
OS 31.19125334 41.29715388
OS 31.17984874 41.29081658
OS 31.1747789 41.28574674
OS 31.17224398 41.28448182
OS 31.16780914 41.28131444
OS 31.16654168 41.27877952
OS 31.15957192 41.27180976
OS 31.157037 41.2705423
OS 31.14943224 41.26293754
OS 31.14309748 41.26040262
OS 31.13486026 41.25723524
OS 31.12409066 41.2464631
OS 31.1221882 41.24583064
OS 31.12092074 41.24329572
OS 31.11711836 41.2344235
OS 31.11205106 41.22555382
OS 31.10571376 41.21921906
OS 31.10191138 41.21288176
OS 31.09557408 41.20654446
OS 31.09050678 41.19260494
OS 31.0860694 41.18690264
OS 31.08416948 41.18626764
OS 31.08290202 41.18373272
OS 31.0740298 41.17232812
OS 31.07149488 41.1697932
OS 31.0689625 41.16345844
OS 31.06579258 41.15522122
OS 31.05882536 41.14191416
OS 31.0575579 41.13684432
OS 31.05629044 41.12797464
OS 31.0518556 41.11593504
OS 31.0461533 41.10263052
OS 31.04425084 41.08552108
OS 31.04298338 41.07791886
OS 31.04171592 41.07284902
OS 31.03791354 41.06270934
OS 31.03664608 41.05764204
OS 31.03538116 41.05003728
OS 31.03284624 41.01962332
OS 31.03221124 41.01518848
OS 31.0334787 41.0113861
OS 31.03538116 40.98414206
OS 31.03664608 40.9765373
OS 31.03791354 40.97146746
OS 31.04044846 40.9651327
OS 31.04235092 40.95816294
OS 31.04361838 40.9530931
OS 31.04488584 40.9404185
OS 31.0461533 40.9353512
OS 31.04741822 40.92647898
OS 31.05502298 40.91000708
OS 31.05945782 40.89036272
OS 31.06769504 40.87452074
OS 31.07086242 40.86628352
OS 31.0740298 40.86185122
OS 31.07656472 40.8593163
OS 31.07783218 40.85678138
OS 31.0803671 40.85424646
OS 31.08163456 40.85171154
OS 31.08416948 40.84917662
OS 31.08543694 40.84664424
OS 31.09177424 40.84030694
OS 31.09367416 40.83333718
OS 31.09620908 40.82699988
OS 31.10317884 40.82003012
OS 31.1044463 40.8174952
OS 31.10698122 40.81496028
OS 31.10824868 40.81242536
OS 31.11268352 40.80925798
OS 31.11965328 40.80229076
OS 31.12028828 40.8003883
OS 31.1228232 40.79912084
OS 31.14372994 40.77821156
OS 31.1449974 40.77567664
OS 31.14943224 40.77250672
OS 31.15640454 40.76553696
OS 31.157037 40.76363704
OS 31.15957192 40.76236958
OS 31.16780914 40.75413236
OS 31.16844414 40.7522299
OS 31.17097652 40.75096244
OS 31.1747789 40.7471626
OS 31.17731382 40.74589514
OS 31.18365112 40.73956038
OS 31.19949056 40.73385808
OS 31.20139048 40.73195562
OS 31.2039254 40.73068816
OS 31.20646032 40.72815324
OS 31.21153016 40.72688578
OS 31.22039984 40.72308594
OS 31.23307444 40.71548118
OS 31.2394092 40.71294626
OS 31.24764642 40.70977888
OS 31.26095094 40.70280912
OS 31.26602078 40.70154166
OS 31.27679292 40.6996392
OS 31.2869326 40.69583682
OS 31.30150712 40.69140198
OS 31.31037426 40.69013452
OS 31.33825584 40.68886706
OS 31.34205822 40.6875996
OS 31.36043258 40.68570222
OS 31.3680348 40.68443476
OS 31.37817448 40.68189984
OS 31.392114 40.68063238
OS 31.44850708 40.677465
OS 31.56763054 40.67619754
OS 32.4851268 40.67493008
OS 32.48892918 40.67366262
OS 32.52314552 40.67239516
OS 32.52948028 40.66986024
OS 32.5383525 40.66605786
OS 32.54722218 40.6647904
OS 32.55229202 40.66352294
OS 32.55926178 40.66162302
OS 32.57383376 40.65465326
OS 32.58270598 40.65211834
OS 32.59284312 40.65085088
OS 32.60171534 40.64578104
OS 32.61565486 40.63944374
OS 32.62199216 40.63691136
OS 32.63086184 40.63057406
OS 32.64290144 40.62613922
OS 32.6492362 40.62233938
OS 32.65050366 40.61980446
OS 32.6562085 40.61536708
OS 32.65874088 40.61409962
OS 32.66317826 40.60966478
OS 32.66444572 40.60712986
OS 32.6676131 40.60396248
OS 32.67014802 40.60269502
OS 32.67711778 40.59699272
OS 32.68155262 40.59255534
OS 32.6910573 40.59065542
OS 32.69549214 40.5887555
OS 32.69739206 40.58685304
OS 32.69865952 40.5817832
OS 32.70056198 40.57354598
OS 32.70372936 40.56911114
OS 32.71069912 40.56721122
OS 32.71703642 40.5659463
OS 32.72147126 40.56277638
OS 32.72400618 40.5539067
OS 32.72527364 40.54883686
OS 32.7328784 40.5412321
OS 32.73414586 40.53869718
OS 32.73984816 40.53172742
OS 32.74681538 40.52602512
OS 32.75251768 40.5177879
OS 32.7550526 40.51652044
OS 32.75695506 40.51462052
OS 32.75948744 40.50828322
OS 32.7607549 40.50321592
OS 32.76582474 40.4943437
OS 32.76835966 40.49180878
OS 32.77089458 40.48547402
OS 32.77406196 40.4772368
OS 32.78039926 40.46709712
OS 32.78356664 40.46012736
OS 32.78800402 40.44808776
OS 32.78990394 40.44618784
OS 32.79497378 40.43478324
OS 32.79624124 40.42591102
OS 32.7975087 40.42084372
OS 32.80384346 40.40436674
OS 32.80510838 40.39929944
OS 32.80701084 40.38219254
OS 32.8082783 40.37205286
OS 32.80954576 40.35431096
OS 32.81081322 40.33910398
OS 32.81208068 40.33276668
OS 32.81588052 40.32263208
OS 32.81841544 40.31629478
OS 32.8203179 40.30932502
OS 32.81905044 40.29538296
OS 32.8139806 40.28397836
OS 32.81017822 40.26877138
OS 32.8082783 40.23898988
OS 32.80574338 40.21871306
OS 32.80447592 40.20730846
OS 32.7975087 40.19020156
OS 32.79624124 40.18132934
OS 32.79497378 40.17626204
OS 32.79180386 40.16802482
OS 32.7848341 40.15218284
OS 32.78293418 40.14014578
OS 32.78039926 40.13380848
OS 32.77469696 40.1243038
OS 32.76962712 40.11036428
OS 32.76392482 40.10339452
OS 32.7607549 40.1002246
OS 32.75948744 40.09768968
OS 32.75378514 40.09071992
OS 32.75061776 40.08755254
OS 32.74808284 40.08121778
OS 32.74491546 40.07298056
OS 32.73667824 40.06474334
OS 32.7328784 40.05840604
OS 32.73097594 40.05650612
OS 32.72844102 40.05523866
OS 32.72273872 40.04953382
OS 32.72147126 40.04700144
OS 32.71957134 40.04509898
OS 32.71703642 40.04383152
OS 32.7087992 40.0355943
OS 32.7081642 40.03369438
OS 32.70562928 40.03242692
OS 32.6961246 40.02292478
OS 32.69549214 40.02102232
OS 32.69295722 40.01975486
OS 32.68598746 40.0127851
OS 32.68472 40.01025018
OS 32.68282008 40.00835026
OS 32.68028516 40.0070828
OS 32.67458286 40.0013805
OS 32.6733154 39.99884558
OS 32.67014802 39.99567566
OS 32.6676131 39.9944082
OS 32.6619108 39.9887059
OS 32.66064334 39.98617098
OS 32.65747596 39.9830036
OS 32.65494104 39.98173614
OS 32.64796874 39.97603384
OS 32.64480136 39.97286392
OS 32.63276176 39.96842908
OS 32.62832692 39.96652916
OS 32.625792 39.96399678
OS 32.62325962 39.96272932
OS 32.6143874 39.95892694
OS 32.60805264 39.95639202
OS 32.59918042 39.95132218
OS 32.59031074 39.94752234
OS 32.58143852 39.94625488
OS 32.57446876 39.94435242
OS 32.56813146 39.9418175
OS 32.5624317 39.93991758
OS 32.55736186 39.93865012
OS 32.54088742 39.93738266
OS 32.50160378 39.9361152
OS 32.46991982 39.93484774
OS 28.73213202 39.93421528
OS 28.72642972 39.93484774
OS 28.72262988 39.93358028
OS 28.70171806 39.93421528
OS 28.67954132 39.93358028
OS 28.6770064 39.93484774
OS 28.67320402 39.93358028
OS 28.6237807 39.9297779
OS 28.61617594 39.92851044
OS 28.60857372 39.92344314
OS 28.60604134 39.92217568
OS 28.59907158 39.91647084
OS 28.59146682 39.89999894
OS 28.5895669 39.87021744
OS 28.58829944 39.85247554
OS 28.58766444 39.83283372
OS 28.5889319 39.8302988
OS 28.58766444 39.82649642
OS 28.58703198 39.76503604
OS 28.58766444 39.5134846
OS 28.58639698 39.50968222
OS 28.58512952 39.40323336
OS 28.58386206 39.39943098
OS 28.5825946 39.36774702
OS 28.57625984 39.35381004
OS 28.57308992 39.34557282
OS 28.57055754 39.34050298
OS 28.56802262 39.33923552
OS 28.56105032 39.33226576
OS 28.5597854 39.32973084
OS 28.5528131 39.32656092
OS 28.54077604 39.32212608
OS 28.53380628 39.3189587
OS 28.5249366 39.31769124
OS 28.49008526 39.31578878
OS 28.43812702 39.31452386
OS 27.58082622 39.31388886
OS 27.57702384 39.31515632
OS 27.50859116 39.31642378
OS 27.50478878 39.31769124
OS 27.4832445 39.3189587
OS 27.46930498 39.325296
OS 27.4610703 39.32846338
OS 27.45410054 39.33543314
OS 27.45156562 39.3367006
OS 27.44459586 39.3424029
OS 27.43952602 39.35000766
OS 27.43825856 39.35254258
OS 27.43445618 39.36141226
OS 27.43382372 39.38105408
OS 27.43445618 39.39055876
OS 27.43318872 39.39436114
OS 27.43192126 39.39943098
OS 27.43255626 39.4190728
OS 27.4306538 39.43237732
OS 27.43192126 39.4361797
OS 27.4312888 39.45835898
OS 27.43192126 39.47419842
OS 27.4306538 39.4780008
OS 27.43192126 39.49700762
OS 27.4306538 39.50081
OS 27.42938634 39.6427452
OS 27.42811888 39.64654758
OS 27.42685142 39.6832963
OS 27.42178412 39.6947009
OS 27.4192492 39.7010382
OS 27.41798174 39.70610804
OS 27.41164444 39.71497772
OS 27.4021423 39.72448494
OS 27.39707246 39.72574986
OS 27.39390508 39.72638486
OS 27.38883524 39.7251174
OS 27.38123302 39.7187801
OS 27.37362826 39.71117788
OS 27.37109334 39.70484058
OS 27.3666585 39.69280098
OS 27.36348858 39.68456376
OS 27.36222112 39.67949392
OS 27.36095366 39.64021028
OS 27.35968874 39.6364079
OS 27.35842128 39.5362938
OS 27.35778628 39.4368147
OS 27.35842128 39.42604256
OS 27.35715382 39.42224272
OS 27.35778628 39.4013309
OS 27.35651882 39.3949936
OS 27.35525136 39.37471678
OS 27.3539839 39.35824488
OS 27.34448176 39.3424029
OS 27.34004692 39.33796806
OS 27.337512 39.3367006
OS 27.32990724 39.32909584
OS 27.32357248 39.32656092
OS 27.31153288 39.32212608
OS 27.30456058 39.3189587
OS 27.29949328 39.31769124
OS 27.25957464 39.31578878
OS 27.20888386 39.31452386
OS 26.86355562 39.31388886
OS 26.85975324 39.31515632
OS 26.79005564 39.31642378
OS 26.78625326 39.31769124
OS 26.76597644 39.3189587
OS 26.7545693 39.32402854
OS 26.74633462 39.32719592
OS 26.73936486 39.33163076
OS 26.73429502 39.3367006
OS 26.7317601 39.33796806
OS 26.72479034 39.34493782
OS 26.72352288 39.34747274
OS 26.71845304 39.3550775
OS 26.71718558 39.3601448
OS 26.71528566 39.39372614
OS 26.7140182 39.40006344
OS 26.71338574 39.40956812
OS 26.7146532 39.4133705
OS 26.71338574 39.4361797
OS 26.7146532 39.43998208
OS 26.71338574 39.4602589
OS 26.71275074 39.77263826
OS 26.71338574 39.78721024
OS 26.71211828 39.79101262
OS 26.71338574 39.8125569
OS 26.71211828 39.81635928
OS 26.71085082 39.8252315
OS 26.70894836 39.86134522
OS 26.7076809 39.86894998
OS 26.70451352 39.87591974
OS 26.69881122 39.89176172
OS 26.69690876 39.89366164
OS 26.6956413 39.89619656
OS 26.68930654 39.90253386
OS 26.68803908 39.90506878
OS 26.68233678 39.91076854
OS 26.67600202 39.91457092
OS 26.67219964 39.9183733
OS 26.66586234 39.92090822
OS 26.64748798 39.9240756
OS 26.6430506 39.92724298
OS 26.631646 39.93231282
OS 26.6202414 39.93104536
OS 26.61137172 39.9247106
OS 26.60503442 39.92217568
OS 26.5967972 39.91900576
OS 26.5910949 39.91330346
OS 26.58855998 39.912036
OS 26.58602506 39.90950108
OS 26.58349014 39.90823362
OS 26.5790553 39.90380132
OS 26.57778784 39.9012664
OS 26.57461792 39.89809902
OS 26.572083 39.89683156
OS 26.5676507 39.89239418
OS 26.56258086 39.8835245
OS 26.56004594 39.8771872
OS 26.55878102 39.87211736
OS 26.56004594 39.86705006
OS 26.55878102 39.85437546
OS 26.5562461 39.82269658
OS 26.55497864 39.8188942
OS 26.5562461 39.81002198
OS 26.5556111 39.7891127
OS 26.5562461 39.77454072
OS 26.55497864 39.77073834
OS 26.5556111 39.75489636
OS 26.55434364 39.67252416
OS 26.55371118 39.66808932
OS 26.55497864 39.66428948
OS 26.55371118 39.6478125
OS 26.55180872 39.59775672
OS 26.55054126 39.58761958
OS 26.54800888 39.58128228
OS 26.5435715 39.57051014
OS 26.54230404 39.5654403
OS 26.53660174 39.55847054
OS 26.53343436 39.55530316
OS 26.5321669 39.55276824
OS 26.5264646 39.54580102
OS 26.51505746 39.5369288
OS 26.49224826 39.52678912
OS 26.48210858 39.52425674
OS 26.44092502 39.52235428
OS 26.43649018 39.52172182
OS 26.4326878 39.52298928
OS 26.41621082 39.52172182
OS 26.28568276 39.52045436
OS 26.25400388 39.52172182
OS 26.21281524 39.52235428
OS 26.20711548 39.52172182
OS 26.2033131 39.52298928
OS 26.16212446 39.5248892
OS 26.15705716 39.52615666
OS 26.14375264 39.53185896
OS 26.13551542 39.53502888
OS 26.13361296 39.5369288
OS 26.13107804 39.53819626
OS 26.12474328 39.54453356
OS 26.12220836 39.54580102
OS 26.11650352 39.55150078
OS 26.1152386 39.5540357
OS 26.1089013 39.56037046
OS 26.10763384 39.56290538
OS 26.10383146 39.5717776
OS 26.10066408 39.58001482
OS 26.09749416 39.58698458
OS 26.0962267 39.59965918
OS 26.09369432 39.68456376
OS 26.09242686 39.80368722
OS 26.0911594 39.91647084
OS 26.08672456 39.92090822
OS 26.07848734 39.92280814
OS 26.0683502 39.92661052
OS 26.0613779 39.9297779
OS 26.02779656 39.93168036
OS 26.00751974 39.93294782
OS 25.93021738 39.93421528
OS 25.3922657 39.93484774
OS 25.38846332 39.93358028
OS 25.29468652 39.93231282
OS 25.29088414 39.93104536
OS 25.25983518 39.92914544
OS 25.25349788 39.92661052
OS 25.24653066 39.92344314
OS 25.23829344 39.92154068
OS 25.2338586 39.91964076
OS 25.23068868 39.91647084
OS 25.22942122 39.90760116
OS 25.22878876 39.54959832
OS 25.22942122 39.53376142
OS 25.22815376 39.52995904
OS 25.22942122 39.51094968
OS 25.22815376 39.5071473
OS 25.22878876 39.48623802
OS 25.2275213 39.48116818
OS 25.22625384 39.47356596
OS 25.22562138 39.46786366
OS 25.2268863 39.46532874
OS 25.22562138 39.46152636
OS 25.22435392 39.44124954
OS 25.21864908 39.43427978
OS 25.21358178 39.42920994
OS 25.20470956 39.42667502
OS 25.17239568 39.42477764
OS 25.16605838 39.42351018
OS 25.16035608 39.42287518
OS 25.1565537 39.42414264
OS 25.14831648 39.42477764
OS 25.13817934 39.42351018
OS 25.13627688 39.42287518
OS 25.1324745 39.42414264
OS 25.10903284 39.42351018
OS 25.0919234 39.42414264
OS 25.08812102 39.42287518
OS 25.07164658 39.42414264
OS 25.06784674 39.42287518
OS 24.51468808 39.42351018
OS 24.50391594 39.42287518
OS 24.50011356 39.42414264
OS 24.47920174 39.42351018
OS 24.45956246 39.42414264
OS 24.45702754 39.42287518
OS 24.45322516 39.42414264
OS 24.44498794 39.42477764
OS 24.43484826 39.42351018
OS 24.42914596 39.42287518
OS 24.42534358 39.42414264
OS 24.4164739 39.4254101
OS 24.3866924 39.42730748
OS 24.38035764 39.4298424
OS 24.37148542 39.43871462
OS 24.3689505 39.44505192
OS 24.36768304 39.48053572
OS 24.36641558 39.4843381
OS 24.36514812 39.4894054
OS 24.36641558 39.50587984
OS 24.36514812 39.5185519
OS 24.36641558 39.52742412
OS 24.36514812 39.54389856
OS 24.36641558 39.5540357
OS 24.36514812 39.55783808
OS 24.36514812 39.73398708
OS 24.36514812 39.73525454
OS 24.36578312 39.82079412
OS 24.36514812 39.83536864
OS 24.36641558 39.83917102
OS 24.36514812 39.8594453
OS 24.36641558 39.86324768
OS 24.36578312 39.88415696
OS 24.36705058 39.8892268
OS 24.36831804 39.8955641
OS 24.3695855 39.92724298
OS 24.37592026 39.93738266
OS 24.38035764 39.94435242
OS 24.38225756 39.94625488
OS 24.39112978 39.95132218
OS 24.39999946 39.95512456
OS 24.4221762 39.95575956
OS 24.42661104 39.95512456
OS 24.43041342 39.95639202
OS 24.4399181 39.95829448
OS 24.44942278 39.95892694
OS 24.45322516 39.95765948
OS 24.47603436 39.95892694
OS 24.47983674 39.95765948
OS 24.50011356 39.95892694
OS 24.50708332 39.95829448
OS 24.8923302 39.9595594
OS 24.89676504 39.96146186
OS 24.89866496 39.96336178
OS 24.89993242 39.96842908
OS 24.90119988 39.9773013
OS 24.89993242 40.51081814
OS 24.89549758 40.51652044
OS 24.8866279 40.5177879
OS 24.51722046 40.51842036
OS 24.50264848 40.5177879
OS 24.4988461 40.51905536
OS 24.47793428 40.51842036
OS 24.46209484 40.51905536
OS 24.458295 40.5177879
OS 24.44942278 40.51905536
OS 24.42851096 40.51842036
OS 24.4221762 40.51968782
OS 24.40063446 40.52095528
OS 24.38542494 40.52222274
OS 24.37845518 40.52665758
OS 24.37021796 40.53489734
OS 24.3689505 40.54376702
OS 24.36641558 40.58051828
OS 24.36514812 40.58431812
OS 24.36641558 40.60966478
OS 24.36514812 40.61346716
OS 24.36641558 40.63374144
OS 24.36768304 40.63754382
OS 24.3695855 40.66986024
OS 24.37275288 40.67429508
OS 24.3746528 40.677465
OS 24.37718772 40.67873246
OS 24.3809901 40.6825323
OS 24.3873274 40.68506722
OS 24.42090874 40.68696714
OS 24.42597858 40.6882346
OS 24.43675072 40.68886706
OS 24.44055056 40.6875996
OS 24.46272984 40.6882346
OS 24.4747669 40.6875996
OS 24.47856928 40.68886706
OS 24.49060888 40.6882346
OS 24.4925088 40.68886706
OS 24.49377626 40.6875996
OS 24.49757864 40.68886706
OS 24.89423012 40.69013452
OS 24.89866496 40.6933019
OS 24.90119988 40.70344158
OS 24.89993242 41.2407608
OS 24.89549758 41.2464631
OS 24.8866279 41.24773056
OS 24.50074602 41.24836302
OS 24.48870642 41.24773056
OS 24.48490404 41.24899802
OS 24.46526476 41.24836302
OS 24.45766 41.24963048
OS 24.45702754 41.25026548
OS 24.45322516 41.24899802
OS 24.44055056 41.24773056
OS 24.43675072 41.24899802
OS 24.42661104 41.25153294
OS 24.39492962 41.2528004
OS 24.39239724 41.25533532
OS 24.38986232 41.25660278
OS 24.37909018 41.26357254
OS 24.37782272 41.26610746
OS 24.37148542 41.27497714
OS 24.3689505 41.28131444
OS 24.36705058 41.31489578
OS 24.36578312 41.32250054
OS 24.36514812 41.33833998
OS 24.36641558 41.34214236
OS 24.36514812 41.36748648
OS 24.36641558 41.37128886
OS 24.36768304 41.3877633
OS 24.37021796 41.41437488
OS 24.3809901 41.42514702
OS 24.39112978 41.42768194
OS 24.39809954 41.42704694
OS 24.41964128 41.4283144
OS 24.42471112 41.42958186
OS 24.4392831 41.43021686
OS 24.44308548 41.4289494
OS 24.45956246 41.43021686
OS 24.89296266 41.43148432
OS 24.89866496 41.43591916
OS 24.89993242 41.440989
OS 24.90119988 41.44985868
OS 24.89993242 41.98337552
OS 24.8973975 41.98591044
OS 24.89676504 41.9878129
OS 24.88789536 41.99034782
OS 24.47920174 41.99098028
OS 24.4633623 41.99034782
OS 24.45956246 41.99161274
OS 24.43801818 41.99034782
OS 24.43168088 41.9928802
OS 24.39619708 41.99414766
OS 24.3873274 42.00048496
OS 24.3809901 42.00428734
OS 24.37782272 42.00745218
OS 24.37655526 42.0099871
OS 24.37021796 42.02012678
OS 24.3689505 42.02519662
OS 24.36705058 42.05117574
OS 24.36578312 42.0638478
OS 24.36514812 42.09109438
OS 24.36641558 42.09489422
OS 24.36768304 42.1278431
OS 24.3689505 42.13164548
OS 24.37021796 42.14431754
OS 24.37655526 42.1582596
OS 24.37845518 42.16649682
OS 24.38035764 42.16839674
OS 24.3809901 42.17029666
OS 24.3873274 42.17283158
OS 24.89549758 42.17409904
OS 24.89866496 42.17726896
OS 24.89993242 42.18233626
OS 24.90119988 42.19120594
OS 24.89993242 42.72472532
OS 24.89549758 42.73042508
OS 24.89042774 42.73169254
OS 24.4868065 42.73232754
OS 24.47856928 42.73169254
OS 24.4747669 42.73296
OS 24.45385762 42.73232754
OS 24.44752286 42.733595
OS 24.44308548 42.73422746
OS 24.4392831 42.73296
OS 24.43041342 42.73169254
OS 24.41520644 42.73549492
OS 24.38225756 42.73676238
OS 24.37021796 42.74880198
OS 24.3689505 42.7576742
OS 24.36768304 42.78935308
OS 24.36641558 42.79315546
OS 24.36514812 42.7982253
OS 24.36641558 42.81469974
OS 24.36514812 42.8273718
OS 24.36641558 42.83624402
OS 24.36514812 42.85271592
OS 24.36641558 42.86412306
OS 24.36514812 42.86792544
OS 24.36641558 44.88033696
OS 24.36768304 44.8841368
OS 24.3695855 44.9253229
OS 24.37085296 44.93039274
OS 24.3752878 44.94116488
OS 24.37782272 44.95003456
OS 24.3816251 44.95637186
OS 24.38859486 44.95827178
OS 31.31417664 44.95700432
OE
OB 27.74937046 44.47164334 H
OS 27.74557062 44.47037588
OS 27.71135174 44.46910842
OS 27.70754936 44.46784096
OS 27.6784054 44.4665735
OS 27.67460302 44.46530604
OS 27.66953318 44.46403858
OS 27.65305874 44.46277366
OS 27.6479889 44.4615062
OS 27.62074486 44.45960628
OS 27.61630748 44.45897128
OS 27.61250764 44.46023874
OS 27.6074378 44.45897128
OS 27.57385646 44.45707136
OS 27.55611456 44.4558039
OS 27.5485098 44.45453644
OS 27.5421725 44.45326898
OS 27.5371052 44.45200152
OS 27.5199983 44.4501016
OS 27.51492846 44.44883414
OS 27.48768188 44.44566676
OS 27.46993998 44.4443993
OS 27.46360522 44.44313184
OS 27.45853538 44.44186438
OS 27.45156562 44.43996192
OS 27.44649578 44.43869446
OS 27.41988166 44.43489462
OS 27.40340976 44.43362716
OS 27.39960738 44.4323597
OS 27.38756778 44.43045724
OS 27.38249794 44.42918978
OS 27.3717258 44.4260224
OS 27.35842128 44.42412248
OS 27.34131438 44.42222002
OS 27.3197701 44.4196851
OS 27.31280034 44.41778518
OS 27.29822582 44.41208288
OS 27.29315598 44.41081542
OS 27.27985146 44.4076455
OS 27.2728817 44.40447812
OS 27.2665444 44.40194574
OS 27.25830718 44.40004582
OS 27.25196988 44.39877836
OS 27.2367629 44.39624344
OS 27.23169306 44.39497598
OS 27.22155846 44.3911736
OS 27.21332124 44.38800622
OS 27.20064664 44.38673876
OS 27.19177696 44.3854713
OS 27.18670712 44.38420384
OS 27.1784699 44.38103392
OS 27.1721326 44.37850154
OS 27.16389792 44.37533162
OS 27.15882808 44.37406416
OS 27.1493234 44.37216424
OS 27.1429861 44.36962932
OS 27.13601634 44.36646194
OS 27.12967904 44.36392702
OS 27.12461174 44.36265956
OS 27.11130468 44.35948964
OS 27.10496992 44.35695726
OS 27.09166286 44.35125242
OS 27.08659302 44.34998496
OS 27.07708834 44.34808504
OS 27.06441628 44.34301774
OS 27.05744652 44.33985036
OS 27.0485743 44.33731544
OS 27.0378047 44.33541298
OS 27.02449764 44.32844322
OS 27.01562542 44.32464084
OS 26.99408114 44.3145037
OS 26.985214 44.31323624
OS 26.97824424 44.31133632
OS 26.95226258 44.29929672
OS 26.9433929 44.29422688
OS 26.92945084 44.28788958
OS 26.91804878 44.28155482
OS 26.90410672 44.27522006
OS 26.88256244 44.26508038
OS 26.87052538 44.26318046
OS 26.86419062 44.26064554
OS 26.85341848 44.25494324
OS 26.84708118 44.25240832
OS 26.80526262 44.23086404
OS 26.79258802 44.2257942
OS 26.78561826 44.22009444
OS 26.78245088 44.21692452
OS 26.77991596 44.21565706
OS 26.76470898 44.20551992
OS 26.75963914 44.20425246
OS 26.74760208 44.20235
OS 26.74063232 44.19791516
OS 26.73682994 44.19411278
OS 26.72795772 44.18904548
OS 26.72289042 44.18397564
OS 26.7203555 44.18270818
OS 26.70894836 44.17763834
OS 26.69754376 44.17130104
OS 26.68613916 44.16623374
OS 26.6798044 44.1624339
OS 26.67473456 44.15736406
OS 26.67219964 44.1560966
OS 26.66966472 44.15356168
OS 26.6671298 44.15229422
OS 26.66332742 44.14849184
OS 26.6607925 44.14722438
OS 26.65826012 44.144692
OS 26.65319028 44.14342454
OS 26.64178314 44.13708724
OS 26.63671584 44.1320174
OS 26.63418092 44.13074994
OS 26.63037854 44.12694756
OS 26.62784362 44.1256801
OS 26.62404378 44.12188026
OS 26.62150886 44.1206128
OS 26.61517156 44.11807788
OS 26.61010426 44.11681042
OS 26.6024995 44.10920566
OS 26.59996458 44.1079382
OS 26.58855998 44.09907106
OS 26.58602506 44.09653614
OS 26.57968776 44.09400122
OS 26.57461792 44.09273376
OS 26.5676507 44.08703146
OS 26.56448332 44.08386154
OS 26.5619484 44.08259408
OS 26.54547396 44.06611964
OS 26.54293904 44.06485218
OS 26.53913666 44.0610498
OS 26.53279936 44.05851488
OS 26.52456214 44.0553475
OS 26.52139476 44.05218012
OS 26.51885984 44.05091266
OS 26.51379 44.04584282
OS 26.51125508 44.04457536
OS 26.50745524 44.04077552
OS 26.50492032 44.03950806
OS 26.50112048 44.03570568
OS 26.48717842 44.03063838
OS 26.4795762 44.02303362
OS 26.47704128 44.02176616
OS 26.47007152 44.01606386
OS 26.46880406 44.01352894
OS 26.46309922 44.00782664
OS 26.4605643 44.00655918
OS 26.45739692 44.00212434
OS 26.45042716 43.99515204
OS 26.44789224 43.99388458
OS 26.44282494 43.98881728
OS 26.44029002 43.98754982
OS 26.43395526 43.9850149
OS 26.42571804 43.98184752
OS 26.41747828 43.9736103
OS 26.4149459 43.97234284
OS 26.41177598 43.97044292
OS 26.41050852 43.967908
OS 26.37249234 43.92988928
OS 26.37122488 43.92735436
OS 26.3680575 43.92418698
OS 26.36552258 43.92292206
OS 26.35855282 43.91721722
OS 26.3553829 43.91404984
OS 26.34144338 43.90898
OS 26.33637354 43.90391016
OS 26.33383862 43.9026427
OS 26.3313037 43.90011032
OS 26.32876878 43.89884286
OS 26.32433648 43.89440548
OS 26.32306902 43.89187056
OS 26.31863418 43.88743572
OS 26.31609926 43.88616826
OS 26.31166442 43.88173342
OS 26.31039696 43.8791985
OS 26.30722704 43.87603112
OS 26.30469212 43.87476366
OS 26.29898982 43.86906136
OS 26.29772236 43.86652644
OS 26.29455498 43.86335906
OS 26.29202006 43.8620916
OS 26.28758522 43.85765676
OS 26.28631776 43.85512184
OS 26.28314784 43.85195446
OS 26.28061546 43.850687
OS 26.27491062 43.8449847
OS 26.27364316 43.84244978
OS 26.27047578 43.83927986
OS 26.26794086 43.8380124
OS 26.26350856 43.83357756
OS 26.2622411 43.83104264
OS 26.25907372 43.82787526
OS 26.2565388 43.8266078
OS 26.25083396 43.8209055
OS 26.2495665 43.81837058
OS 26.24639912 43.81520066
OS 26.2438642 43.81393574
OS 26.2381619 43.8082309
OS 26.23689444 43.80569598
OS 26.23435952 43.8031636
OS 26.23309206 43.80063122
OS 26.22928968 43.79682884
OS 26.22485484 43.78478924
OS 26.22168746 43.78035186
OS 26.21661762 43.77528456
OS 26.21535016 43.77274964
OS 26.21218278 43.7683148
OS 26.20964786 43.76704734
OS 26.20014572 43.75754266
OS 26.19951072 43.7556402
OS 26.1969758 43.75437274
OS 26.17479906 43.73219854
OS 26.1735316 43.72966362
OS 26.17099668 43.72332632
OS 26.17416406 43.71889148
OS 26.18303628 43.71762402
OS 26.19317342 43.71889148
OS 26.20014572 43.72459378
OS 26.20204564 43.7264937
OS 26.21091532 43.73156354
OS 26.2140827 43.73473346
OS 26.21535016 43.73726584
OS 26.22105246 43.74297068
OS 26.22358738 43.74423814
OS 26.2267573 43.74740298
OS 26.22802222 43.7499379
OS 26.23372706 43.75690766
OS 26.23689444 43.76007504
OS 26.23879436 43.76704734
OS 26.24132928 43.7733821
OS 26.24830158 43.78035186
OS 26.2495665 43.78288678
OS 26.25527134 43.78985908
OS 26.25780626 43.791124
OS 26.26477602 43.7980963
OS 26.26604348 43.80063122
OS 26.27047578 43.8037986
OS 26.27744554 43.81076582
OS 26.27808054 43.81266828
OS 26.28061546 43.81393574
OS 26.28885268 43.82217296
OS 26.29012014 43.82470788
OS 26.29202006 43.8266078
OS 26.29455498 43.82787526
OS 26.30025728 43.83357756
OS 26.30152474 43.83611248
OS 26.3034272 43.8380124
OS 26.30595958 43.83927986
OS 26.31293188 43.84625216
OS 26.31419934 43.84878454
OS 26.31609926 43.850687
OS 26.31863418 43.85195446
OS 26.32560394 43.85892422
OS 26.3262364 43.86082414
OS 26.32876878 43.8620916
OS 26.33827346 43.87159374
OS 26.33890846 43.8734962
OS 26.34144338 43.87476366
OS 26.3496806 43.88300088
OS 26.35094806 43.8855358
OS 26.35284798 43.88743572
OS 26.3553829 43.88870318
OS 26.35791782 43.8912381
OS 26.36045274 43.89250556
OS 26.36552258 43.8975754
OS 26.37185734 43.90011032
OS 26.3800971 43.9032777
OS 26.3857994 43.90898
OS 26.38833178 43.91024746
OS 26.3908667 43.91278238
OS 26.39340162 43.91404984
OS 26.396569 43.91721722
OS 26.39783646 43.91975214
OS 26.4022713 43.92418698
OS 26.40480622 43.92545444
OS 26.40924106 43.92988928
OS 26.41050852 43.9324242
OS 26.4149459 43.93685904
OS 26.41747828 43.9381265
OS 26.4206482 43.94129388
OS 26.42191566 43.9438288
OS 26.42761796 43.9495311
OS 26.43015288 43.95079856
OS 26.43332026 43.95396848
OS 26.43458772 43.9565034
OS 26.44029002 43.9622057
OS 26.44219248 43.96283816
OS 26.44282494 43.96474062
OS 26.4447274 43.96537308
OS 26.44599486 43.967908
OS 26.45296208 43.97487776
OS 26.455497 43.97614522
OS 26.4605643 43.98121506
OS 26.46309922 43.98248252
OS 26.47577382 43.98754982
OS 26.48274358 43.99325212
OS 26.48591096 43.9964195
OS 26.48844588 43.99768696
OS 26.51759238 44.026836
OS 26.5201273 44.02810346
OS 26.52266222 44.03063838
OS 26.52519714 44.03190584
OS 26.5315319 44.03444076
OS 26.54040412 44.03950806
OS 26.54293904 44.04204298
OS 26.54547396 44.04331044
OS 26.5492738 44.04711028
OS 26.55180872 44.04837774
OS 26.5556111 44.05218012
OS 26.55814602 44.05344758
OS 26.56068094 44.0559825
OS 26.56701824 44.05851488
OS 26.572083 44.05978234
OS 26.5790553 44.06548718
OS 26.58222268 44.06865456
OS 26.5847576 44.06992202
OS 26.58729252 44.07245694
OS 26.58982744 44.0737244
OS 26.59489474 44.07879424
OS 26.59742966 44.08005916
OS 26.61010426 44.085129
OS 26.61263918 44.08766392
OS 26.61517156 44.08893138
OS 26.6202414 44.09400122
OS 26.62277632 44.09526868
OS 26.62974354 44.10223844
OS 26.631011 44.10477082
OS 26.63418092 44.1079382
OS 26.63671584 44.10920566
OS 26.64051568 44.11300804
OS 26.6430506 44.1142755
OS 26.64558552 44.11681042
OS 26.65192282 44.11934534
OS 26.66016004 44.12251272
OS 26.6677648 44.12758256
OS 26.67473456 44.13074994
OS 26.68297178 44.13391986
OS 26.690574 44.14025462
OS 26.69374138 44.14342454
OS 26.6962763 44.144692
OS 26.70324606 44.1503943
OS 26.70514598 44.15229422
OS 26.7140182 44.1560966
OS 26.73049264 44.16496628
OS 26.73936486 44.16876866
OS 26.74570216 44.17130104
OS 26.7545693 44.17763834
OS 26.7609066 44.18017326
OS 26.76597644 44.18144072
OS 26.77484612 44.18651056
OS 26.78878818 44.19284532
OS 26.79512294 44.1966477
OS 26.80019278 44.20171754
OS 26.8027277 44.202985
OS 26.80526262 44.20551992
OS 26.807795 44.20678738
OS 26.81286484 44.21185722
OS 26.81539976 44.21312214
OS 26.82680436 44.21819198
OS 26.83567658 44.22326182
OS 26.85215102 44.23086404
OS 26.87115784 44.23973372
OS 26.87622768 44.24100118
OS 26.88573236 44.24290364
OS 26.89206966 44.24543856
OS 26.90030688 44.2498734
OS 26.91297894 44.25494324
OS 26.91551386 44.2562107
OS 26.925651 44.26254546
OS 26.93198576 44.26508038
OS 26.99408114 44.29549434
OS 27.00041844 44.29929672
OS 27.00548828 44.30056418
OS 27.0143605 44.30183164
OS 27.0194278 44.30309656
OS 27.03590478 44.31070132
OS 27.04477446 44.31323624
OS 27.05807898 44.31640362
OS 27.0720185 44.32274092
OS 27.08279064 44.3259083
OS 27.09229786 44.32781076
OS 27.09863262 44.33034568
OS 27.11193714 44.33604798
OS 27.12207682 44.3385829
OS 27.13031404 44.34048282
OS 27.14425356 44.34681758
OS 27.1550257 44.34998496
OS 27.16833022 44.35315488
OS 27.17529998 44.35632226
OS 27.1841722 44.36012464
OS 27.19430934 44.36265956
OS 27.2025491 44.36455948
OS 27.20888386 44.3670944
OS 27.21712108 44.37026178
OS 27.22726076 44.3727967
OS 27.24183274 44.37469916
OS 27.26591194 44.37850154
OS 27.27604908 44.38230138
OS 27.28301884 44.38420384
OS 27.29315598 44.38673876
OS 27.30899796 44.38863868
OS 27.3140678 44.38990614
OS 27.32040256 44.39244106
OS 27.32863978 44.39560844
OS 27.33877946 44.39814336
OS 27.35651882 44.40067828
OS 27.36158866 44.40194574
OS 27.37362826 44.40637804
OS 27.37996556 44.4076455
OS 27.39137016 44.40891296
OS 27.39770746 44.41018042
OS 27.40784206 44.41144788
OS 27.42051666 44.41271534
OS 27.43572364 44.41525026
OS 27.44206094 44.41651772
OS 27.45283308 44.4196851
OS 27.4775422 44.42158756
OS 27.49781902 44.42412248
OS 27.51556092 44.4253874
OS 27.53266782 44.42728986
OS 27.5428075 44.42982478
OS 27.55547956 44.43109224
OS 27.571954 44.4323597
OS 27.63531938 44.43489462
OS 27.69931468 44.43552708
OS 27.83301012 44.43489462
OS 27.8368125 44.43615954
OS 27.9065101 44.43489462
OS 27.95783588 44.43299216
OS 27.98064762 44.4317247
OS 27.99838952 44.43045724
OS 28.00472428 44.42918978
OS 28.01486142 44.42665486
OS 28.04907776 44.42285502
OS 28.06935458 44.4203201
OS 28.0832941 44.41905264
OS 28.0889964 44.41715018
OS 28.09786862 44.41461526
OS 28.10800576 44.41208288
OS 28.12701258 44.41081542
OS 28.13081496 44.40954796
OS 28.13841972 44.4082805
OS 28.1422221 44.40701304
OS 28.15616162 44.4032132
OS 28.16503384 44.40067828
OS 28.18150828 44.39941082
OS 28.19037796 44.39814336
OS 28.19861518 44.39624344
OS 28.20368502 44.39497598
OS 28.21382216 44.3911736
OS 28.22079192 44.38927368
OS 28.22586176 44.38800622
OS 28.24170374 44.38610376
OS 28.25183834 44.38356884
OS 28.25817564 44.38103392
OS 28.26894778 44.37786654
OS 28.27401762 44.37659908
OS 28.2898596 44.37469916
OS 28.29746182 44.3734317
OS 28.30759896 44.37216424
OS 28.3126688 44.37089678
OS 28.32280594 44.3670944
OS 28.33104316 44.36392702
OS 28.336113 44.36265956
OS 28.34561768 44.3607571
OS 28.35195498 44.35822472
OS 28.36526204 44.35251988
OS 28.37032934 44.35125242
OS 28.37983402 44.3493525
OS 28.38997116 44.34555012
OS 28.40327822 44.33985036
OS 28.40834806 44.3385829
OS 28.41785274 44.33668044
OS 28.42419004 44.33414806
OS 28.4412944 44.32717576
OS 28.45016662 44.3259083
OS 28.46220622 44.32147346
OS 28.47551328 44.31577116
OS 28.48058312 44.3145037
OS 28.4938851 44.31133632
OS 28.51986676 44.29929672
OS 28.53887612 44.2904245
OS 28.55091318 44.28852458
OS 28.55725048 44.28598966
OS 28.56802262 44.28028736
OS 28.5768923 44.27648752
OS 28.59843658 44.26634784
OS 28.60350642 44.26508038
OS 28.61364356 44.26381292
OS 28.63518784 44.25367578
OS 28.64912736 44.24607102
OS 28.66306688 44.23973372
OS 28.6656018 44.23846626
OS 28.67256902 44.23276396
OS 28.6770064 44.22959658
OS 28.68397616 44.22389428
OS 28.68714354 44.2207269
OS 28.68967846 44.21945944
OS 28.69855068 44.21565706
OS 28.7067879 44.21248968
OS 28.71439012 44.20741984
OS 28.72136242 44.20551992
OS 28.72642972 44.20425246
OS 28.7352994 44.202985
OS 28.75684368 44.19284532
OS 28.7657159 44.18777802
OS 28.77268566 44.18207318
OS 28.77458558 44.18017326
OS 28.7771205 44.1789058
OS 28.78409026 44.1732035
OS 28.78725764 44.17003358
OS 28.80119716 44.16496628
OS 28.80880192 44.15989898
OS 28.8176716 44.1560966
OS 28.82907874 44.1497593
OS 28.83414858 44.144692
OS 28.83668096 44.14342454
OS 28.84365326 44.1377197
OS 28.8468181 44.13455232
OS 28.8531554 44.1320174
OS 28.86139262 44.12885002
OS 28.86329254 44.12694756
OS 28.87976952 44.11934534
OS 28.8886392 44.1142755
OS 28.89117412 44.11174058
OS 28.89370904 44.11047312
OS 28.91018094 44.09400122
OS 28.91271586 44.09273376
OS 28.92032062 44.085129
OS 28.93236022 44.08069416
OS 28.93679506 44.07752678
OS 28.94376482 44.07182194
OS 28.95136958 44.06675464
OS 28.95707188 44.0610498
OS 28.96340918 44.05851488
OS 28.96847648 44.05724996
OS 28.97988108 44.04837774
OS 28.98685084 44.04267798
OS 28.9887533 44.04077552
OS 28.99128822 44.03950806
OS 28.99508806 44.03570568
OS 29.00206036 44.03380576
OS 29.0121975 44.02746846
OS 29.01536488 44.02430108
OS 29.0178998 44.02303362
OS 29.04451138 43.9964195
OS 29.0470463 43.99515204
OS 29.05465106 43.98754982
OS 29.06352074 43.9850149
OS 29.06985804 43.98121506
OS 29.0768278 43.97551276
OS 29.08126264 43.97234284
OS 29.08696494 43.96664054
OS 29.0882324 43.96410562
OS 29.09139978 43.96093824
OS 29.0939347 43.95967078
OS 29.09710208 43.9565034
OS 29.09836954 43.95396848
OS 29.10407184 43.94826364
OS 29.10660676 43.94699872
OS 29.11357906 43.94129388
OS 29.11674644 43.9381265
OS 29.12498366 43.93622658
OS 29.13195342 43.9317892
OS 29.1357558 43.92798682
OS 29.13829072 43.92671936
OS 29.14082564 43.92418698
OS 29.14336056 43.92292206
OS 29.14526048 43.9210196
OS 29.1465254 43.91848468
OS 29.16870468 43.89630794
OS 29.1706046 43.89567294
OS 29.17187206 43.89313802
OS 29.22826514 43.83674494
OS 29.23016506 43.83611248
OS 29.23143252 43.83357756
OS 29.276421 43.78859162
OS 29.27832092 43.78795662
OS 29.27958838 43.7854217
OS 29.29923274 43.76577988
OS 29.30176766 43.76451242
OS 29.30493504 43.7613425
OS 29.3062025 43.75880758
OS 29.3119048 43.75310528
OS 29.31443972 43.75183782
OS 29.3176071 43.74867044
OS 29.31887456 43.74613552
OS 29.3245794 43.7391683
OS 29.32647678 43.73726584
OS 29.3290117 43.73093108
OS 29.33217908 43.72269386
OS 29.33788138 43.71698902
OS 29.33914884 43.7144541
OS 29.34168376 43.71192172
OS 29.34295122 43.7093868
OS 29.3473886 43.70494942
OS 29.34992098 43.70368196
OS 29.35435836 43.69924712
OS 29.35562582 43.6967122
OS 29.36006066 43.69227736
OS 29.36259558 43.6910099
OS 29.36703042 43.68657506
OS 29.36829788 43.68404268
OS 29.37210026 43.6802403
OS 29.37336772 43.67770538
OS 29.37590264 43.67517046
OS 29.38033748 43.66313086
OS 29.38350486 43.65869602
OS 29.38857216 43.65362618
OS 29.38983962 43.65109126
OS 29.41645374 43.62447968
OS 29.4177212 43.6219473
OS 29.42279104 43.61687746
OS 29.4240585 43.61434254
OS 29.42659088 43.60800524
OS 29.43166072 43.59913556
OS 29.43736302 43.59216326
OS 29.43926548 43.59026334
OS 29.44053294 43.58772842
OS 29.44433532 43.58392604
OS 29.44560278 43.58139112
OS 29.44940008 43.57759128
OS 29.45130254 43.57061898
OS 29.45383746 43.56428676
OS 29.46080722 43.557317
OS 29.46207468 43.55478208
OS 29.47094436 43.54337494
OS 29.47347928 43.54084002
OS 29.47474674 43.53577272
OS 29.48108404 43.52436558
OS 29.48615388 43.51929574
OS 29.48742134 43.51676082
OS 29.49692602 43.50725614
OS 29.49882594 43.50662368
OS 29.5000934 43.5040913
OS 29.50389578 43.50028892
OS 29.50516324 43.497754
OS 29.50896308 43.49395162
OS 29.511498 43.48761686
OS 29.51466538 43.47937964
OS 29.51973522 43.47177488
OS 29.52417006 43.46100274
OS 29.5292399 43.45213052
OS 29.53430974 43.44706322
OS 29.5355772 43.4445283
OS 29.53810958 43.44199592
OS 29.53937704 43.439461
OS 29.54444688 43.43439116
OS 29.54571434 43.43185624
OS 29.54951672 43.42298656
OS 29.55712148 43.4090445
OS 29.56092132 43.40017482
OS 29.56599116 43.3913026
OS 29.57105846 43.38623276
OS 29.57232592 43.38370038
OS 29.57802822 43.37673062
OS 29.58119814 43.37229578
OS 29.58373052 43.36976086
OS 29.58690044 43.36152364
OS 29.58943536 43.35518634
OS 29.59513766 43.34568166
OS 29.59830504 43.33744444
OS 29.6002075 43.3330096
OS 29.6052748 43.32540484
OS 29.60907718 43.31653516
OS 29.6116121 43.3102004
OS 29.6179494 43.30006072
OS 29.62175178 43.29119104
OS 29.64329352 43.24936994
OS 29.6470959 43.24050026
OS 29.65026328 43.23226304
OS 29.6521632 43.23036058
OS 29.65596558 43.2214909
OS 29.65723304 43.21261868
OS 29.6585005 43.20754884
OS 29.66166788 43.19931416
OS 29.66737272 43.18980948
OS 29.66864018 43.18473964
OS 29.69271684 43.13531886
OS 29.69398176 43.13024902
OS 29.69524922 43.12010934
OS 29.70412144 43.10109998
OS 29.70665636 43.09096284
OS 29.70792382 43.08336062
OS 29.71299366 43.07195348
OS 29.7167935 43.0630838
OS 29.71932842 43.05294412
OS 29.72059588 43.0453419
OS 29.72693318 43.03139984
OS 29.7294681 43.02506508
OS 29.73073556 43.01999778
OS 29.73263548 43.00922564
OS 29.73897278 42.99528358
OS 29.74214016 42.98704636
OS 29.74340762 42.98197652
OS 29.74467508 42.97310684
OS 29.75100984 42.95916732
OS 29.75354476 42.95283256
OS 29.75671214 42.93825804
OS 29.76051452 42.92811836
OS 29.7636819 42.91988114
OS 29.76494936 42.9148113
OS 29.76685182 42.90024186
OS 29.76938674 42.87996504
OS 29.77191912 42.86982536
OS 29.77508904 42.86158814
OS 29.77889142 42.84891354
OS 29.78079134 42.83307664
OS 29.7820588 42.82673934
OS 29.78586118 42.81659966
OS 29.78966356 42.80266014
OS 29.79093102 42.79505538
OS 29.7934634 42.77224618
OS 29.79599832 42.76210904
OS 29.79916824 42.7513369
OS 29.80170316 42.74119722
OS 29.80296808 42.73232754
OS 29.80423554 42.7272577
OS 29.805503 42.70951834
OS 29.80676792 42.70571596
OS 29.81183776 42.68797406
OS 29.81500768 42.65692764
OS 29.8162726 42.64678796
OS 29.81754006 42.62651114
OS 29.81944252 42.6094017
OS 29.8226099 42.59482972
OS 29.82451236 42.57772282
OS 29.82641228 42.5454064
OS 29.82767974 42.49725054
OS 29.8289472 42.42375056
OS 29.83211458 42.41931572
OS 29.83401704 42.41741326
OS 29.83908434 42.4161458
OS 29.85809624 42.41741326
OS 29.86253108 42.42185064
OS 29.86379854 42.4269154
OS 29.86253108 42.44339238
OS 29.85746124 42.45479698
OS 29.85619378 42.4636692
OS 29.85429386 42.48837832
OS 29.8530264 42.50232038
OS 29.85049148 42.55554354
OS 29.84922402 42.57708782
OS 29.84795656 42.59482972
OS 29.8466891 42.60496686
OS 29.84542164 42.61130416
OS 29.84415418 42.61637146
OS 29.84288672 42.62270876
OS 29.8403518 42.63791574
OS 29.83781688 42.6632624
OS 29.8352845 42.67846938
OS 29.83401704 42.68353668
OS 29.83211458 42.68924152
OS 29.83084712 42.69430882
OS 29.82957966 42.70698342
OS 29.8283122 42.71205326
OS 29.82577982 42.73739484
OS 29.82451236 42.74246468
OS 29.8232449 42.75260436
OS 29.82070998 42.75893912
OS 29.8169076 42.77414864
OS 29.81564014 42.78681816
OS 29.81437268 42.791888
OS 29.81310522 42.80456006
OS 29.81183776 42.80836244
OS 29.8105703 42.81343228
OS 29.80676792 42.82610434
OS 29.805503 42.83117418
OS 29.80296808 42.84891354
OS 29.80106816 42.86475552
OS 29.7998007 42.86982536
OS 29.79599832 42.87996504
OS 29.79283094 42.88820226
OS 29.79029602 42.8983394
OS 29.78902856 42.90594162
OS 29.78269126 42.91988114
OS 29.78015888 42.92875336
OS 29.77825642 42.94459534
OS 29.77698896 42.9509301
OS 29.77191912 42.96486962
OS 29.76875174 42.97310684
OS 29.76621682 42.98324398
OS 29.7643169 42.99021628
OS 29.76114698 42.9984535
OS 29.75734714 43.00732318
OS 29.75481222 43.0161954
OS 29.7516423 43.02949992
OS 29.74467508 43.0453419
OS 29.74214016 43.05547904
OS 29.74024024 43.0624488
OS 29.73643786 43.07258848
OS 29.73200302 43.08336062
OS 29.7294681 43.09349522
OS 29.72820064 43.10109998
OS 29.72186334 43.11123966
OS 29.72059588 43.11630696
OS 29.70665636 43.14545346
OS 29.7053889 43.15812806
OS 29.69271684 43.18473964
OS 29.68637954 43.19614678
OS 29.68004478 43.21008376
OS 29.67370748 43.2214909
OS 29.66737272 43.23543042
OS 29.6585005 43.25443978
OS 29.65660058 43.26647684
OS 29.65406566 43.27281414
OS 29.63758868 43.30576302
OS 29.62555162 43.33047468
OS 29.61414702 43.35201896
OS 29.60907718 43.3570888
OS 29.60780972 43.35962118
OS 29.60210742 43.36659348
OS 29.59767258 43.3748307
OS 29.59640512 43.38370038
OS 29.59513766 43.3913026
OS 29.59133528 43.3976399
OS 29.5875329 43.40144228
OS 29.58626544 43.40397466
OS 29.57739576 43.4153818
OS 29.57232592 43.42298656
OS 29.570426 43.42995632
OS 29.56409124 43.44009346
OS 29.56092132 43.44706322
OS 29.55775394 43.45530044
OS 29.55141664 43.46290266
OS 29.54951672 43.46480512
OS 29.54824926 43.46734004
OS 29.54254696 43.4743098
OS 29.53937704 43.47747718
OS 29.53810958 43.4800121
OS 29.5355772 43.4863494
OS 29.5292399 43.497754
OS 29.5229026 43.5040913
OS 29.52163514 43.50662368
OS 29.51783276 43.51042606
OS 29.5165653 43.51296098
OS 29.51403292 43.51549336
OS 29.511498 43.52183066
OS 29.50832808 43.53006788
OS 29.50136086 43.53703764
OS 29.5000934 43.53957256
OS 29.4943911 43.54654486
OS 29.49122372 43.54971224
OS 29.48742134 43.557317
OS 29.48742134 43.55858192
OS 29.48108404 43.56998652
OS 29.4760142 43.57505636
OS 29.47474674 43.57759128
OS 29.4582723 43.59406572
OS 29.45700484 43.59660064
OS 29.45320246 43.60040302
OS 29.45066754 43.60673778
OS 29.44750016 43.614975
OS 29.4418004 43.62067984
OS 29.44053294 43.62321476
OS 29.43673056 43.62701206
OS 29.4354631 43.62954698
OS 29.43102826 43.6327169
OS 29.42532596 43.6384192
OS 29.4240585 43.64095412
OS 29.42025612 43.6447565
OS 29.41898866 43.64728888
OS 29.41645374 43.6498238
OS 29.41391882 43.6561611
OS 29.41075144 43.66439832
OS 29.40378168 43.67136808
OS 29.40251422 43.673903
OS 29.3873047 43.68910998
OS 29.38603978 43.6916449
OS 29.38096994 43.6967122
OS 29.37970502 43.69924712
OS 29.3771701 43.70558442
OS 29.37590264 43.71065426
OS 29.3701978 43.71762402
OS 29.36703042 43.7207914
OS 29.36576296 43.72332632
OS 29.35752574 43.73156354
OS 29.35499082 43.732831
OS 29.35182344 43.73726584
OS 29.33598146 43.75310528
OS 29.33344654 43.75437274
OS 29.33027916 43.75754266
OS 29.3290117 43.76007504
OS 29.32331194 43.76577988
OS 29.32077702 43.76704734
OS 29.3176071 43.77021472
OS 29.31633964 43.77274964
OS 29.3125398 43.77655202
OS 29.31127234 43.77908694
OS 29.3062025 43.78415424
OS 29.30366758 43.79302646
OS 29.2998652 43.79936376
OS 29.29479536 43.80442852
OS 29.2935279 43.80696344
OS 29.2878256 43.81393574
OS 29.28085584 43.81963804
OS 29.27958838 43.82217296
OS 29.27515354 43.8266078
OS 29.27261862 43.82787526
OS 29.26818378 43.8323101
OS 29.26691632 43.83484502
OS 29.26248148 43.83927986
OS 29.25994656 43.84054732
OS 29.25677918 43.84371724
OS 29.25551172 43.84625216
OS 29.25107688 43.850687
OS 29.24854196 43.85195446
OS 29.24410712 43.8563893
OS 29.24283966 43.85892422
OS 29.23840228 43.86335906
OS 29.2358699 43.86462398
OS 29.23143252 43.86906136
OS 29.23016506 43.87159374
OS 29.22573022 43.87603112
OS 29.2231953 43.87729858
OS 29.22002792 43.88046596
OS 29.21876046 43.88300088
OS 29.21432562 43.88743572
OS 29.2117907 43.88870318
OS 29.20482094 43.89440548
OS 29.20165356 43.8975754
OS 29.18771404 43.9026427
OS 29.1826442 43.90771254
OS 29.18010928 43.90898
OS 29.17757436 43.91151492
OS 29.17503944 43.91278238
OS 29.1706046 43.91721722
OS 29.16933714 43.91975214
OS 29.16616976 43.92292206
OS 29.16363484 43.92418698
OS 29.1592 43.92862182
OS 29.15793254 43.93115674
OS 29.15349516 43.93559158
OS 29.15096024 43.93685904
OS 29.14526048 43.94256134
OS 29.14399302 43.94509626
OS 29.12815104 43.96093824
OS 29.12561612 43.9622057
OS 29.1237162 43.96410562
OS 29.12244874 43.96664054
OS 29.11547898 43.9736103
OS 29.11294406 43.97487776
OS 29.10660676 43.98121506
OS 29.10407184 43.98248252
OS 29.09773708 43.9850149
OS 29.09266724 43.98628236
OS 29.08570002 43.99198466
OS 29.0825301 43.99515204
OS 29.07999772 43.9964195
OS 29.0647882 44.01162902
OS 29.06225328 44.01289648
OS 29.05591852 44.01923124
OS 29.05084868 44.0204987
OS 29.04261146 44.02366862
OS 29.03690916 44.02937092
OS 29.03437424 44.03063838
OS 29.03183932 44.0331733
OS 29.0293044 44.03444076
OS 29.02233718 44.04141052
OS 29.02106972 44.04394544
OS 29.01663234 44.04711028
OS 29.0128325 44.05091266
OS 29.01029758 44.05218012
OS 29.00776266 44.05471504
OS 29.00522774 44.0559825
OS 28.99889044 44.05851488
OS 28.99002076 44.06358472
OS 28.98748584 44.06611964
OS 28.98495092 44.0673871
OS 28.96974394 44.08259408
OS 28.96720902 44.08386154
OS 28.9596068 44.0914663
OS 28.9532695 44.09400122
OS 28.94819966 44.09526868
OS 28.92539046 44.11300804
OS 28.92158808 44.11681042
OS 28.91651824 44.11807788
OS 28.90828102 44.12124526
OS 28.90511364 44.12441518
OS 28.90258126 44.1256801
OS 28.89751142 44.13074994
OS 28.8949765 44.1320174
OS 28.8886392 44.1383547
OS 28.88610428 44.13962216
OS 28.8772346 44.14342454
OS 28.86836238 44.14849184
OS 28.86329254 44.15356168
OS 28.86075762 44.15482914
OS 28.85822524 44.15736406
OS 28.85569032 44.15863152
OS 28.84935302 44.16496628
OS 28.84301826 44.1675012
OS 28.83478104 44.17066858
OS 28.82527636 44.17637088
OS 28.81893906 44.1789058
OS 28.80753446 44.1852431
OS 28.80373208 44.18904548
OS 28.80119716 44.19031294
OS 28.7942274 44.19601524
OS 28.78979256 44.20045008
OS 28.7834578 44.202985
OS 28.77522058 44.20615238
OS 28.76761582 44.21122222
OS 28.76064606 44.2143896
OS 28.75177384 44.21819198
OS 28.74923892 44.21945944
OS 28.7416367 44.22452674
OS 28.73276448 44.22832912
OS 28.7245298 44.2314965
OS 28.72262988 44.23339896
OS 28.72009496 44.23466642
OS 28.7061529 44.24100118
OS 28.6947483 44.24733848
OS 28.68080878 44.25367578
OS 28.6592645 44.26381292
OS 28.6541972 44.26508038
OS 28.64405752 44.26634784
OS 28.63518784 44.27141768
OS 28.62631562 44.27522006
OS 28.6180784 44.27838744
OS 28.61047364 44.28345728
OS 28.58829944 44.29422688
OS 28.55408056 44.31070132
OS 28.54521342 44.31323624
OS 28.5363412 44.3145037
OS 28.50972708 44.32717576
OS 28.49071772 44.33604798
OS 28.48184804 44.33731544
OS 28.46981098 44.34175028
OS 28.46347368 44.34428266
OS 28.45650392 44.34745258
OS 28.45143408 44.3487175
OS 28.43812702 44.35188742
OS 28.43178972 44.35442234
OS 28.4248225 44.35758972
OS 28.4184852 44.36012464
OS 28.4134179 44.3613921
OS 28.40391068 44.36329202
OS 28.39377354 44.3670944
OS 28.38680378 44.37026178
OS 28.38046648 44.3727967
OS 28.37159426 44.37406416
OS 28.3595572 44.37850154
OS 28.35131998 44.38166892
OS 28.34498522 44.38420384
OS 28.336113 44.3854713
OS 28.33104316 44.38673876
OS 28.31710364 44.38800622
OS 28.30569904 44.39307352
OS 28.29936428 44.39560844
OS 28.2892246 44.39814336
OS 28.28161984 44.39941082
OS 28.27021524 44.40447812
OS 28.26387794 44.40701304
OS 28.25500826 44.40954796
OS 28.23916882 44.41144788
OS 28.23283152 44.41271534
OS 28.22269438 44.41651772
OS 28.21572208 44.41841764
OS 28.21065478 44.4196851
OS 28.1948128 44.42158756
OS 28.18087328 44.42285502
OS 28.15806408 44.42665486
OS 28.15299424 44.42792232
OS 28.14602448 44.42982478
OS 28.14095464 44.43109224
OS 28.12321528 44.43362716
OS 28.10610584 44.43552708
OS 28.09850108 44.43679454
OS 28.08836394 44.438062
OS 28.08202664 44.43932946
OS 28.0769568 44.44059692
OS 28.06998704 44.44249684
OS 28.0547826 44.44503176
OS 28.02246618 44.44819914
OS 28.00535928 44.4501016
OS 27.99648706 44.45136906
OS 27.9895173 44.45326898
OS 27.98318 44.45453644
OS 27.9660731 44.4564389
OS 27.94199644 44.45770382
OS 27.925522 44.45897128
OS 27.91601478 44.45960628
OS 27.91031248 44.45897128
OS 27.9065101 44.46023874
OS 27.88053352 44.4621412
OS 27.86786146 44.46340866
OS 27.8539194 44.46594104
OS 27.84378226 44.4672085
OS 27.82097306 44.46847596
OS 27.807031 44.46974342
OS 27.7829518 44.47100834
OS 27.74937046 44.47164334
OE
OB 27.45790292 43.58329358 H
OS 26.72732526 43.58265858
OS 26.71275074 43.58329358
OS 26.70894836 43.58202612
OS 26.6962763 43.58075866
OS 26.66016004 43.57885874
OS 26.6557252 43.57695628
OS 26.64622052 43.5674516
OS 26.64495306 43.5623843
OS 26.6430506 43.52373312
OS 26.64115068 43.50662368
OS 26.64051568 42.4630342
OS 26.64178314 42.44782722
OS 26.64495306 42.44339238
OS 26.64685298 42.44148992
OS 26.65192282 42.44022246
OS 26.90157434 42.44148992
OS 26.90600918 42.4459273
OS 26.90727664 42.4509946
OS 26.9079091 42.52639704
OS 26.90727664 42.53083442
OS 26.9085441 42.5346368
OS 26.90727664 42.54730632
OS 26.9085441 42.5865925
OS 26.9079091 43.31083286
OS 26.90917656 43.32224
OS 26.91171148 43.3260373
OS 26.91804878 43.32857222
OS 27.12080936 43.32730476
OS 27.1252442 43.32413992
OS 27.12651166 43.31907008
OS 27.12714412 43.31210032
OS 27.12651166 43.30513056
OS 27.12777912 43.30132818
OS 27.12714412 43.23986526
OS 27.12777912 43.2328955
OS 27.12651166 43.22909312
OS 27.12714412 43.20691638
OS 27.12651166 43.19361186
OS 27.12777912 43.18980948
OS 27.12714412 43.17143258
OS 27.12777912 42.55364362
OS 27.12777912 42.55237616
OS 27.12904658 42.50041792
OS 27.13031404 42.49661554
OS 27.1315815 42.45986682
OS 27.13791626 42.4509946
OS 27.14108618 42.44782722
OS 27.1436211 42.44655976
OS 27.14995586 42.44402484
OS 27.19304442 42.44275738
OS 27.19684426 42.44148992
OS 27.20571648 42.44022246
OS 27.22472584 42.44148992
OS 27.22852568 42.44022246
OS 27.36285612 42.44148992
OS 27.36855842 42.4459273
OS 27.36982588 42.4509946
OS 27.37109334 43.321605
OS 27.37552818 43.32730476
OS 27.3844004 43.32857222
OS 27.43509118 43.32983968
OS 27.43889102 43.33110714
OS 27.4490307 43.3323746
OS 27.45156562 43.33490952
OS 27.45410054 43.33617698
OS 27.45980284 43.34187928
OS 27.4610703 43.3444142
OS 27.46360522 43.3507515
OS 27.46550514 43.39320252
OS 27.4667726 43.39953982
OS 27.46740506 43.4153818
OS 27.46614014 43.41918418
OS 27.46740506 43.43185624
OS 27.46614014 43.57759128
OS 27.46423768 43.58075866
OS 27.45790292 43.58329358
OE
OB 28.81640414 43.58329358 H
OS 28.8126043 43.58202612
OS 28.7999297 43.58329358
OS 28.26007556 43.58202612
OS 28.25627572 43.58075866
OS 28.21762454 43.57885874
OS 28.20748486 43.57505636
OS 28.19354534 43.56998652
OS 28.1891105 43.56681914
OS 28.18657812 43.56428676
OS 28.1840432 43.5630193
OS 28.18150828 43.56048438
OS 28.17897336 43.55921692
OS 28.17327106 43.55351462
OS 28.1720036 43.5509797
OS 28.16883622 43.54780978
OS 28.1663013 43.54654486
OS 28.159329 43.53957256
OS 28.15806408 43.53703764
OS 28.15616162 43.53513772
OS 28.1536267 43.53387026
OS 28.1479244 43.52816796
OS 28.14665694 43.52563304
OS 28.14475702 43.52373312
OS 28.1422221 43.52246566
OS 28.13525234 43.51549336
OS 28.13398488 43.51296098
OS 28.1295475 43.50979106
OS 28.12384774 43.5040913
OS 28.12258028 43.50155638
OS 28.12068036 43.49965646
OS 28.11814544 43.498389
OS 28.11244314 43.49268416
OS 28.11117568 43.49015178
OS 28.10800576 43.48698186
OS 28.10547084 43.4857144
OS 28.09850108 43.47874464
OS 28.09723362 43.47620972
OS 28.0953337 43.4743098
OS 28.09279878 43.47304234
OS 28.08709648 43.46734004
OS 28.08582902 43.46480512
OS 28.08392656 43.46290266
OS 28.08139418 43.4616352
OS 28.07568934 43.4559329
OS 28.07442188 43.45339798
OS 28.0712545 43.4502306
OS 28.06871958 43.44896314
OS 28.06301982 43.44326338
OS 28.06175236 43.44072846
OS 28.0598499 43.438826
OS 28.05731752 43.43755854
OS 28.05161268 43.43185624
OS 28.05034522 43.42932132
OS 28.042743 43.41791672
OS 28.04020808 43.40777704
OS 28.03894062 43.3913026
OS 28.03767316 43.38750022
OS 28.0364057 43.38243292
OS 28.03387078 43.37609816
OS 28.03260332 43.37102832
OS 28.03133586 43.35835372
OS 28.02943594 43.3260373
OS 28.02816848 43.28802112
OS 28.02753348 42.72345786
OS 28.02880094 42.71965548
OS 28.0300684 42.66769724
OS 28.03133586 42.6638974
OS 28.03260332 42.63855074
OS 28.03767316 42.6271436
OS 28.03957308 42.61890638
OS 28.04147554 42.60686678
OS 28.04781284 42.59673218
OS 28.05034522 42.59039488
OS 28.0541476 42.58025774
OS 28.0598499 42.57328544
OS 28.06301982 42.57011806
OS 28.06428728 42.56758314
OS 28.0712545 42.56061338
OS 28.07378942 42.55934592
OS 28.08012672 42.55300862
OS 28.08646148 42.5504737
OS 28.0946987 42.54730632
OS 28.09913608 42.54414148
OS 28.10230346 42.5397041
OS 28.10547084 42.53653672
OS 28.10800576 42.53526926
OS 28.10990822 42.53336934
OS 28.11244314 42.52703204
OS 28.11434306 42.52006228
OS 28.11624298 42.51815982
OS 28.11751044 42.5156249
OS 28.12068036 42.51245752
OS 28.12321528 42.51119006
OS 28.12638266 42.50675522
OS 28.1295475 42.5035853
OS 28.14538948 42.497883
OS 28.1479244 42.49534808
OS 28.14919186 42.49281316
OS 28.1536267 42.48837832
OS 28.15616162 42.48711086
OS 28.15806408 42.48521094
OS 28.16059646 42.47887618
OS 28.16376638 42.47063896
OS 28.16693376 42.46620412
OS 28.1713686 42.4630342
OS 28.17327106 42.46113428
OS 28.17453852 42.45859936
OS 28.1777059 42.45543198
OS 28.1840432 42.45289706
OS 28.19608026 42.44845968
OS 28.20431748 42.4452923
OS 28.22079192 42.44402484
OS 28.2531058 42.44212492
OS 28.30633404 42.44085746
OS 28.66306688 42.44022246
OS 28.66433434 42.44022246
OS 28.89751142 42.44148992
OS 28.9006788 42.44465984
OS 28.90321372 42.45479698
OS 28.90194626 42.66516232
OS 28.89751142 42.66959716
OS 28.89244158 42.67086462
OS 28.44699924 42.67149708
OS 28.43115726 42.67086462
OS 28.42735488 42.67213208
OS 28.4064456 42.67149708
OS 28.39187362 42.67213208
OS 28.38807124 42.67086462
OS 28.37603164 42.67276454
OS 28.37286172 42.67339954
OS 28.36906188 42.67213208
OS 28.35892474 42.67086462
OS 28.35512236 42.67213208
OS 28.34498522 42.674667
OS 28.3120338 42.67593446
OS 28.29999674 42.68797406
OS 28.29872928 42.69304136
OS 28.29746182 42.70191358
OS 28.29619436 42.73106008
OS 28.2949269 42.73486246
OS 28.29619436 42.75640674
OS 28.2949269 42.76020658
OS 28.2955619 42.84067886
OS 28.2949269 42.85398338
OS 28.29619436 42.85778576
OS 28.29746182 42.86665798
OS 28.29872928 42.89453702
OS 28.30506658 42.90340924
OS 28.31076634 42.909109
OS 28.32090602 42.91164392
OS 28.35258744 42.91291138
OS 28.35638982 42.91417884
OS 28.3772991 42.91354638
OS 28.80436454 42.9148113
OS 28.8119693 42.91607876
OS 28.81577168 42.91988114
OS 28.8183066 42.92875336
OS 28.8176716 43.0218977
OS 28.8183066 43.03393476
OS 28.81703914 43.03773714
OS 28.81577168 43.05421158
OS 28.81450422 43.06688618
OS 28.81387176 43.08145816
OS 28.81450422 43.085893
OS 28.81323676 43.08969538
OS 28.80943438 43.09603014
OS 28.80246462 43.10300244
OS 28.7935924 43.10553482
OS 28.75177384 43.10680228
OS 28.747974 43.10806974
OS 28.73910178 43.1093372
OS 28.72262988 43.10806974
OS 28.71375766 43.1093372
OS 28.69791568 43.10870474
OS 28.30253166 43.1099722
OS 28.29809682 43.11187212
OS 28.2949269 43.11884188
OS 28.2955619 43.2512724
OS 28.2949269 43.26584438
OS 28.29619436 43.26964676
OS 28.2955619 43.29055604
OS 28.29682936 43.29689334
OS 28.29809682 43.31843762
OS 28.29936428 43.33490952
OS 28.3012642 43.33680944
OS 28.30253166 43.33934436
OS 28.30949888 43.34631666
OS 28.3120338 43.34758158
OS 28.31583618 43.34884904
OS 28.35068752 43.3507515
OS 28.35575736 43.35201896
OS 28.36779442 43.35265142
OS 28.37159426 43.35138396
OS 28.394406 43.35265142
OS 28.39820838 43.35138396
OS 28.41088298 43.35265142
OS 28.89624396 43.35391888
OS 28.9006788 43.3570888
OS 28.90321372 43.36595848
OS 28.90258126 43.47050742
OS 28.90321372 43.48508194
OS 28.90194626 43.48888432
OS 28.90321372 43.51042606
OS 28.90194626 43.51422844
OS 28.9006788 43.51929574
OS 28.89877888 43.5630193
OS 28.89687642 43.5674516
OS 28.8943415 43.56998652
OS 28.89307404 43.57252144
OS 28.89117412 43.57442136
OS 28.8886392 43.57568882
OS 28.88610428 43.57822374
OS 28.88103698 43.5794912
OS 28.83858342 43.58139112
OS 28.83224612 43.58265858
OS 28.81640414 43.58329358
OE
OB 26.01829188 43.58329358 H
OS 26.01449204 43.58202612
OS 26.00181744 43.58329358
OS 25.23512606 43.58202612
OS 25.23068868 43.57759128
OS 25.22942122 43.56871906
OS 25.23005622 43.4147468
OS 25.22942122 43.40144228
OS 25.23068868 43.3976399
OS 25.23195614 43.38876768
OS 25.2338586 43.34884904
OS 25.23575852 43.3444142
OS 25.24082836 43.33934436
OS 25.24146082 43.33744444
OS 25.24399574 43.33617698
OS 25.24653066 43.33364206
OS 25.25540034 43.3323746
OS 25.29405152 43.33047468
OS 25.30038882 43.32920722
OS 25.31622826 43.32857222
OS 25.32003064 43.32983968
OS 25.3327027 43.32857222
OS 25.41064006 43.32793976
OS 25.4214122 43.32857222
OS 25.42521458 43.32730476
OS 25.44612386 43.32793976
OS 25.4619633 43.32730476
OS 25.46576568 43.32857222
OS 25.47653782 43.3266723
OS 25.51645646 43.32350746
OS 25.52849606 43.31146786
OS 25.52976352 43.30639802
OS 25.52976352 43.29499088
OS 25.52976352 43.29372342
OS 25.53103098 43.28485374
OS 25.53229844 43.26584438
OS 25.5335659 43.26204454
OS 25.53229844 43.24936994
OS 25.5335659 43.23036058
OS 25.53229844 43.2265582
OS 25.5335659 43.20501392
OS 25.53229844 43.20121662
OS 25.5335659 43.18854202
OS 25.53483336 42.4459273
OS 25.53800074 42.44275738
OS 25.54307058 42.44148992
OS 25.55193772 42.44022246
OS 25.68817062 42.44085746
OS 25.70274514 42.44022246
OS 25.70654498 42.44148992
OS 25.7268218 42.44022246
OS 25.73062164 42.44148992
OS 25.73949386 42.44275738
OS 25.77941504 42.44465984
OS 25.7857498 42.44719476
OS 25.79461948 42.45606444
OS 25.7971544 42.46493666
OS 25.79842186 42.50548776
OS 25.79968932 42.50929014
OS 25.80095678 42.5219622
OS 25.79968932 42.5346368
OS 25.80095678 42.54350648
OS 25.80032178 42.55934592
OS 25.80158924 43.2208559
OS 25.80222424 43.22782566
OS 25.80095678 43.23162804
OS 25.80222424 43.25443978
OS 25.80095678 43.25824216
OS 25.80222424 43.27217914
OS 25.8034917 43.27598152
OS 25.80412416 43.30069572
OS 25.8034917 43.30132818
OS 25.80475916 43.30513056
OS 25.80602408 43.31146786
OS 25.81806368 43.32350746
OS 25.8269359 43.32477238
OS 25.84658026 43.32540484
OS 25.8497451 43.32477238
OS 25.85354748 43.3260373
OS 25.86431962 43.32793976
OS 25.87128938 43.32857222
OS 25.87509176 43.32730476
OS 25.89853596 43.32793976
OS 25.91057302 43.32730476
OS 25.9143754 43.32857222
OS 25.93148484 43.32793976
OS 25.9973826 43.32920722
OS 26.00435236 43.32983968
OS 26.00815474 43.32857222
OS 26.0271641 43.32983968
OS 26.03096394 43.33110714
OS 26.0734175 43.3330096
OS 26.08925694 43.34251428
OS 26.09242686 43.34568166
OS 26.09749416 43.35455388
OS 26.10129654 43.36342356
OS 26.103199 43.40714458
OS 26.10446646 43.41348188
OS 26.10509892 43.42551894
OS 26.10383146 43.42932132
OS 26.10509892 43.45466544
OS 26.10383146 43.45846782
OS 26.10509892 43.47494226
OS 26.10383146 43.497754
OS 26.10509892 43.50155638
OS 26.10383146 43.51549336
OS 26.102564 43.51929574
OS 26.10066408 43.5630193
OS 26.09876162 43.5674516
OS 26.09305932 43.57442136
OS 26.0854571 43.5794912
OS 26.04046862 43.58139112
OS 26.03413132 43.58265858
OS 26.01829188 43.58329358
OE
OB 26.455497 43.58329358 H
OS 26.24893404 43.58329358
OS 26.22105246 43.58202612
OS 26.21661762 43.57885874
OS 26.21535016 43.5737889
OS 26.2147177 43.56935406
OS 26.21535016 43.56111684
OS 26.2140827 43.557317
OS 26.21535016 43.54844478
OS 26.21661762 42.4459273
OS 26.22105246 42.44148992
OS 26.23372706 42.44022246
OS 26.46309922 42.44148992
OS 26.4675366 42.44465984
OS 26.47007152 42.45352952
OS 26.46880406 43.57759128
OS 26.46436668 43.58202612
OS 26.455497 43.58329358
OE
OB 29.68321216 42.29448996 H
OS 29.67941232 42.2932225
OS 29.66040042 42.29448996
OS 29.65660058 42.2932225
OS 29.63568876 42.29385496
OS 29.628084 42.2925875
OS 29.61034464 42.29132004
OS 29.6059098 42.29068758
OS 29.60464234 42.29068758
OS 29.59006782 42.29005512
OS 29.58309806 42.29068758
OS 29.57929568 42.28942012
OS 29.57676076 42.28815266
OS 29.57295838 42.28435028
OS 29.570426 42.28308282
OS 29.56852354 42.2811829
OS 29.56725608 42.27864798
OS 29.5647237 42.27231068
OS 29.56282378 42.2349295
OS 29.56155632 42.22478982
OS 29.56028886 41.17929788
OS 29.55965386 41.17106066
OS 29.56092132 41.16725828
OS 29.56218878 41.15585622
OS 29.5653587 41.1526863
OS 29.57422584 41.15141884
OS 30.2870616 41.15205384
OS 30.3041685 41.15141884
OS 30.30797088 41.1526863
OS 30.32064548 41.15395376
OS 30.35676174 41.15585622
OS 30.36626642 41.16155852
OS 30.36880134 41.16282598
OS 30.37323618 41.16599082
OS 30.37450364 41.16852574
OS 30.49742694 41.29145158
OS 30.4986944 41.29398396
OS 30.50629916 41.30158872
OS 30.50883408 41.30792602
OS 30.51326892 41.31996562
OS 30.51516884 41.32566792
OS 30.5164363 41.33073776
OS 30.51833876 41.36051672
OS 30.52023868 41.39790298
OS 30.52150614 41.50942168
OS 30.52087368 42.02709654
OS 30.52150614 42.03533376
OS 30.52023868 42.03913614
OS 30.52087368 42.06131288
OS 30.51960622 42.06764764
OS 30.5170713 42.10186652
OS 30.5164363 42.10756882
OS 30.51770376 42.1113712
OS 30.5164363 42.1164385
OS 30.51010154 42.1278431
OS 30.5043967 42.13481286
OS 30.49742694 42.14051516
OS 30.49615948 42.14305008
OS 30.49045718 42.14875238
OS 30.48792226 42.15001984
OS 30.48475488 42.15318976
OS 30.48348742 42.15572468
OS 30.47778512 42.16142698
OS 30.4752502 42.16269444
OS 30.47334774 42.16459436
OS 30.47208028 42.16712928
OS 30.46637798 42.17283158
OS 30.4638456 42.17409904
OS 30.46067822 42.17726896
OS 30.45941076 42.17980388
OS 30.45370846 42.18550364
OS 30.45117354 42.1867711
OS 30.44927108 42.18867102
OS 30.44800362 42.19120594
OS 30.44230132 42.19690824
OS 30.4397664 42.1981757
OS 30.43659902 42.20134562
OS 30.43533156 42.203878
OS 30.42962926 42.20958284
OS 30.42709434 42.2108503
OS 30.42392696 42.21401768
OS 30.4226595 42.2165526
OS 30.41695466 42.2222549
OS 30.41442228 42.22352236
OS 30.41251982 42.22542228
OS 30.41125236 42.2279572
OS 30.4055526 42.23366204
OS 30.40301768 42.2349295
OS 30.3998503 42.23809688
OS 30.39858284 42.2406318
OS 30.392878 42.24633156
OS 30.39034562 42.24759902
OS 30.38844316 42.24949894
OS 30.3871757 42.25203386
OS 30.3814734 42.2577387
OS 30.37893848 42.25900362
OS 30.3757711 42.26217354
OS 30.37450364 42.26470846
OS 30.36880134 42.27041076
OS 30.36626642 42.27167822
OS 30.35992912 42.27801552
OS 30.3573942 42.27928298
OS 30.34852452 42.28308282
OS 30.3402873 42.28625274
OS 30.33395254 42.28878766
OS 30.32634778 42.29005512
OS 30.3231804 42.29068758
OS 30.31937802 42.28942012
OS 30.31557564 42.29068758
OS 30.28072684 42.2925875
OS 30.22496622 42.29385496
OS 29.68321216 42.29448996
OE
OB 27.03336986 42.29448996 H
OS 27.02956748 42.2932225
OS 27.00485328 42.29385496
OS 27.00422082 42.2932225
OS 26.96873956 42.29448996
OS 26.48084366 42.2932225
OS 26.47704128 42.29195504
OS 26.44092502 42.29005512
OS 26.42698296 42.28878766
OS 26.4206482 42.28625274
OS 26.41050852 42.28245036
OS 26.40417376 42.27991544
OS 26.39973638 42.27674806
OS 26.395934 42.27294568
OS 26.39340162 42.27167822
OS 26.3908667 42.2691433
OS 26.38833178 42.26787584
OS 26.38643186 42.26597592
OS 26.3851644 42.263441
OS 26.3794621 42.2577387
OS 26.37692718 42.25647124
OS 26.3737598 42.25330132
OS 26.37249234 42.2507664
OS 26.36679004 42.24506664
OS 26.36425512 42.24379918
OS 26.3610852 42.2406318
OS 26.35981774 42.23809688
OS 26.35411544 42.23239458
OS 26.35158052 42.23112712
OS 26.3496806 42.22922466
OS 26.34841314 42.22668974
OS 26.34144338 42.21971998
OS 26.33890846 42.21845252
OS 26.33700854 42.2165526
OS 26.33574108 42.21401768
OS 26.33003624 42.20831538
OS 26.32750386 42.20704792
OS 26.32433648 42.203878
OS 26.32306902 42.20134562
OS 26.31736672 42.19564078
OS 26.3148318 42.19437332
OS 26.31293188 42.1924734
OS 26.31166442 42.18993848
OS 26.30595958 42.18423872
OS 26.3034272 42.18297126
OS 26.30025728 42.17980388
OS 26.29898982 42.17726896
OS 26.29455498 42.17283158
OS 26.29202006 42.17156412
OS 26.28885268 42.16839674
OS 26.28758522 42.16586182
OS 26.28188292 42.16015952
OS 26.279348 42.15889206
OS 26.27617808 42.15572468
OS 26.27491062 42.15318976
OS 26.27047578 42.14875238
OS 26.26794086 42.14748746
OS 26.26350856 42.14305008
OS 26.25970618 42.13671532
OS 26.25336888 42.1278431
OS 26.25210142 42.1227758
OS 26.2502015 42.1107362
OS 26.24639912 42.10059906
OS 26.2444992 42.09362676
OS 26.24323174 42.08855946
OS 26.24132928 42.0524432
OS 26.24006182 42.01695686
OS 26.23942936 41.4169098
OS 26.24069682 41.41310742
OS 26.24196428 41.35988172
OS 26.24323174 41.35608188
OS 26.2444992 41.33707252
OS 26.25083396 41.323133
OS 26.25210142 41.31806316
OS 26.25843872 41.30919348
OS 26.2622411 41.3053911
OS 26.26350856 41.30285618
OS 26.27047578 41.29588642
OS 26.2730107 41.29461896
OS 26.27491062 41.29271904
OS 26.27617808 41.29018412
OS 26.28314784 41.28321436
OS 26.28568276 41.2819469
OS 26.28885268 41.27751206
OS 26.29455498 41.27180976
OS 26.2970899 41.2705423
OS 26.29898982 41.26864238
OS 26.30025728 41.26610746
OS 26.30722704 41.25913516
OS 26.30976196 41.25787024
OS 26.31166442 41.25596778
OS 26.31293188 41.25343286
OS 26.31990164 41.2464631
OS 26.32243656 41.24519564
OS 26.32560394 41.2407608
OS 26.3313037 41.2350585
OS 26.33383862 41.23379104
OS 26.33700854 41.22935366
OS 26.3439783 41.22238644
OS 26.34651322 41.22111898
OS 26.3496806 41.21668414
OS 26.3553829 41.21098184
OS 26.35791782 41.20971438
OS 26.35981774 41.20781192
OS 26.3610852 41.205277
OS 26.3680575 41.19830724
OS 26.37058988 41.19703978
OS 26.37249234 41.19513986
OS 26.3737598 41.19260494
OS 26.38072956 41.18563518
OS 26.38326448 41.18436772
OS 26.38643186 41.17993288
OS 26.39213416 41.17422804
OS 26.39466654 41.17296058
OS 26.396569 41.17106066
OS 26.39783646 41.16852574
OS 26.39973638 41.1653609
OS 26.4022713 41.16409344
OS 26.41621082 41.15522122
OS 26.45993184 41.1533213
OS 26.4675366 41.15205384
OS 26.4846435 41.15141884
OS 26.48844588 41.1526863
OS 26.4973181 41.15141884
OS 27.10940222 41.1526863
OS 27.11257214 41.15585622
OS 27.11510706 41.16599082
OS 27.11447206 41.2819469
OS 27.11510706 41.29271904
OS 27.1138396 41.29651888
OS 27.11447206 41.31869816
OS 27.1132046 41.32630038
OS 27.11193714 41.34404482
OS 27.11066968 41.36051672
OS 27.11003722 41.36495156
OS 27.11130468 41.36875394
OS 27.11003722 41.37382378
OS 27.10876976 41.37762616
OS 27.10307 41.38459592
OS 27.10053508 41.38713084
OS 27.09419778 41.38966576
OS 27.05300914 41.39156568
OS 27.03590478 41.3934656
OS 27.02133026 41.39283314
OS 26.67790194 41.3941006
OS 26.6031345 41.39536806
OS 26.56891562 41.39663552
OS 26.54103658 41.39790298
OS 26.53596928 41.39917044
OS 26.52963198 41.40170536
OS 26.52139476 41.40487274
OS 26.51632492 41.40613766
OS 26.5080877 41.4105725
OS 26.50682278 41.41564234
OS 26.50745524 41.9637337
OS 26.50682278 41.97830822
OS 26.5080877 41.98210806
OS 26.50935516 41.9871779
OS 26.51062262 42.02012678
OS 26.51632492 42.02709654
OS 26.52266222 42.03343384
OS 26.53279936 42.03596876
OS 26.56575078 42.03723368
OS 26.56955062 42.03850114
OS 26.5904599 42.03786868
OS 26.93262076 42.03913614
OS 27.0073882 42.0404036
OS 27.0606139 42.04420598
OS 27.06568374 42.04547344
OS 27.07645588 42.04864082
OS 27.08152572 42.04990828
OS 27.09419778 42.05117574
OS 27.10940222 42.0524432
OS 27.11257214 42.05561058
OS 27.11510706 42.06574772
OS 27.11447206 42.1817038
OS 27.11510706 42.19374086
OS 27.1138396 42.19754324
OS 27.11447206 42.21971998
OS 27.1132046 42.22605728
OS 27.11066968 42.26153854
OS 27.11003722 42.26597592
OS 27.11130468 42.26977576
OS 27.11003722 42.2748456
OS 27.10876976 42.27738052
OS 27.10307 42.28435028
OS 27.09926762 42.28815266
OS 27.0903954 42.29068758
OS 27.08152572 42.28942012
OS 27.07772334 42.29068758
OS 27.04667692 42.2925875
OS 27.03907216 42.29385496
OS 27.03336986 42.29448996
OE
OB 28.02816848 42.29448996 H
OS 28.0243661 42.2932225
OS 28.01486142 42.29132004
OS 27.99838952 42.29005512
OS 27.99395214 42.28815266
OS 27.99141976 42.28561774
OS 27.98888484 42.28435028
OS 27.98001262 42.27801552
OS 27.97367532 42.27041076
OS 27.96797302 42.26597592
OS 27.96670556 42.263441
OS 27.9597358 42.25647124
OS 27.95720088 42.25520378
OS 27.95530096 42.25330132
OS 27.9540335 42.2507664
OS 27.9483312 42.24506664
OS 27.94579882 42.24379918
OS 27.9426289 42.2406318
OS 27.94136144 42.23809688
OS 27.93565914 42.23239458
OS 27.93312422 42.23112712
OS 27.9312243 42.22922466
OS 27.92995684 42.22668974
OS 27.92298708 42.21971998
OS 27.92045216 42.21845252
OS 27.9185497 42.2165526
OS 27.91728224 42.21401768
OS 27.91157994 42.20831538
OS 27.90904502 42.20704792
OS 27.9071451 42.20514546
OS 27.90587764 42.20261308
OS 27.89890788 42.19564078
OS 27.89637296 42.19437332
OS 27.8944705 42.1924734
OS 27.89320558 42.18993848
OS 27.88750074 42.18423872
OS 27.88496836 42.18297126
OS 27.88180098 42.17980388
OS 27.88053352 42.17726896
OS 27.87483122 42.17156412
OS 27.8722963 42.17029666
OS 27.87039384 42.16839674
OS 27.86912892 42.16586182
OS 27.86215662 42.15889206
OS 27.8596217 42.1576246
OS 27.85772178 42.15572468
OS 27.85645432 42.15318976
OS 27.85075202 42.14748746
OS 27.8482171 42.14622
OS 27.84631718 42.14431754
OS 27.84504972 42.14178262
OS 27.83807742 42.13481286
OS 27.83554504 42.1335454
OS 27.83364258 42.13164548
OS 27.83237512 42.12911056
OS 27.82667536 42.1234108
OS 27.82414044 42.12214334
OS 27.82097306 42.11897342
OS 27.8197056 42.1164385
OS 27.8140033 42.1107362
OS 27.81146838 42.10946874
OS 27.80956592 42.10756882
OS 27.80829846 42.1050339
OS 27.8013287 42.09806414
OS 27.79879378 42.09679668
OS 27.79689386 42.09489422
OS 27.7956264 42.0923593
OS 27.78865664 42.08538954
OS 27.78612172 42.08412208
OS 27.77661704 42.07081502
OS 27.77978442 42.06511526
OS 27.78865664 42.0638478
OS 27.79816132 42.06321534
OS 27.84441472 42.0638478
OS 27.8482171 42.06258034
OS 27.86469154 42.0638478
OS 27.91221494 42.06194788
OS 27.92235208 42.06321534
OS 27.925522 42.0638478
OS 27.92932184 42.06258034
OS 27.94199644 42.06131288
OS 27.97050794 42.05941296
OS 27.9774777 42.05497812
OS 27.98571492 42.0467409
OS 27.98698238 42.04167106
OS 27.98888484 42.00681972
OS 27.9901523 42.00175242
OS 27.99078476 41.98971282
OS 27.9895173 41.98591044
OS 27.99078476 41.9630987
OS 27.9895173 41.95929632
OS 27.99078476 41.95042664
OS 27.9901523 41.83574056
OS 27.99078476 41.81990112
OS 27.9895173 41.81609874
OS 27.99078476 41.79582192
OS 27.98824984 41.78948462
OS 27.98634992 41.75336836
OS 27.98001262 41.74323122
OS 27.97494278 41.73562646
OS 27.97240786 41.734359
OS 27.96227072 41.7280217
OS 27.9533985 41.72548932
OS 27.94643128 41.72612178
OS 27.92361954 41.72485432
OS 27.9185497 41.72358686
OS 27.90397772 41.7229544
OS 27.90017534 41.72422186
OS 27.88750074 41.7229544
OS 27.62834708 41.72358686
OS 27.61250764 41.7229544
OS 27.60617034 41.72548932
OS 27.58272614 41.72612178
OS 27.57575638 41.72548932
OS 27.571954 41.72675424
OS 27.56942162 41.7280217
OS 27.56181686 41.73309154
OS 27.55928194 41.734359
OS 27.55357964 41.73879384
OS 27.55231218 41.74132876
OS 27.54597488 41.75020098
OS 27.5421725 41.75907066
OS 27.54090504 41.78314732
OS 27.53963758 41.79835684
OS 27.53520274 41.80279168
OS 27.5301329 41.80152422
OS 27.52759798 41.7989893
OS 27.52506814 41.79772184
OS 27.50985862 41.78251486
OS 27.5073237 41.7812474
OS 27.50542378 41.77934748
OS 27.50415632 41.77681256
OS 27.49718656 41.7698428
OS 27.49465164 41.76857534
OS 27.48831434 41.76097312
OS 27.4832445 41.75590328
OS 27.48071212 41.75463582
OS 27.4775422 41.75020098
OS 27.47310736 41.74576614
OS 27.47057244 41.74449868
OS 27.46740506 41.7400613
OS 27.46170276 41.734359
OS 27.45916784 41.73309154
OS 27.45726792 41.73119162
OS 27.45600046 41.7286567
OS 27.4490307 41.72168694
OS 27.44649578 41.72041948
OS 27.44459586 41.71851702
OS 27.4433284 41.7159821
OS 27.43635864 41.70901234
OS 27.43445618 41.70837988
OS 27.43318872 41.70584496
OS 27.4249515 41.69761028
OS 27.42241658 41.69634282
OS 27.4192492 41.6931729
OS 27.41798174 41.69064052
OS 27.41101198 41.68366822
OS 27.40910952 41.68303576
OS 27.40784206 41.68050084
OS 27.39960738 41.67226362
OS 27.39707246 41.67099616
OS 27.39390508 41.66656132
OS 27.38820278 41.66085648
OS 27.38566786 41.65958902
OS 27.3837654 41.6576891
OS 27.38249794 41.65515418
OS 27.37552818 41.64818442
OS 27.37299326 41.64691696
OS 27.37109334 41.64501958
OS 27.36982588 41.64248466
OS 27.36158866 41.63424744
OS 27.35968874 41.63361244
OS 27.35842128 41.63107752
OS 27.35018152 41.6228403
OS 27.34764914 41.62157284
OS 27.34448176 41.617138
OS 27.34004692 41.61270316
OS 27.337512 41.6114357
OS 27.33561208 41.60953324
OS 27.33434462 41.60699832
OS 27.32737232 41.60002856
OS 27.32483994 41.5987611
OS 27.32293748 41.59686118
OS 27.32167002 41.59432626
OS 27.31470026 41.5873565
OS 27.31216534 41.58608904
OS 27.30899796 41.5816542
OS 27.3020282 41.57468444
OS 27.29949328 41.57341698
OS 27.29759082 41.57151706
OS 27.28872114 41.5525077
OS 27.2899886 41.54236802
OS 27.28872114 41.53856564
OS 27.28682122 41.50878668
OS 27.28555376 41.50118446
OS 27.2849213 41.49421216
OS 27.28618876 41.49041232
OS 27.28555376 41.46696558
OS 27.28618876 41.45366106
OS 27.2849213 41.44985868
OS 27.28555376 41.43275178
OS 27.2849213 41.1647259
OS 27.28618876 41.16092352
OS 27.28745368 41.15585622
OS 27.29062106 41.1526863
OS 27.2956909 41.15141884
OS 27.53520274 41.1526863
OS 27.53837012 41.15585622
OS 27.54090504 41.16599082
OS 27.54154004 41.39093322
OS 27.54090504 41.4004379
OS 27.5421725 41.40423774
OS 27.54343996 41.4587309
OS 27.54470742 41.46253328
OS 27.54597488 41.47647026
OS 27.55104472 41.4878774
OS 27.55231218 41.4929447
OS 27.5548471 41.499282
OS 27.55801448 41.50245192
OS 27.56308432 41.50371684
OS 27.57512392 41.50815422
OS 27.58145868 41.51068914
OS 27.58652852 41.5119566
OS 27.61440756 41.51322406
OS 27.64988882 41.51448898
OS 27.72339134 41.51575644
OS 27.807666 41.51639144
OS 27.81146838 41.51512398
OS 27.91664978 41.51385652
OS 27.92045216 41.51258906
OS 27.94959612 41.5113216
OS 27.96353818 41.5049843
OS 27.9717754 41.50308438
OS 27.97621024 41.499917
OS 27.97938016 41.4929447
OS 27.98128008 41.48470748
OS 27.98698238 41.47140042
OS 27.98888484 41.43275178
OS 27.9901523 41.382061
OS 27.99141976 41.16155852
OS 27.99268468 41.15648868
OS 27.99648706 41.1526863
OS 28.0015569 41.15141884
OS 28.24106874 41.1526863
OS 28.24423866 41.15585622
OS 28.24550612 41.16092352
OS 28.24613858 41.23759088
OS 28.24550612 41.24202826
OS 28.24677358 41.24583064
OS 28.24550612 41.25470032
OS 28.24677358 41.3053911
OS 28.24677358 41.96690108
OS 28.24677358 41.96816854
OS 28.24550612 41.9808406
OS 28.24423866 42.06701518
OS 28.2429712 42.07081502
OS 28.24170374 42.1050339
OS 28.2366339 42.1164385
OS 28.23536644 42.12150834
OS 28.23283152 42.1278431
OS 28.23156406 42.13037802
OS 28.2252293 42.13671532
OS 28.22396184 42.1392477
OS 28.218257 42.14622
OS 28.21128724 42.1519223
OS 28.20558494 42.15889206
OS 28.19861518 42.16459436
OS 28.19291288 42.17156412
OS 28.18594312 42.17726896
OS 28.18024082 42.18423872
OS 28.1777059 42.18550364
OS 28.17327106 42.18993848
OS 28.1720036 42.1924734
OS 28.16756876 42.19690824
OS 28.16503384 42.1981757
OS 28.16059646 42.20261308
OS 28.159329 42.20514546
OS 28.15616162 42.20831538
OS 28.1536267 42.20958284
OS 28.14919186 42.21401768
OS 28.1479244 42.2165526
OS 28.14348956 42.22098744
OS 28.14095464 42.2222549
OS 28.1365198 42.22668974
OS 28.13525234 42.22922466
OS 28.13081496 42.23366204
OS 28.12828004 42.2349295
OS 28.12384774 42.23936434
OS 28.12258028 42.24189926
OS 28.1194129 42.24506664
OS 28.11687798 42.24633156
OS 28.11244314 42.2507664
OS 28.11117568 42.25330132
OS 28.1067383 42.2577387
OS 28.10420338 42.25900362
OS 28.09976854 42.263441
OS 28.09850108 42.26597592
OS 28.09406624 42.27041076
OS 28.09153132 42.27167822
OS 28.08836394 42.2748456
OS 28.08709648 42.27738052
OS 28.0826591 42.28181536
OS 28.08012672 42.28308282
OS 28.0712545 42.28942012
OS 28.0661872 42.29068758
OS 28.0484453 42.29195504
OS 28.04464292 42.2932225
OS 28.02816848 42.29448996
OE
OB 27.6137751 44.24100118 H
OS 27.60997272 44.23973372
OS 27.60363542 44.23593388
OS 27.6017355 44.22896158
OS 27.6011005 42.54160656
OS 27.6017355 42.52576458
OS 27.60046804 42.5219622
OS 27.6017355 42.50295284
OS 27.60046804 42.49915046
OS 27.6017355 42.47760872
OS 27.59920058 42.47127142
OS 27.59856558 42.4630342
OS 27.59920058 42.45606444
OS 27.59793312 42.45226206
OS 27.59666566 42.4332527
OS 27.59032836 42.42438302
OS 27.58652852 42.41804826
OS 27.5846286 42.4161458
OS 27.58209368 42.41487834
OS 27.57639138 42.40917604
OS 27.57512392 42.40664112
OS 27.57322146 42.4047412
OS 27.57068654 42.40347374
OS 27.56498424 42.39777144
OS 27.56371678 42.39523652
OS 27.5605494 42.3920666
OS 27.55801448 42.39080168
OS 27.55231218 42.38509684
OS 27.55104472 42.38256192
OS 27.54787734 42.37939454
OS 27.54534242 42.37812708
OS 27.54090504 42.37369224
OS 27.53963758 42.37115732
OS 27.5364702 42.36798994
OS 27.53393528 42.36672248
OS 27.52823298 42.36102018
OS 27.52696806 42.35848526
OS 27.52380068 42.35531788
OS 27.52126576 42.35405042
OS 27.51556092 42.34834812
OS 27.514296 42.3458132
OS 27.51112608 42.34264582
OS 27.50478878 42.33884344
OS 27.49845402 42.33250614
OS 27.4895818 42.32997122
OS 27.4832445 42.32616884
OS 27.4781772 42.32110154
OS 27.47564228 42.31983408
OS 27.46867252 42.31413178
OS 27.46297022 42.30715948
OS 27.45600046 42.30145972
OS 27.454733 42.2989248
OS 27.4490307 42.2932225
OS 27.44649578 42.29195504
OS 27.4433284 42.28878766
OS 27.44206094 42.28625274
OS 27.43762356 42.28181536
OS 27.43509118 42.2805479
OS 27.43192126 42.27738052
OS 27.4306538 42.2748456
OS 27.4249515 42.2691433
OS 27.42241658 42.26787584
OS 27.4192492 42.26470846
OS 27.41798174 42.26217354
OS 27.4135469 42.2577387
OS 27.41101198 42.25647124
OS 27.40784206 42.25330132
OS 27.40657714 42.2507664
OS 27.40087484 42.24506664
OS 27.39833992 42.24379918
OS 27.39517254 42.2406318
OS 27.39390508 42.23809688
OS 27.38947024 42.23366204
OS 27.38693532 42.23239458
OS 27.3837654 42.22922466
OS 27.38249794 42.22668974
OS 27.37679564 42.22098744
OS 27.37426072 42.21971998
OS 27.37109334 42.2165526
OS 27.36982588 42.21401768
OS 27.36539104 42.20958284
OS 27.36285612 42.20831538
OS 27.35842128 42.203878
OS 27.35715382 42.20134562
OS 27.35271644 42.19690824
OS 27.35018152 42.19564078
OS 27.34701668 42.1924734
OS 27.34574922 42.18993848
OS 27.34004692 42.18423872
OS 27.337512 42.18297126
OS 27.33434462 42.17980388
OS 27.33307716 42.17726896
OS 27.32737232 42.17156412
OS 27.32483994 42.17029666
OS 27.32167002 42.16712928
OS 27.32040256 42.16459436
OS 27.31596772 42.16015952
OS 27.3134328 42.15889206
OS 27.31026542 42.15572468
OS 27.30899796 42.15318976
OS 27.30456058 42.14875238
OS 27.3020282 42.14748746
OS 27.29759082 42.14305008
OS 27.29632336 42.14051516
OS 27.29188852 42.13608032
OS 27.2893536 42.13481286
OS 27.28618876 42.13164548
OS 27.2849213 42.12911056
OS 27.279219 42.1234108
OS 27.27668408 42.12214334
OS 27.27351416 42.11897342
OS 27.2722467 42.1164385
OS 27.2665444 42.1107362
OS 27.26400948 42.10946874
OS 27.26210956 42.10756882
OS 27.2608421 42.1050339
OS 27.2551398 42.0993316
OS 27.25260488 42.09806414
OS 27.24817004 42.09362676
OS 27.24690258 42.09109438
OS 27.24373266 42.08792446
OS 27.24119774 42.086657
OS 27.2367629 42.08222216
OS 27.23549544 42.07968724
OS 27.2310606 42.0752524
OS 27.22852568 42.07398494
OS 27.22536084 42.07081502
OS 27.22409338 42.06828264
OS 27.21838854 42.06258034
OS 27.21585362 42.06131288
OS 27.21268624 42.0581455
OS 27.21141878 42.05561058
OS 27.20571648 42.04990828
OS 27.20318156 42.04864082
OS 27.20128164 42.0467409
OS 27.20001418 42.04420598
OS 27.19430934 42.03850114
OS 27.19177696 42.03723368
OS 27.18733958 42.03279884
OS 27.18607212 42.03026392
OS 27.18290474 42.02709654
OS 27.18036982 42.02582908
OS 27.17593498 42.02139424
OS 27.17466752 42.01885932
OS 27.17023268 42.01442448
OS 27.16769776 42.01315702
OS 27.16453038 42.0099871
OS 27.16326292 42.00745218
OS 27.15756062 42.00175242
OS 27.1550257 42.00048496
OS 27.15185832 41.99731758
OS 27.15059086 41.99478266
OS 27.14615602 41.99034782
OS 27.1436211 41.98908036
OS 27.13918372 41.98464298
OS 27.13791626 41.98210806
OS 27.13348142 41.97767322
OS 27.1309465 41.97640576
OS 27.12777912 41.97323838
OS 27.12651166 41.97070346
OS 27.12080936 41.96500116
OS 27.11827444 41.9637337
OS 27.11637198 41.96183124
OS 27.11510706 41.95929632
OS 27.10940222 41.95359402
OS 27.10686984 41.95232656
OS 27.10370246 41.94915918
OS 27.102435 41.94662426
OS 27.0967327 41.9409245
OS 27.09419778 41.93965704
OS 27.0910304 41.93648712
OS 27.08976294 41.93395474
OS 27.0840581 41.9282499
OS 27.08152572 41.92698244
OS 27.07962326 41.92508252
OS 27.0783558 41.9225476
OS 27.0726535 41.9168453
OS 27.07011858 41.91557784
OS 27.0669512 41.91241046
OS 27.06568374 41.90987554
OS 27.05998144 41.9041707
OS 27.05744652 41.90290578
OS 27.0542766 41.89973586
OS 27.05300914 41.89720094
OS 27.04730938 41.89149864
OS 27.04477446 41.89023118
OS 27.04287454 41.88833126
OS 27.04160708 41.88579634
OS 27.03907216 41.88326396
OS 27.0378047 41.88072904
OS 27.03273486 41.8756592
OS 27.0314674 41.87312428
OS 27.02893248 41.86678952
OS 27.02766502 41.86171968
OS 27.02259772 41.85031254
OS 27.02133026 41.83764048
OS 27.0194278 41.80025676
OS 27.01816034 41.75717074
OS 27.01752788 41.72485432
OS 27.01879534 41.72105194
OS 27.0200628 41.66022402
OS 27.02133026 41.65642164
OS 27.02259772 41.63107752
OS 27.02766502 41.61967292
OS 27.02893248 41.61460308
OS 27.03526978 41.60319848
OS 27.04033962 41.59812864
OS 27.04160708 41.59559372
OS 27.04604192 41.58989142
OS 27.0485743 41.58862396
OS 27.05554406 41.5816542
OS 27.05617906 41.57975428
OS 27.05871398 41.57848682
OS 27.06378128 41.57341698
OS 27.0663162 41.57214952
OS 27.06885112 41.5696146
OS 27.07392096 41.56834968
OS 27.07645588 41.57088206
OS 27.0789908 41.57214952
OS 27.08279064 41.5759519
OS 27.08532556 41.57721936
OS 27.08976294 41.5816542
OS 27.0910304 41.58418912
OS 27.09546524 41.58862396
OS 27.09800016 41.58989142
OS 27.102435 41.59432626
OS 27.10370246 41.59686118
OS 27.10813476 41.60129602
OS 27.11066968 41.60256348
OS 27.11510706 41.60699832
OS 27.11637198 41.60953324
OS 27.1195419 41.61270316
OS 27.12207682 41.61397062
OS 27.12651166 41.61840546
OS 27.12777912 41.62094038
OS 27.13221396 41.62537522
OS 27.13474888 41.62664268
OS 27.13918372 41.63107752
OS 27.14045118 41.63361244
OS 27.14488856 41.63804728
OS 27.14742348 41.63931474
OS 27.15059086 41.64248466
OS 27.15185832 41.64501958
OS 27.15629316 41.64945188
OS 27.15882808 41.65071934
OS 27.16326292 41.65515418
OS 27.16453038 41.6576891
OS 27.16896522 41.66212394
OS 27.17150014 41.6633914
OS 27.17593498 41.66782878
OS 27.17720244 41.67036116
OS 27.18036982 41.67353108
OS 27.18290474 41.67479854
OS 27.1898745 41.68050084
OS 27.19304442 41.68366822
OS 27.19937918 41.68620314
OS 27.2076164 41.68937306
OS 27.2145887 41.69634282
OS 27.21712108 41.69761028
OS 27.22409338 41.70331258
OS 27.22536084 41.70584496
OS 27.23232806 41.71281472
OS 27.23486298 41.71408218
OS 27.23803036 41.71851702
OS 27.24373266 41.72422186
OS 27.24626758 41.72548932
OS 27.24817004 41.72738924
OS 27.24943496 41.72992416
OS 27.2551398 41.73562646
OS 27.25767472 41.73689392
OS 27.25957464 41.73879384
OS 27.2608421 41.74132876
OS 27.26781186 41.74829852
OS 27.27034678 41.74956598
OS 27.2722467 41.75146844
OS 27.27351416 41.75400336
OS 27.279219 41.75970566
OS 27.28175138 41.76097312
OS 27.28365384 41.76287304
OS 27.2849213 41.76540542
OS 27.29188852 41.77237518
OS 27.29442344 41.77364264
OS 27.29759082 41.77808002
OS 27.30456058 41.78504978
OS 27.30646304 41.78568224
OS 27.3077305 41.78821716
OS 27.31596772 41.79645438
OS 27.31850264 41.79772184
OS 27.32040256 41.7996243
OS 27.32167002 41.80215922
OS 27.32863978 41.80912898
OS 27.3311747 41.81039644
OS 27.33307716 41.81229636
OS 27.33434462 41.81483128
OS 27.34131438 41.82180104
OS 27.3438493 41.8230685
OS 27.35018152 41.83067072
OS 27.3539839 41.8344731
OS 27.35651882 41.83574056
OS 27.36285612 41.84334278
OS 27.36539104 41.8458777
OS 27.36729096 41.8465127
OS 27.36855842 41.84904508
OS 27.37679564 41.85728484
OS 27.37933056 41.85854976
OS 27.38123302 41.86045222
OS 27.38249794 41.86298714
OS 27.38947024 41.8699569
OS 27.39200516 41.87122436
OS 27.39390508 41.87312428
OS 27.39517254 41.8756592
OS 27.4021423 41.88262896
OS 27.40467722 41.88389642
OS 27.40784206 41.88833126
OS 27.41481436 41.89530102
OS 27.41734674 41.89656848
OS 27.42051666 41.90100332
OS 27.42621896 41.90670562
OS 27.42811888 41.90734062
OS 27.42938634 41.90987554
OS 27.43762356 41.91811276
OS 27.44015848 41.91938022
OS 27.44206094 41.92128014
OS 27.4433284 41.92381506
OS 27.45029816 41.93078482
OS 27.45283308 41.93205228
OS 27.454733 41.93395474
OS 27.45600046 41.93648712
OS 27.46297022 41.94345942
OS 27.46550514 41.94472688
OS 27.46867252 41.94915918
OS 27.47437482 41.95486148
OS 27.47690974 41.95612894
OS 27.47880966 41.9580314
OS 27.48007712 41.96056378
OS 27.48704688 41.96753608
OS 27.4895818 41.96880354
OS 27.4959191 41.97640576
OS 27.49845402 41.97894068
OS 27.50098894 41.98020814
OS 27.50288886 41.98210806
OS 27.50415632 41.98464298
OS 27.51112608 41.99161274
OS 27.513661 41.9928802
OS 27.51556092 41.99478266
OS 27.51682838 41.99731758
OS 27.52380068 42.00428734
OS 27.52633306 42.00555226
OS 27.52950044 42.0099871
OS 27.53520274 42.0156894
OS 27.53773766 42.01695686
OS 27.53963758 42.01885932
OS 27.54090504 42.02139424
OS 27.54787734 42.028364
OS 27.55040972 42.02963146
OS 27.55357964 42.0340663
OS 27.55928194 42.0397686
OS 27.56181686 42.04103606
OS 27.56371678 42.04293852
OS 27.56498424 42.04547344
OS 27.57068654 42.05117574
OS 27.57322146 42.0524432
OS 27.57639138 42.05561058
OS 27.57765884 42.0581455
OS 27.5846286 42.06511526
OS 27.58652852 42.06574772
OS 27.58779344 42.06828264
OS 27.59603066 42.07651986
OS 27.59856558 42.07778732
OS 27.60046804 42.07968724
OS 27.6017355 42.08222216
OS 27.6074378 42.08792446
OS 27.60997272 42.08919192
OS 27.61187264 42.09109438
OS 27.6131401 42.09362676
OS 27.62010986 42.10059906
OS 27.62264478 42.10186652
OS 27.62454724 42.10376644
OS 27.6258147 42.10630136
OS 27.631517 42.11200366
OS 27.63405192 42.11327112
OS 27.6372193 42.1164385
OS 27.63848676 42.11897342
OS 27.64545652 42.12594318
OS 27.6479889 42.1272081
OS 27.64988882 42.12911056
OS 27.65115628 42.13164548
OS 27.65812858 42.13861524
OS 27.6600285 42.1392477
OS 27.66129596 42.14178262
OS 27.66826572 42.14875238
OS 27.67080064 42.15001984
OS 27.67270056 42.1519223
OS 27.67396802 42.15445722
OS 27.68094032 42.16142698
OS 27.6834727 42.16269444
OS 27.68537516 42.16459436
OS 27.68664262 42.16712928
OS 27.69361238 42.17409904
OS 27.6961473 42.1753665
OS 27.69804722 42.17726896
OS 27.69931468 42.17980388
OS 27.70501698 42.18550364
OS 27.70754936 42.1867711
OS 27.70945182 42.18867102
OS 27.71071928 42.19120594
OS 27.71768904 42.1981757
OS 27.72022396 42.19944316
OS 27.72212388 42.20134562
OS 27.72339134 42.203878
OS 27.7303611 42.2108503
OS 27.73289602 42.21211776
OS 27.73606594 42.2165526
OS 27.74176824 42.2222549
OS 27.74430316 42.22352236
OS 27.74620308 42.22542228
OS 27.74747054 42.2279572
OS 27.7544403 42.2349295
OS 27.75697522 42.23619442
OS 27.75887514 42.23809688
OS 27.7601426 42.2406318
OS 27.76584744 42.24633156
OS 27.76837982 42.24759902
OS 27.77027974 42.24949894
OS 27.7715472 42.25203386
OS 27.77851696 42.25900362
OS 27.78105188 42.26027108
OS 27.7829518 42.26217354
OS 27.78421926 42.26470846
OS 27.79119156 42.27167822
OS 27.79372394 42.27294568
OS 27.80006124 42.2805479
OS 27.80259616 42.28308282
OS 27.80513108 42.28435028
OS 27.807031 42.28625274
OS 27.80829846 42.28878766
OS 27.81526822 42.29575742
OS 27.81780314 42.29702488
OS 27.8197056 42.2989248
OS 27.82097306 42.30145972
OS 27.82667536 42.30842694
OS 27.8298402 42.31159686
OS 27.83237512 42.31793162
OS 27.83554504 42.32616884
OS 27.84061234 42.3337736
OS 27.84378226 42.34074336
OS 27.84631718 42.34708066
OS 27.84948456 42.35531788
OS 27.85265194 42.36608748
OS 27.8545544 42.40347374
OS 27.85582186 42.43768754
OS 27.85645432 42.44845968
OS 27.85645432 42.44972714
OS 27.85582186 43.99261712
OS 27.85645432 44.01099402
OS 27.85518686 44.0147964
OS 27.8539194 44.02366862
OS 27.85201948 44.06358472
OS 27.84631718 44.0730894
OS 27.84504972 44.07562432
OS 27.84061234 44.08132662
OS 27.83807742 44.08259408
OS 27.83237512 44.08829892
OS 27.83110766 44.0908313
OS 27.82920774 44.09273376
OS 27.82667536 44.09400122
OS 27.81843814 44.10223844
OS 27.81717068 44.10477082
OS 27.81273584 44.1079382
OS 27.807031 44.11364304
OS 27.80576354 44.11617542
OS 27.80386362 44.11807788
OS 27.8013287 44.11934534
OS 27.79435894 44.1263151
OS 27.79309148 44.12885002
OS 27.78865664 44.1320174
OS 27.7829518 44.1377197
OS 27.78168688 44.14025462
OS 27.77978442 44.14215708
OS 27.7772495 44.14342454
OS 27.77027974 44.1503943
OS 27.76901228 44.15292922
OS 27.76141006 44.15926398
OS 27.75761022 44.16306636
OS 27.75634276 44.16559874
OS 27.748738 44.17193604
OS 27.74620308 44.17447096
OS 27.74493562 44.17700588
OS 27.7430357 44.1789058
OS 27.74050078 44.18017326
OS 27.73353102 44.18714302
OS 27.73226356 44.18967794
OS 27.72782618 44.19284532
OS 27.72212388 44.19855016
OS 27.72085642 44.20108508
OS 27.7189565 44.202985
OS 27.71642158 44.20425246
OS 27.70945182 44.21122222
OS 27.70818436 44.21375714
OS 27.70628444 44.21565706
OS 27.70374952 44.21692452
OS 27.69677976 44.22262936
OS 27.69487984 44.22452674
OS 27.69234492 44.2257942
OS 27.68600762 44.22832912
OS 27.67396802 44.23276396
OS 27.66699826 44.23593388
OS 27.65876104 44.2378338
OS 27.65242374 44.23910126
OS 27.6372193 44.24036872
OS 27.6137751 44.24100118
OE
OB 29.00142536 42.29448996 H
OS 28.41215044 42.2932225
OS 28.4064456 42.28878766
OS 28.40517814 42.28371782
OS 28.4064456 41.15585622
OS 28.40961552 41.1526863
OS 28.41468282 41.15141884
OS 28.58386206 41.15205384
OS 28.6009715 41.15141884
OS 28.60477388 41.1526863
OS 28.6174434 41.15395376
OS 28.65229474 41.15585622
OS 28.65673212 41.15775614
OS 28.6662368 41.16725828
OS 28.66750172 41.17232812
OS 28.66940164 41.21098184
OS 28.67193656 41.23125612
OS 28.67130156 41.2521654
OS 28.67256902 41.25596778
OS 28.67130156 41.25977016
OS 28.67193656 41.28448182
OS 28.6706691 41.37065386
OS 28.66940164 41.38713084
OS 28.66813418 41.40867258
OS 28.66686672 41.42387956
OS 28.6656018 41.4289494
OS 28.66306688 41.4352867
OS 28.6598995 41.44605884
OS 28.66116696 41.4587309
OS 28.67130156 41.48027264
OS 28.67320402 41.49738208
OS 28.6763714 41.50181692
OS 28.68334116 41.50371684
OS 28.81323676 41.50308438
OS 28.82907874 41.50371684
OS 28.83288112 41.50245192
OS 28.85442286 41.50371684
OS 28.86075762 41.50118446
OS 28.89687642 41.499282
OS 28.90448118 41.49421216
OS 28.90764602 41.49104478
OS 28.91018094 41.48977732
OS 28.91335086 41.48660994
OS 28.91588324 41.47773772
OS 28.92095308 41.46886804
OS 28.92729038 41.46253328
OS 28.92855784 41.45999836
OS 28.93426014 41.4530286
OS 28.93742752 41.44985868
OS 28.93996244 41.44352392
OS 28.9412299 41.43845408
OS 28.95010212 41.42451456
OS 28.95453696 41.41247496
OS 28.95770688 41.40803758
OS 28.96277418 41.40297028
OS 28.96404164 41.4004379
OS 28.96974394 41.3934656
OS 28.97417878 41.38903076
OS 28.97988108 41.37318878
OS 28.98304846 41.3700214
OS 28.98431592 41.36748648
OS 28.9881183 41.3586168
OS 28.99128822 41.35037704
OS 28.99952544 41.34214236
OS 29.00332782 41.3358076
OS 29.00966258 41.3294703
OS 29.01346496 41.32059808
OS 29.01473242 41.31552824
OS 29.02106972 41.30665856
OS 29.02233718 41.30412364
OS 29.0248721 41.29778634
OS 29.02803694 41.28954912
OS 29.03310678 41.2819469
OS 29.03627416 41.27497714
OS 29.03944154 41.26673992
OS 29.04261146 41.26230508
OS 29.04894622 41.25596778
OS 29.0527486 41.24963048
OS 29.0590859 41.24329572
OS 29.06352074 41.23125612
OS 29.06985804 41.22111898
OS 29.07302542 41.21288176
OS 29.07936272 41.20147716
OS 29.08443256 41.19640732
OS 29.08570002 41.1938724
OS 29.09139978 41.18690264
OS 29.09456716 41.18373272
OS 29.09583462 41.18120034
OS 29.09836954 41.17486304
OS 29.099637 41.1697932
OS 29.10407184 41.16409344
OS 29.10660676 41.16282598
OS 29.10914168 41.16029106
OS 29.1116766 41.1590236
OS 29.11421152 41.15648868
OS 29.12308374 41.15522122
OS 29.16046492 41.1533213
OS 29.16806968 41.15205384
OS 29.18644658 41.15141884
OS 29.19024896 41.1526863
OS 29.19531626 41.15141884
OS 29.38540732 41.1526863
OS 29.3873047 41.15458876
OS 29.38857216 41.15965606
OS 29.3873047 41.1697932
OS 29.38096994 41.17866542
OS 29.37843756 41.18500018
OS 29.37526764 41.1932374
OS 29.37336772 41.19513986
OS 29.37210026 41.19767478
OS 29.36703042 41.20274462
OS 29.36576296 41.205277
OS 29.36006066 41.2122493
OS 29.35562582 41.21668414
OS 29.35118844 41.2287212
OS 29.34802106 41.23315604
OS 29.34421868 41.23695842
OS 29.34295122 41.23949334
OS 29.33724892 41.24773056
OS 29.335349 41.24836302
OS 29.334714 41.25026548
OS 29.33281408 41.25089794
OS 29.33154662 41.25343286
OS 29.3290117 41.25977016
OS 29.32584432 41.26800738
OS 29.3239444 41.2699073
OS 29.32267694 41.27244222
OS 29.32014202 41.27497714
OS 29.31443972 41.29081658
OS 29.30746996 41.29778634
OS 29.3062025 41.30032126
OS 29.29733028 41.3117284
OS 29.29479536 41.31426332
OS 29.29226298 41.32059808
OS 29.29099552 41.32566792
OS 29.2821233 41.33960744
OS 29.27768846 41.3516445
OS 29.27451854 41.35608188
OS 29.27198362 41.35734934
OS 29.2707187 41.35988172
OS 29.26818378 41.36241664
OS 29.26438394 41.36875394
OS 29.25804664 41.37509124
OS 29.2536118 41.38713084
OS 29.2472745 41.39726798
OS 29.24410712 41.4055052
OS 29.2415722 41.41183996
OS 29.2358699 41.41880972
OS 29.23269998 41.42197964
OS 29.2288976 41.4283144
OS 29.22256284 41.4346517
OS 29.22002792 41.440989
OS 29.216858 41.44922622
OS 29.21369062 41.45366106
OS 29.20862078 41.46126582
OS 29.20672086 41.46823304
OS 29.20418848 41.47457034
OS 29.19848618 41.48534248
OS 29.19595126 41.49421216
OS 29.19721872 41.51955882
OS 29.20355348 41.5284285
OS 29.2060884 41.53096342
OS 29.20988824 41.53729818
OS 29.21305816 41.5404681
OS 29.21495808 41.54110056
OS 29.21559054 41.54173556
OS 29.21876046 41.54490294
OS 29.22002792 41.54743786
OS 29.22573022 41.55314016
OS 29.22826514 41.55440762
OS 29.23143252 41.55757754
OS 29.23269998 41.56010992
OS 29.23840228 41.56581476
OS 29.2409372 41.56708222
OS 29.24283966 41.56898214
OS 29.24410712 41.57151706
OS 29.24980942 41.57721936
OS 29.25234434 41.57848682
OS 29.25551172 41.5816542
OS 29.25677918 41.58418912
OS 29.26248148 41.58989142
OS 29.2650164 41.59115888
OS 29.26691632 41.5930588
OS 29.26818378 41.59559372
OS 29.27388608 41.60129602
OS 29.276421 41.60256348
OS 29.27958838 41.60573086
OS 29.28085584 41.60826578
OS 29.28655814 41.61397062
OS 29.28909306 41.61523554
OS 29.29226298 41.61840546
OS 29.2935279 41.62094038
OS 29.29923274 41.62664268
OS 29.30176766 41.62791014
OS 29.30366758 41.62981006
OS 29.30493504 41.63234498
OS 29.31063734 41.63804728
OS 29.31317226 41.63931474
OS 29.31633964 41.64248466
OS 29.3176071 41.64501958
OS 29.32331194 41.65071934
OS 29.32584432 41.6519868
OS 29.3290117 41.65515418
OS 29.33027916 41.6576891
OS 29.334714 41.66212394
OS 29.33724892 41.6633914
OS 29.34168376 41.66782878
OS 29.34295122 41.67036116
OS 29.34865352 41.67733346
OS 29.35055598 41.67923338
OS 29.3530909 41.68557068
OS 29.35435836 41.69064052
OS 29.35942566 41.70204512
OS 29.36069312 41.70711242
OS 29.36259558 41.73689392
OS 29.3644955 41.77427764
OS 29.3651305 41.8230685
OS 29.3644955 41.8237035
OS 29.36576296 41.8275008
OS 29.3651305 41.98654544
OS 29.36576296 41.99605012
OS 29.3644955 41.9998525
OS 29.36322804 42.07334994
OS 29.36196058 42.07715232
OS 29.36006066 42.10693382
OS 29.35435836 42.12024088
OS 29.35118844 42.12847556
OS 29.3467536 42.13544786
OS 29.34295122 42.1392477
OS 29.34168376 42.14178262
OS 29.334714 42.14875238
OS 29.33217908 42.15001984
OS 29.33027916 42.1519223
OS 29.3290117 42.15445722
OS 29.32204448 42.16142698
OS 29.31950956 42.16269444
OS 29.3176071 42.16459436
OS 29.31633964 42.16712928
OS 29.29669782 42.1867711
OS 29.29479536 42.18740356
OS 29.2935279 42.18993848
OS 29.28529068 42.1981757
OS 29.28275576 42.19944316
OS 29.27958838 42.203878
OS 29.27388608 42.20958284
OS 29.27135116 42.2108503
OS 29.26945124 42.21275022
OS 29.26818378 42.21528514
OS 29.26121402 42.2222549
OS 29.2586791 42.22352236
OS 29.25677918 42.22542228
OS 29.25551172 42.2279572
OS 29.23713482 42.24633156
OS 29.23460244 42.24759902
OS 29.23269998 42.24949894
OS 29.23143252 42.25203386
OS 29.22446276 42.25900362
OS 29.22192784 42.26027108
OS 29.21559054 42.26787584
OS 29.21305816 42.27041076
OS 29.21052324 42.27167822
OS 29.20418848 42.27801552
OS 29.20165356 42.27928298
OS 29.19278134 42.28308282
OS 29.18454412 42.28625274
OS 29.17820936 42.28878766
OS 29.1706046 42.29005512
OS 29.14272556 42.29132004
OS 29.1053393 42.2932225
OS 29.00142536 42.29448996
OE
OB 25.69387292 42.2932225 H
OS 25.68373324 42.29195504
OS 25.68183332 42.29005512
OS 25.6792984 42.28371782
OS 25.68120086 42.1981757
OS 25.68246832 42.17156412
OS 25.68373324 42.15001984
OS 25.6850007 42.1398827
OS 25.68626816 42.13481286
OS 25.68753562 42.12847556
OS 25.68880308 42.12087588
OS 25.69070554 42.10376644
OS 25.691973 42.09489422
OS 25.69324046 42.0746174
OS 25.69640784 42.05624558
OS 25.69830776 42.04927328
OS 25.7033776 42.02899646
OS 25.70464506 42.0163244
OS 25.70591252 42.00238488
OS 25.70844744 41.99605012
OS 25.71224982 41.98210806
OS 25.71351728 41.97704076
OS 25.71604966 41.96183124
OS 25.71795212 41.9459918
OS 25.71921958 41.93965704
OS 25.72048704 41.9345872
OS 25.72492188 41.92001268
OS 25.72618934 41.91494284
OS 25.72872172 41.89720094
OS 25.73062164 41.88262896
OS 25.7318891 41.8762942
OS 25.73569148 41.86615452
OS 25.73759394 41.85918476
OS 25.74012632 41.84904508
OS 25.74139378 41.83637302
OS 25.74329624 41.8281358
OS 25.74773108 41.8173662
OS 25.75153346 41.80849398
OS 25.75280092 41.7996243
OS 25.75406838 41.79455446
OS 25.75723576 41.78631724
OS 25.76293806 41.77301018
OS 25.76547298 41.7641405
OS 25.76674044 41.75527082
OS 25.7743452 41.73879384
OS 25.77688012 41.72992416
OS 25.77941504 41.71851702
OS 25.7857498 41.70458004
OS 25.78828218 41.69570782
OS 25.78954964 41.69064052
OS 25.7914521 41.68240076
OS 25.79778686 41.66846124
OS 25.79968932 41.66275894
OS 25.80222424 41.65261926
OS 25.8034917 41.64501958
OS 25.80982646 41.6348799
OS 25.81299638 41.62664268
OS 25.81933114 41.61270316
OS 25.82503598 41.5993961
OS 25.8269359 41.58862396
OS 25.83010328 41.58038674
OS 25.8389755 41.56137738
OS 25.84911264 41.5398331
OS 25.85037756 41.53096342
OS 25.85228002 41.5239962
OS 25.85798232 41.51322406
OS 25.8617847 41.50435184
OS 25.92388008 41.37889362
OS 25.92768246 41.37255632
OS 25.93401976 41.36621902
OS 25.93528722 41.3636841
OS 25.94098952 41.35671434
OS 25.94288944 41.35481442
OS 25.9441569 41.3522795
OS 25.94922674 41.3408749
OS 25.95429658 41.33200522
OS 25.96063134 41.31806316
OS 25.96696864 41.30665856
OS 25.97203594 41.29525142
OS 25.97710578 41.28638174
OS 25.98344054 41.28004698
OS 25.984708 41.27751206
OS 25.99041284 41.2705423
OS 25.99358022 41.26737492
OS 25.99611514 41.26103762
OS 25.9973826 41.25596778
OS 26.00625228 41.24202826
OS 26.00751974 41.23695842
OS 26.01385704 41.22555382
OS 26.01892688 41.22048652
OS 26.02019434 41.2179516
OS 26.03539878 41.20274462
OS 26.03666624 41.2002097
OS 26.04046862 41.19640732
OS 26.04173608 41.1938724
OS 26.044271 41.1875351
OS 26.05060576 41.1761305
OS 26.05694306 41.1697932
OS 26.05821052 41.16725828
OS 26.0620129 41.16345844
OS 26.06328036 41.16092352
OS 26.06708274 41.15712368
OS 26.07151758 41.14508408
OS 26.07785488 41.13747932
OS 26.08102226 41.13304448
OS 26.08355718 41.13050956
OS 26.08418964 41.1286071
OS 26.08672456 41.12733964
OS 26.09495924 41.11910242
OS 26.0962267 41.1165675
OS 26.10129654 41.1115002
OS 26.102564 41.10896528
OS 26.10636638 41.1000956
OS 26.10763384 41.09629322
OS 26.11333614 41.08932346
OS 26.11650352 41.08615608
OS 26.11777098 41.08362116
OS 26.14565256 41.05573958
OS 26.14692002 41.05320466
OS 26.15071986 41.04940228
OS 26.15198732 41.0468699
OS 26.15705716 41.03419784
OS 26.16339192 41.02786054
OS 26.16465938 41.02532562
OS 26.17036422 41.01835586
OS 26.17733398 41.01265356
OS 26.18303628 41.0056838
OS 26.19000604 40.9999815
OS 26.1912735 40.99744658
OS 26.19570834 40.9930092
OS 26.19824326 40.99174428
OS 26.20394556 40.98603944
OS 26.20521302 40.98350706
OS 26.20711548 40.98160714
OS 26.20964786 40.98033968
OS 26.3737598 40.81622774
OS 26.37502726 40.81369282
OS 26.37692718 40.8117929
OS 26.3794621 40.81052544
OS 26.3851644 40.80482314
OS 26.38643186 40.80229076
OS 26.3908667 40.79785338
OS 26.39340162 40.79658592
OS 26.396569 40.79341854
OS 26.39783646 40.79088362
OS 26.40353876 40.78518132
OS 26.40607368 40.78391386
OS 26.40924106 40.78074648
OS 26.41050852 40.77821156
OS 26.4149459 40.77377418
OS 26.41747828 40.77250672
OS 26.42191566 40.76807188
OS 26.42318312 40.76553696
OS 26.4263505 40.76236958
OS 26.42888542 40.76110212
OS 26.43142034 40.7585672
OS 26.43395526 40.75729974
OS 26.43902256 40.7522299
OS 26.44535986 40.74969498
OS 26.45042716 40.74843006
OS 26.45296208 40.74589514
OS 26.455497 40.74463022
OS 26.45803192 40.7420953
OS 26.4605643 40.74082784
OS 26.47704128 40.7243534
OS 26.4795762 40.72308594
OS 26.48591096 40.71674864
OS 26.48844588 40.71548118
OS 26.49478318 40.71294626
OS 26.49985302 40.7116788
OS 26.50238794 40.70914388
OS 26.50492032 40.70787642
OS 26.50998762 40.70280912
OS 26.51252254 40.70154166
OS 26.52202722 40.69203698
OS 26.52266222 40.69013452
OS 26.52519714 40.68886706
OS 26.5321669 40.6831673
OS 26.53660174 40.67873246
OS 26.5435715 40.67683
OS 26.5499088 40.67429508
OS 26.55307618 40.6711277
OS 26.5556111 40.66986024
OS 26.56068094 40.6647904
OS 26.56321586 40.66352294
OS 26.56828316 40.65845564
OS 26.57081808 40.65718818
OS 26.57335046 40.65465326
OS 26.57968776 40.65211834
OS 26.58792498 40.64894842
OS 26.59236236 40.64451358
OS 26.59489474 40.64324612
OS 26.61137172 40.62677168
OS 26.61390664 40.62550676
OS 26.6202414 40.61916946
OS 26.62911108 40.61536708
OS 26.63418092 40.61409962
OS 26.6430506 40.60776486
OS 26.6493879 40.60522994
OS 26.65762512 40.60206256
OS 26.66522988 40.59572526
OS 26.6671298 40.5938228
OS 26.66966472 40.59255534
OS 26.67663448 40.58685304
OS 26.6798044 40.58368566
OS 26.68233678 40.5824182
OS 26.69120646 40.57861582
OS 26.70514598 40.57101106
OS 26.71655312 40.5659463
OS 26.72795772 40.559609
OS 26.73682994 40.55580662
OS 26.74823454 40.54946932
OS 26.75330184 40.54440202
OS 26.75583676 40.54313456
OS 26.76280652 40.53742972
OS 26.7672439 40.53299488
OS 26.77548112 40.5298275
OS 26.78181588 40.52729258
OS 26.7913231 40.52159028
OS 26.79765786 40.51905536
OS 26.9028418 40.46709712
OS 26.92185116 40.45822744
OS 26.93325322 40.45695998
OS 26.95986734 40.44428792
OS 26.9788767 40.43541824
OS 26.98394654 40.43415078
OS 26.99725106 40.43098086
OS 27.0257651 40.4176738
OS 27.04223954 40.41007158
OS 27.05300914 40.40816912
OS 27.05807898 40.40690166
OS 27.06504874 40.40373428
OS 27.06758366 40.40246682
OS 27.07645588 40.39866444
OS 27.09419778 40.39486206
OS 27.10813476 40.3885273
OS 27.12080936 40.38472746
OS 27.12841158 40.38346
OS 27.13474888 40.38092508
OS 27.1486884 40.37458778
OS 27.15375824 40.37332032
OS 27.16263046 40.37205286
OS 27.16896522 40.36952048
OS 27.18290474 40.36318318
OS 27.19304442 40.36064826
OS 27.2025491 40.35874834
OS 27.219656 40.35177604
OS 27.22979314 40.34924112
OS 27.24436766 40.3473412
OS 27.2545048 40.34480628
OS 27.2608421 40.34227136
OS 27.27161424 40.33910398
OS 27.2893536 40.33656906
OS 27.3013932 40.33466914
OS 27.31153288 40.33340168
OS 27.31660018 40.33213422
OS 27.32483994 40.3289643
OS 27.33307716 40.32706438
OS 27.33941192 40.32579946
OS 27.34701668 40.324532
OS 27.35715382 40.32326454
OS 27.37362826 40.32072962
OS 27.3786981 40.31946216
OS 27.38693532 40.31629478
OS 27.39517254 40.31439232
OS 27.40150984 40.3131274
OS 27.41544682 40.31185994
OS 27.42938634 40.30932502
OS 27.43445618 40.30805756
OS 27.44079348 40.3067901
OS 27.44776324 40.30488764
OS 27.45790292 40.30235526
OS 27.47057244 40.3010878
OS 27.49275172 40.29918534
OS 27.50415632 40.29791788
OS 27.52063076 40.29538296
OS 27.53330282 40.29284804
OS 27.54470742 40.29158312
OS 27.572589 40.29031566
OS 27.5890609 40.2890482
OS 27.65876104 40.28778074
OS 27.87102884 40.28714574
OS 27.87483122 40.2884132
OS 27.95846834 40.28968066
OS 27.96227072 40.29094812
OS 27.99775452 40.29221558
OS 28.0015569 40.29348304
OS 28.00979158 40.29538296
OS 28.03577324 40.29855288
OS 28.04464292 40.29982034
OS 28.06111736 40.3010878
OS 28.07632434 40.30235526
OS 28.08012672 40.30362018
OS 28.08519402 40.30488764
OS 28.09406624 40.30742256
OS 28.101036 40.30932502
OS 28.1073733 40.31059248
OS 28.12448274 40.3124924
OS 28.1365198 40.31439232
OS 28.1415871 40.31565978
OS 28.14855686 40.31756224
OS 28.15489416 40.32009716
OS 28.16376638 40.32136462
OS 28.16883622 40.32263208
OS 28.18467566 40.324532
OS 28.19227788 40.32579946
OS 28.19861518 40.32706438
OS 28.20875232 40.3295993
OS 28.21952446 40.33276668
OS 28.2245943 40.33403414
OS 28.2423362 40.33656906
OS 28.25690818 40.33846898
OS 28.26324548 40.33973644
OS 28.26958278 40.34227136
OS 28.28415476 40.34670874
OS 28.2892246 40.3479762
OS 28.30506658 40.34987612
OS 28.31013388 40.35114358
OS 28.32027102 40.35494596
OS 28.33104316 40.3593808
OS 28.34878506 40.36318318
OS 28.36272712 40.36952048
OS 28.36906188 40.37205286
OS 28.37793156 40.37332032
OS 28.3830014 40.37458778
OS 28.39694092 40.38092508
OS 28.40327822 40.38346
OS 28.41785274 40.38662484
OS 28.42798734 40.39042722
OS 28.43495964 40.3935946
OS 28.4412944 40.39612952
OS 28.45206654 40.39803198
OS 28.45713638 40.39929944
OS 28.46981098 40.4056342
OS 28.47487828 40.40690166
OS 28.48184804 40.40880412
OS 28.49515256 40.4119715
OS 28.50465724 40.4176738
OS 28.512897 40.42084372
OS 28.51986676 40.4240111
OS 28.53887612 40.43288332
OS 28.55154564 40.43415078
OS 28.56295278 40.44048554
OS 28.57435738 40.44555538
OS 28.58069468 40.44808776
OS 28.59970404 40.45695998
OS 28.60857372 40.45822744
OS 28.61554348 40.46012736
OS 28.62885054 40.46709712
OS 28.63518784 40.46963204
OS 28.69981814 40.50258092
OS 28.70868782 40.50638076
OS 28.72516226 40.51525298
OS 28.73403194 40.51905536
OS 28.747974 40.52665758
OS 28.75684368 40.53045996
OS 28.76825082 40.53679726
OS 28.77458558 40.54313456
OS 28.78092288 40.54693694
OS 28.78599272 40.55200424
OS 28.79485986 40.55580662
OS 28.80119716 40.55834154
OS 28.80880192 40.56341138
OS 28.8176716 40.56721122
OS 28.8240089 40.56974614
OS 28.83097866 40.57544844
OS 28.83288112 40.57734836
OS 28.83541604 40.57861582
OS 28.83794842 40.58115074
OS 28.84048334 40.5824182
OS 28.8468181 40.5887555
OS 28.8594927 40.5938228
OS 28.86202508 40.59509026
OS 28.87216476 40.60142756
OS 28.88420436 40.6058624
OS 28.8943415 40.6121997
OS 28.9013138 40.61536708
OS 28.90954848 40.618537
OS 28.9114484 40.62043692
OS 28.91398332 40.62170438
OS 28.92032062 40.62803914
OS 28.92285554 40.6293066
OS 28.93932998 40.64578104
OS 28.9418649 40.6470485
OS 28.94439982 40.64958342
OS 28.95073458 40.65211834
OS 28.9589718 40.65528572
OS 28.9659441 40.66225548
OS 28.96847648 40.66352294
OS 28.97988108 40.67239516
OS 28.982416 40.67493008
OS 28.9944556 40.67936492
OS 28.99889044 40.6825323
OS 29.00396028 40.6875996
OS 29.0064952 40.68886706
OS 29.02170218 40.70407404
OS 29.0242371 40.7053415
OS 29.0293044 40.71041134
OS 29.0356417 40.71294626
OS 29.04387892 40.71611364
OS 29.04577884 40.7180161
OS 29.04831376 40.71928356
OS 29.05465106 40.72561832
OS 29.05718598 40.72688578
OS 29.0654232 40.73512554
OS 29.06669066 40.73765792
OS 29.0711255 40.74082784
OS 29.07429288 40.74399522
OS 29.07556034 40.7465276
OS 29.07873026 40.74969498
OS 29.08126264 40.75096244
OS 29.08506502 40.75476482
OS 29.0875974 40.75603228
OS 29.09139978 40.75983466
OS 29.1053393 40.7649045
OS 29.1116766 40.77123926
OS 29.11421152 40.77250672
OS 29.12118128 40.77821156
OS 29.12244874 40.78074648
OS 29.12815104 40.78644878
OS 29.13068596 40.78771624
OS 29.13385588 40.79088362
OS 29.13512334 40.79341854
OS 29.14082564 40.79912084
OS 29.14336056 40.8003883
OS 29.14526048 40.80229076
OS 29.1465254 40.80482314
OS 29.15349516 40.8117929
OS 29.15603008 40.81306036
OS 29.15983246 40.8168602
OS 29.16236738 40.81812766
OS 29.1649023 40.82066258
OS 29.1769419 40.82509996
OS 29.18137674 40.82826734
OS 29.18644658 40.83333718
OS 29.1889815 40.83460464
OS 29.19595126 40.8415744
OS 29.19721872 40.84410932
OS 29.20355348 40.85044408
OS 29.20482094 40.852979
OS 29.20735332 40.8593163
OS 29.20862078 40.86438614
OS 29.21432562 40.87135336
OS 29.2231953 40.88022558
OS 29.2295326 40.88275796
OS 29.23776982 40.88592788
OS 29.24220466 40.88909526
OS 29.2472745 40.8941651
OS 29.24980942 40.89543256
OS 29.25677918 40.90240232
OS 29.25804664 40.90493724
OS 29.2656514 40.912542
OS 29.26818378 40.92267914
OS 29.27198362 40.9290139
OS 29.27388608 40.93091382
OS 29.27895592 40.93218128
OS 29.28592568 40.93408374
OS 29.2878256 40.93598366
OS 29.29036052 40.93725112
OS 29.29543036 40.94232096
OS 29.29796528 40.94358842
OS 29.3062025 40.95182564
OS 29.30746996 40.95436056
OS 29.31380726 40.96069532
OS 29.31633964 40.96703262
OS 29.31950956 40.97526984
OS 29.3239444 40.98350706
OS 29.32267694 40.98857436
OS 29.31697464 40.99047682
OS 29.30936988 40.98920936
OS 29.30430004 40.98414206
OS 29.30176766 40.9828746
OS 29.29923274 40.98033968
OS 29.29669782 40.97907222
OS 29.2935279 40.97590484
OS 29.29226298 40.97336992
OS 29.28655814 40.96766762
OS 29.28402322 40.96640016
OS 29.28085584 40.96323024
OS 29.27958838 40.96069532
OS 29.27261862 40.95372556
OS 29.2700837 40.9524581
OS 29.26818378 40.95055818
OS 29.26691632 40.94802326
OS 29.24980942 40.93091382
OS 29.24790696 40.93028136
OS 29.24664204 40.92774644
OS 29.23840228 40.91951176
OS 29.2358699 40.9182443
OS 29.23269998 40.91507438
OS 29.23143252 40.912542
OS 29.22446276 40.9055697
OS 29.22192784 40.90430224
OS 29.22002792 40.90240232
OS 29.21876046 40.8998674
OS 29.19024896 40.87135336
OS 29.18771404 40.8700859
OS 29.18454412 40.86691852
OS 29.18327666 40.86438614
OS 29.17757436 40.8586813
OS 29.17503944 40.85741638
OS 29.17187206 40.85424646
OS 29.1706046 40.85171154
OS 29.1649023 40.84600924
OS 29.16236738 40.84474178
OS 29.15983246 40.84220686
OS 29.15729754 40.8409394
OS 29.1522277 40.8358721
OS 29.14336056 40.83333718
OS 29.13702326 40.8295348
OS 29.13068596 40.8231975
OS 29.12815104 40.82193004
OS 29.1237162 40.81876266
OS 29.12244874 40.81622774
OS 29.07175796 40.76553696
OS 29.0711255 40.76363704
OS 29.06859058 40.76236958
OS 29.0647882 40.7585672
OS 29.06225328 40.75729974
OS 29.05718598 40.7522299
OS 29.05465106 40.75096244
OS 29.04831376 40.74843006
OS 29.04324392 40.7471626
OS 29.03944154 40.74336276
OS 29.03754162 40.74272776
OS 29.03690916 40.74082784
OS 29.03437424 40.73956038
OS 29.03183932 40.73702546
OS 29.0293044 40.735758
OS 29.02360464 40.7300557
OS 29.02233718 40.72752078
OS 29.01916726 40.7243534
OS 29.01663234 40.72308594
OS 29.01156504 40.7180161
OS 29.00903012 40.71674864
OS 29.0064952 40.71421372
OS 29.00142536 40.71294626
OS 28.99318814 40.70977888
OS 28.98621838 40.70280912
OS 28.98368346 40.70154166
OS 28.9767137 40.69583682
OS 28.97354378 40.69266944
OS 28.9710114 40.69140198
OS 28.96214172 40.6875996
OS 28.9532695 40.6825323
OS 28.94693474 40.67619754
OS 28.94439982 40.67493008
OS 28.92792284 40.65845564
OS 28.92539046 40.65718818
OS 28.92285554 40.65465326
OS 28.91651824 40.65211834
OS 28.90828102 40.64894842
OS 28.9013138 40.64197866
OS 28.89877888 40.6407112
OS 28.89180912 40.6350089
OS 28.88990666 40.63310898
OS 28.88737174 40.63184152
OS 28.88483682 40.6293066
OS 28.87279722 40.62487176
OS 28.86836238 40.62170438
OS 28.86456 40.617902
OS 28.86202508 40.61663454
OS 28.8594927 40.61409962
OS 28.85695778 40.6128347
OS 28.85062048 40.6064974
OS 28.84808556 40.60522994
OS 28.83921588 40.60142756
OS 28.81513668 40.59002296
OS 28.806267 40.58495312
OS 28.76698336 40.5659463
OS 28.76064606 40.56214392
OS 28.75557622 40.55707408
OS 28.7530413 40.55580662
OS 28.75050638 40.5532717
OS 28.747974 40.55200424
OS 28.74417162 40.54820186
OS 28.7416367 40.54693694
OS 28.73910178 40.54440202
OS 28.73086456 40.5412321
OS 28.7245298 40.53869718
OS 28.71629258 40.53299488
OS 28.70995528 40.53045996
OS 28.70171806 40.52729258
OS 28.6941133 40.52222274
OS 28.68714354 40.51905536
OS 28.67890632 40.51588544
OS 28.66876918 40.50955068
OS 28.66179942 40.50638076
OS 28.65546466 40.50384838
OS 28.64405752 40.49751362
OS 28.63265292 40.49244378
OS 28.61110864 40.4823041
OS 28.59907158 40.48040418
OS 28.59273428 40.47786926
OS 28.5597854 40.46139482
OS 28.54394596 40.45442506
OS 28.5249366 40.44555538
OS 28.51352946 40.44428792
OS 28.49705502 40.43668316
OS 28.49071772 40.43415078
OS 28.48184804 40.43288332
OS 28.4660086 40.42717848
OS 28.45270154 40.42147618
OS 28.44382932 40.42020872
OS 28.43875948 40.41894126
OS 28.42102012 40.41133904
OS 28.41468282 40.40880412
OS 28.40264576 40.40690166
OS 28.39630846 40.40436674
OS 28.38046648 40.39739698
OS 28.36082466 40.39296214
OS 28.35512236 40.38979476
OS 28.34878506 40.38725984
OS 28.33991538 40.38472746
OS 28.33484554 40.38346
OS 28.32787578 40.38155754
OS 28.32153848 40.37902516
OS 28.31456872 40.3771227
OS 28.31393626 40.37649024
OS 28.30696396 40.37458778
OS 28.3018992 40.37332032
OS 28.28542222 40.37205286
OS 28.28035492 40.3707854
OS 28.26831532 40.36888548
OS 28.26324548 40.36761802
OS 28.25690818 40.3650831
OS 28.24613858 40.36191572
OS 28.24106874 40.36064826
OS 28.23219906 40.3593808
OS 28.22015946 40.35748088
OS 28.2062174 40.35241104
OS 28.19924764 40.35050858
OS 28.1891105 40.3479762
OS 28.17073614 40.34480628
OS 28.1656663 40.34353882
OS 28.159329 40.3410039
OS 28.1542617 40.33973644
OS 28.14665694 40.33846898
OS 28.1365198 40.33720406
OS 28.12891504 40.3359366
OS 28.11751044 40.33466914
OS 28.09216632 40.33086676
OS 28.08519402 40.3289643
OS 28.07632434 40.32769684
OS 28.0712545 40.32643192
OS 28.0484453 40.32516446
OS 28.04464292 40.32389954
OS 28.0021919 40.32199708
OS 27.9895173 40.32072962
OS 27.9781127 40.31946216
OS 27.97050794 40.3181947
OS 27.96417064 40.31692724
OS 27.9540335 40.31565978
OS 27.93882652 40.31439232
OS 27.9185497 40.3131274
OS 27.87419622 40.31185994
OS 27.86342408 40.31122494
OS 27.8596217 40.3124924
OS 27.82794028 40.31122494
OS 27.66509834 40.31185994
OS 27.66066096 40.31122494
OS 27.65686112 40.3124924
OS 27.65305874 40.31122494
OS 27.63278446 40.3124924
OS 27.59729812 40.31375986
OS 27.59349828 40.31502732
OS 27.56815416 40.31629478
OS 27.56435178 40.31756224
OS 27.55547956 40.3188297
OS 27.55040972 40.32009716
OS 27.5301329 40.32136462
OS 27.50922616 40.32326454
OS 27.4838795 40.324532
OS 27.47373982 40.32579946
OS 27.45726792 40.32706438
OS 27.4433284 40.3295993
OS 27.43635864 40.33149922
OS 27.40594468 40.3353016
OS 27.37933056 40.33910398
OS 27.37426072 40.34037144
OS 27.36539104 40.34290636
OS 27.35525136 40.34544128
OS 27.3432143 40.3473412
OS 27.32610486 40.34924112
OS 27.31280034 40.35241104
OS 27.30582804 40.35557842
OS 27.29315598 40.3593808
OS 27.2849213 40.36128072
OS 27.27985146 40.36254818
OS 27.2728817 40.3657181
OS 27.2665444 40.36825302
OS 27.25133742 40.3707854
OS 27.23866282 40.37205286
OS 27.22979314 40.37332032
OS 27.22155846 40.37522278
OS 27.2076164 40.38029262
OS 27.19684426 40.38346
OS 27.18860704 40.38535992
OS 27.1835372 40.38662484
OS 27.17656744 40.38979476
OS 27.16516538 40.39486206
OS 27.15312578 40.39676452
OS 27.1429861 40.4005669
OS 27.12967904 40.4062692
OS 27.12461174 40.40753666
OS 27.11130468 40.41070404
OS 27.09736516 40.41704134
OS 27.08659302 40.42020872
OS 27.07708834 40.42211118
OS 27.07075358 40.4246461
OS 27.05744652 40.4303484
OS 27.04730938 40.43288332
OS 27.03970462 40.43415078
OS 27.01055812 40.44808776
OS 26.99408114 40.45569252
OS 26.985214 40.45695998
OS 26.98014416 40.45822744
OS 26.95606496 40.46963204
OS 26.94972766 40.47216696
OS 26.93325322 40.47977172
OS 26.92818338 40.48103664
OS 26.91868124 40.4829391
OS 26.91234648 40.48547402
OS 26.9028418 40.49117632
OS 26.89460204 40.4943437
OS 26.88826728 40.49687862
OS 26.88066252 40.50194846
OS 26.87432522 40.50448338
OS 26.86038824 40.51081814
OS 26.85848832 40.51271806
OS 26.8559534 40.51398552
OS 26.84454626 40.51905536
OS 26.83314166 40.52539266
OS 26.82173452 40.53045996
OS 26.807795 40.53806472
OS 26.7963904 40.54313456
OS 26.79005564 40.54693694
OS 26.78308334 40.55263924
OS 26.77738104 40.55707408
OS 26.77484612 40.55834154
OS 26.76851136 40.56467884
OS 26.76153906 40.56657622
OS 26.75393684 40.5703786
OS 26.7444347 40.5760809
OS 26.7380974 40.57861582
OS 26.70894836 40.59255534
OS 26.70641344 40.5938228
OS 26.70388106 40.59635772
OS 26.70134614 40.59762518
OS 26.6962763 40.60269502
OS 26.69374138 40.60396248
OS 26.68677416 40.60966478
OS 26.68360424 40.6128347
OS 26.67726948 40.61536708
OS 26.67219964 40.61663454
OS 26.66522988 40.62233938
OS 26.66205996 40.62550676
OS 26.65952758 40.62677168
OS 26.65255528 40.63247398
OS 26.6493879 40.6356439
OS 26.64685298 40.63691136
OS 26.63418092 40.64197866
OS 26.631646 40.64324612
OS 26.62277632 40.64958342
OS 26.61770648 40.65085088
OS 26.60630188 40.65718818
OS 26.59933212 40.66289048
OS 26.59489474 40.66605786
OS 26.58982744 40.6711277
OS 26.58729252 40.67239516
OS 26.57588538 40.677465
OS 26.57335046 40.67873246
OS 26.56638324 40.68443476
OS 26.5619484 40.6875996
OS 26.54674142 40.70280912
OS 26.5442065 40.70407404
OS 26.5378692 40.71041134
OS 26.52899698 40.71294626
OS 26.5201273 40.7180161
OS 26.51505746 40.72308594
OS 26.51252254 40.7243534
OS 26.50555532 40.73132316
OS 26.50428786 40.73385808
OS 26.50238794 40.735758
OS 26.49985302 40.73702546
OS 26.4973181 40.73956038
OS 26.49478318 40.74082784
OS 26.48844588 40.7471626
OS 26.4795762 40.74969498
OS 26.4732389 40.75349736
OS 26.46943652 40.75729974
OS 26.4669016 40.7585672
OS 26.46436668 40.76110212
OS 26.46183176 40.76236958
OS 26.45993184 40.7642695
OS 26.45866438 40.76680442
OS 26.4377551 40.78771624
OS 26.43585518 40.7883487
OS 26.43458772 40.79088362
OS 26.4022713 40.8231975
OS 26.39973638 40.82446496
OS 26.39340162 40.83080226
OS 26.3908667 40.83206972
OS 26.38706686 40.83333718
OS 26.37882964 40.83650456
OS 26.37122488 40.84284186
OS 26.36679004 40.84600924
OS 26.23562698 40.9771723
OS 26.23435952 40.97970722
OS 26.22928968 40.98477452
OS 26.2267573 40.99110928
OS 26.22485484 40.99807904
OS 26.22295492 40.9999815
OS 26.22168746 41.00251642
OS 26.21535016 41.00885118
OS 26.2140827 41.0113861
OS 26.18176882 41.04370252
OS 26.1798689 41.04433752
OS 26.17860144 41.0468699
OS 26.161492 41.0639768
OS 26.15895708 41.06524426
OS 26.15325478 41.07094656
OS 26.15198732 41.07348148
OS 26.1494524 41.0760164
OS 26.14818494 41.07855132
OS 26.1443851 41.0823537
OS 26.14311764 41.08488862
OS 26.14058272 41.09122592
OS 26.13931526 41.09629322
OS 26.13171304 41.10389798
OS 26.13044558 41.10643036
OS 26.12474328 41.11340012
OS 26.12220836 41.11466758
OS 26.1152386 41.12163734
OS 26.11397114 41.12417226
OS 26.1089013 41.1292421
OS 26.10763384 41.13177702
OS 26.10509892 41.13811178
OS 26.10193154 41.14635154
OS 26.09495924 41.1533213
OS 26.09369432 41.15585622
OS 26.07721988 41.17232812
OS 26.07595242 41.17486304
OS 26.07215004 41.17866542
OS 26.07088258 41.18120034
OS 26.0683502 41.1875351
OS 26.06328036 41.19640732
OS 26.05947798 41.2002097
OS 26.05821052 41.20274462
OS 26.0556756 41.205277
OS 26.05440814 41.20781192
OS 26.04807338 41.21414922
OS 26.04680592 41.21668414
OS 26.044271 41.22302144
OS 26.04110108 41.23125612
OS 26.0379337 41.23569096
OS 26.03286386 41.24329572
OS 26.03096394 41.25026548
OS 26.02906148 41.25470032
OS 26.02336172 41.26167008
OS 26.02019434 41.26484
OS 26.01892688 41.26737492
OS 26.01639196 41.2699073
OS 26.0151245 41.27244222
OS 26.01005466 41.27751206
OS 26.00751974 41.28384936
OS 26.00625228 41.28891666
OS 26.00054998 41.29588642
OS 25.9973826 41.2990538
OS 25.99611514 41.30158872
OS 25.99041284 41.30855848
OS 25.98851038 41.31046094
OS 25.98724292 41.31299586
OS 25.984708 41.31552824
OS 25.98344054 41.32059808
OS 25.9618988 41.36241664
OS 25.95809896 41.37128886
OS 25.95302912 41.38016108
OS 25.94795928 41.38522838
OS 25.94669182 41.3877633
OS 25.94098952 41.39473306
OS 25.93908706 41.39663552
OS 25.9378196 41.39917044
OS 25.9327523 41.4105725
OS 25.92768246 41.41944472
OS 25.92134516 41.43338424
OS 25.9150104 41.44479138
OS 25.9086731 41.4587309
OS 25.9036058 41.46760058
OS 25.89600104 41.48407502
OS 25.89473358 41.48660994
OS 25.88839882 41.49674708
OS 25.8858639 41.50308438
OS 25.88269398 41.5113216
OS 25.87572422 41.52462866
OS 25.87445676 41.52969596
OS 25.87128938 41.54427048
OS 25.86431962 41.55757754
OS 25.8617847 41.5639123
OS 25.85037756 41.58798896
OS 25.84911264 41.59686118
OS 25.84784772 41.60193102
OS 25.8446778 41.61016824
OS 25.84277788 41.61206816
OS 25.8389755 41.62094038
OS 25.83644058 41.62727514
OS 25.82630344 41.64881688
OS 25.82503598 41.65388672
OS 25.82313352 41.6633914
OS 25.8205986 41.6697287
OS 25.81362884 41.68683814
OS 25.81236138 41.69570782
OS 25.80792654 41.70774488
OS 25.80475916 41.71471718
OS 25.80222424 41.72105194
OS 25.80095678 41.72612178
OS 25.79778686 41.73942884
OS 25.79525194 41.74576614
OS 25.79208456 41.7527359
OS 25.78954964 41.75907066
OS 25.78828218 41.7641405
OS 25.78701726 41.77301018
OS 25.7806825 41.7869497
OS 25.77814758 41.793287
OS 25.77688012 41.79835684
OS 25.7737102 41.8116639
OS 25.77117528 41.81799866
OS 25.76927536 41.8237035
OS 25.76674044 41.83257064
OS 25.76547298 41.83764048
OS 25.76420552 41.85411492
OS 25.76293806 41.85918476
OS 25.76103814 41.87122436
OS 25.75977068 41.8762942
OS 25.75723576 41.88262896
OS 25.75280092 41.89720094
OS 25.75153346 41.90987554
OS 25.750266 41.91494284
OS 25.74899854 41.9225476
OS 25.74519616 41.93141982
OS 25.74139378 41.94662426
OS 25.74012632 41.95549648
OS 25.73885886 41.97197092
OS 25.73759394 41.97704076
OS 25.73569148 41.98401052
OS 25.7325241 41.99478266
OS 25.72872172 42.0099871
OS 25.72555688 42.03596876
OS 25.72048704 42.05624558
OS 25.71858458 42.07334994
OS 25.71668466 42.0929943
OS 25.7154172 42.1170735
OS 25.71414974 42.12847556
OS 25.71288228 42.1512873
OS 25.71161482 42.16142698
OS 25.71034736 42.16903174
OS 25.7090799 42.17409904
OS 25.70781244 42.18423872
OS 25.70654498 42.20578046
OS 25.70527752 42.2222549
OS 25.7040126 42.24506664
OS 25.70274514 42.28561774
OS 25.70084268 42.29005512
OS 25.69894276 42.29195504
OS 25.69387292 42.2932225
OE
SE
S P 0
OB 32.9083924 44.95700432 I
OS 32.97809254 44.95573686
OS 32.98189492 44.9544694
OS 33.0021692 44.95320194
OS 33.01104142 44.94939956
OS 33.0199111 44.94686718
OS 33.038288 44.94496472
OS 33.04335784 44.94369726
OS 33.04969006 44.94116488
OS 33.06299712 44.93546258
OS 33.07186934 44.93419512
OS 33.07693918 44.93292766
OS 33.0851764 44.92976028
OS 33.08707632 44.92785782
OS 33.09848346 44.92279052
OS 33.10671814 44.9196206
OS 33.1136879 44.91518576
OS 33.12762742 44.90884846
OS 33.13396472 44.90504608
OS 33.13903456 44.89997878
OS 33.14156948 44.89871132
OS 33.15107416 44.89174156
OS 33.15170662 44.8898391
OS 33.15424154 44.88857164
OS 33.1669136 44.88350434
OS 33.16944852 44.88223688
OS 33.17705074 44.87463466
OS 33.17958566 44.8733672
OS 33.1840205 44.87019728
OS 33.18528796 44.8676649
OS 33.18782288 44.86512998
OS 33.18845788 44.86322752
OS 33.1909928 44.86196006
OS 33.20619978 44.84675308
OS 33.2080997 44.84612062
OS 33.20936716 44.8435857
OS 33.21190208 44.84105078
OS 33.21253708 44.83914832
OS 33.21506946 44.83788086
OS 33.21760438 44.83534848
OS 33.2201393 44.83408102
OS 33.2252066 44.82647626
OS 33.23217636 44.81950904
OS 33.2372462 44.80556698
OS 33.2429485 44.79859722
OS 33.24611842 44.79542984
OS 33.24738334 44.79289492
OS 33.25308818 44.78592516
OS 33.25625556 44.78275524
OS 33.2606904 44.77071564
OS 33.26386032 44.7662808
OS 33.26892762 44.7612135
OS 33.27019508 44.75867858
OS 33.27653238 44.7498089
OS 33.28033476 44.74600652
OS 33.28286968 44.73586684
OS 33.2841346 44.7257297
OS 33.29300428 44.70672034
OS 33.2955392 44.6965832
OS 33.29680666 44.68771352
OS 33.30314396 44.67377146
OS 33.30504388 44.65919694
OS 33.30631134 44.65159472
OS 33.3075788 44.63005298
OS 33.30884626 44.61737838
OS 33.31011372 44.60597378
OS 33.31138118 44.60090394
OS 33.31518356 44.5907668
OS 33.31835094 44.58252958
OS 33.3196184 44.57746228
OS 33.31835094 44.56605514
OS 33.31201618 44.55211562
OS 33.31074872 44.54704578
OS 33.30948126 44.53817356
OS 33.3082138 44.53310626
OS 33.30694634 44.51283198
OS 33.30504388 44.49952492
OS 33.3025115 44.48685032
OS 33.29680666 44.47354326
OS 33.2955392 44.46467358
OS 33.29300428 44.45453644
OS 33.28666952 44.4443993
OS 33.2841346 44.438062
OS 33.28096722 44.42982478
OS 33.27843484 44.42348748
OS 33.27653238 44.42158756
OS 33.27526492 44.41905264
OS 33.27146254 44.41018042
OS 33.26956262 44.3968759
OS 33.2670277 44.39054114
OS 33.26005794 44.38356884
OS 33.2549881 44.37469916
OS 33.2486508 44.36836186
OS 33.2435835 44.35442234
OS 33.23597874 44.34681758
OS 33.23471128 44.34428266
OS 33.23027644 44.3385829
OS 33.22774152 44.33731544
OS 33.17134844 44.28092236
OS 33.17071344 44.27902244
OS 33.16818106 44.27775498
OS 33.16564614 44.27522006
OS 33.16311376 44.2739526
OS 33.15677646 44.2676153
OS 33.15043916 44.26508038
OS 33.14220194 44.261913
OS 33.13459972 44.25684316
OS 33.12762742 44.25367578
OS 33.1193902 44.25050586
OS 33.11242044 44.24607102
OS 33.09848346 44.23973372
OS 33.08707632 44.23339896
OS 33.07567172 44.22832912
OS 33.05159252 44.21692452
OS 33.03955546 44.2150246
OS 33.02941578 44.21122222
OS 33.02371348 44.2093223
OS 33.01484126 44.20805484
OS 32.96668794 44.20551992
OS 32.8665713 44.20425246
OS 32.7550526 44.20425246
OS 32.47625712 44.20551992
OS 32.47245474 44.20678738
OS 32.4382384 44.20805484
OS 32.43443856 44.2093223
OS 32.4261988 44.21248968
OS 32.41542666 44.21565706
OS 32.40592198 44.21755952
OS 32.39578484 44.2213619
OS 32.38754762 44.2257942
OS 32.37741048 44.22832912
OS 32.36727334 44.22959658
OS 32.35840112 44.23466642
OS 32.3444616 44.24100118
OS 32.3381243 44.2435361
OS 32.32925208 44.2498734
OS 32.3153151 44.25494324
OS 32.3096128 44.25937808
OS 32.30834534 44.261913
OS 32.2975732 44.26888276
OS 32.2912359 44.27522006
OS 32.28616606 44.27648752
OS 32.27792884 44.2796549
OS 32.26969162 44.28788958
OS 32.26335686 44.29169196
OS 32.26145694 44.29359188
OS 32.26018948 44.2961268
OS 32.25448718 44.30183164
OS 32.25195226 44.30309656
OS 32.24878234 44.30626648
OS 32.24751488 44.3088014
OS 32.24181258 44.3145037
OS 32.23927766 44.31577116
OS 32.23737774 44.31767108
OS 32.23611028 44.320206
OS 32.23040798 44.3259083
OS 32.22787306 44.32717576
OS 32.22470568 44.33034568
OS 32.2209033 44.33668044
OS 32.214566 44.34301774
OS 32.21203108 44.3493525
OS 32.21076362 44.35442234
OS 32.20189648 44.36836186
OS 32.20062902 44.3734317
OS 32.19429172 44.3848363
OS 32.18922188 44.38990614
OS 32.18795442 44.39244106
OS 32.18225212 44.39941082
OS 32.17781728 44.40384566
OS 32.17211244 44.4196851
OS 32.16704514 44.42728986
OS 32.16387522 44.438062
OS 32.1619753 44.44883414
OS 32.15944038 44.45517144
OS 32.156273 44.4621412
OS 32.15373808 44.46847596
OS 32.15247062 44.47354326
OS 32.15120316 44.48621786
OS 32.1499357 44.496355
OS 32.14486586 44.5090296
OS 32.14360094 44.5140969
OS 32.14170102 44.53500618
OS 32.14043356 44.555283
OS 32.13979856 44.60660624
OS 32.14106602 44.61040862
OS 32.14233348 44.64082512
OS 32.14360094 44.64462496
OS 32.14486586 44.65349464
OS 32.14740078 44.65983194
OS 32.1499357 44.66870416
OS 32.15437054 44.69595074
OS 32.15690546 44.7022855
OS 32.16260776 44.71559002
OS 32.16387522 44.72446224
OS 32.16577768 44.73269946
OS 32.1676776 44.73460192
OS 32.16894506 44.7371343
OS 32.1740149 44.74220414
OS 32.17528236 44.74473906
OS 32.18098466 44.75170882
OS 32.18288458 44.75361128
OS 32.18415204 44.7561462
OS 32.18922188 44.76754826
OS 32.19429172 44.77642048
OS 32.20062902 44.79036
OS 32.20506132 44.79859722
OS 32.20759624 44.79986468
OS 32.20949616 44.80176714
OS 32.21076362 44.80429952
OS 32.21646592 44.81127182
OS 32.22343822 44.81697412
OS 32.22914052 44.82394134
OS 32.23611028 44.82964364
OS 32.24181258 44.8366134
OS 32.2443475 44.83788086
OS 32.24878234 44.84231824
OS 32.2500498 44.84485316
OS 32.25448718 44.849288
OS 32.2570221 44.85055546
OS 32.26145694 44.8549903
OS 32.2627244 44.85752522
OS 32.26588924 44.8606926
OS 32.26842416 44.86196006
OS 32.272859 44.86639744
OS 32.27412646 44.86892982
OS 32.27856384 44.8733672
OS 32.28109622 44.87463466
OS 32.2855336 44.8790695
OS 32.28680106 44.88160442
OS 32.28996844 44.88476926
OS 32.29250336 44.88603672
OS 32.29503828 44.88857164
OS 32.2975732 44.8898391
OS 32.29884066 44.89237402
OS 32.30137558 44.89364148
OS 32.30390796 44.8961764
OS 32.31088026 44.89807632
OS 32.31848248 44.9018787
OS 32.3260847 44.90694854
OS 32.33622438 44.91075092
OS 32.34255914 44.91328584
OS 32.34572906 44.91645322
OS 32.34826144 44.91772068
OS 32.35713366 44.92152306
OS 32.36347096 44.92405798
OS 32.36600588 44.9253229
OS 32.37487556 44.9316602
OS 32.38691262 44.93609504
OS 32.39324992 44.93862996
OS 32.40148714 44.94306734
OS 32.40655698 44.94433226
OS 32.42429888 44.94686718
OS 32.43760594 44.95003456
OS 32.44394324 44.95256948
OS 32.45027546 44.95383694
OS 32.4680199 44.9551044
OS 32.48956418 44.95637186
OS 32.54151988 44.95763932
OS 32.90459002 44.95827178
OS 32.9083924 44.95700432
OE
SE
S P 0
OB 34.1952961 42.10883628 I
OS 34.20036594 42.10756882
OS 34.2067007 42.10630136
OS 34.21493792 42.10313144
OS 34.2250776 42.10059906
OS 34.24091958 42.0986966
OS 34.25105418 42.09616168
OS 34.25739148 42.09362676
OS 34.2592914 42.09172684
OS 34.271966 42.08792446
OS 34.28210314 42.086657
OS 34.30111504 42.07778732
OS 34.31124964 42.0752524
OS 34.32138932 42.07398494
OS 34.32835908 42.06828264
OS 34.33152646 42.06511526
OS 34.34039868 42.06004542
OS 34.34673344 42.05371066
OS 34.35307074 42.05117574
OS 34.3549732 42.05054074
OS 34.35560566 42.04990828
OS 34.3606755 42.04864082
OS 34.36827772 42.04103606
OS 34.3708101 42.0397686
OS 34.37334502 42.03723368
OS 34.37587994 42.03596876
OS 34.37904986 42.03153138
OS 34.38475216 42.02582908
OS 34.38728708 42.02456162
OS 34.39362184 42.01822432
OS 34.39615676 42.01695686
OS 34.40249406 42.01442448
OS 34.4075639 42.01315702
OS 34.41453366 42.00745218
OS 34.4189685 42.00301988
OS 34.42150342 42.00175242
OS 34.42847064 41.99478266
OS 34.4297381 41.99224774
OS 34.43164056 41.99034782
OS 34.43417548 41.98908036
OS 34.43987778 41.98337552
OS 34.44114524 41.9808406
OS 34.44748 41.97450584
OS 34.44874746 41.97197092
OS 34.45128238 41.96563362
OS 34.45254984 41.96056378
OS 34.45508476 41.9580314
OS 34.45635222 41.95549648
OS 34.46268952 41.94915918
OS 34.46395698 41.94662426
OS 34.46965928 41.93965704
OS 34.47282666 41.93648712
OS 34.47726404 41.92445006
OS 34.48043142 41.92001268
OS 34.48423126 41.9162103
OS 34.48549872 41.91367792
OS 34.4943684 41.90227078
OS 34.49690332 41.89973586
OS 34.49943824 41.88959872
OS 34.5007057 41.87946158
OS 34.50957792 41.86045222
OS 34.51211284 41.85031254
OS 34.51337776 41.84144286
OS 34.52098252 41.82496842
OS 34.52288498 41.81799866
OS 34.5241499 41.80405914
OS 34.52541736 41.79645438
OS 34.52731982 41.78948462
OS 34.52985474 41.78314732
OS 34.53238966 41.77427764
OS 34.53365712 41.76160558
OS 34.5361895 41.72738924
OS 34.53428958 41.70267758
OS 34.53302212 41.6874706
OS 34.53175466 41.67986838
OS 34.52795228 41.6697287
OS 34.52668482 41.66465886
OS 34.5247849 41.6576891
OS 34.52351744 41.64501958
OS 34.52224998 41.63614736
OS 34.52098252 41.63234498
OS 34.51464522 41.61840546
OS 34.51211284 41.60953324
OS 34.51084538 41.5993961
OS 34.49817078 41.57278452
OS 34.49310094 41.5639123
OS 34.48549872 41.54743786
OS 34.48043142 41.53856564
OS 34.47536158 41.52716104
OS 34.47029174 41.51829136
OS 34.46522444 41.51322406
OS 34.46395698 41.51068914
OS 34.4595196 41.5049843
OS 34.45698722 41.50371684
OS 34.44874746 41.49547962
OS 34.448115 41.4935797
OS 34.44558008 41.49231224
OS 34.43734286 41.48407502
OS 34.4360754 41.4815401
OS 34.42847064 41.4752028
OS 34.38791954 41.4346517
OS 34.38728708 41.43275178
OS 34.38475216 41.43148432
OS 34.37651494 41.4232471
OS 34.37524748 41.42071218
OS 34.3708101 41.41754226
OS 34.36384034 41.41183996
OS 34.3606755 41.40867258
OS 34.3543382 41.40613766
OS 34.34926836 41.40487274
OS 34.3429336 41.40107036
OS 34.34039868 41.39853544
OS 34.33152646 41.39473306
OS 34.32328924 41.39156568
OS 34.31631948 41.38713084
OS 34.30237996 41.38079354
OS 34.2833706 41.37192132
OS 34.2783033 41.37065386
OS 34.26182632 41.36938894
OS 34.25675902 41.36812148
OS 34.24471942 41.3636841
OS 34.23394982 41.36051672
OS 34.22887998 41.35924926
OS 34.21620538 41.3579818
OS 34.2073357 41.35671434
OS 34.1952961 41.35481442
OS 34.19022626 41.35354696
OS 34.18008912 41.34974458
OS 34.17375436 41.34847712
OS 34.16361468 41.34720966
OS 34.14650778 41.34531228
OS 34.12939834 41.34720966
OS 34.1192612 41.34847712
OS 34.1129239 41.34974458
OS 34.10595414 41.35291196
OS 34.09898438 41.35481442
OS 34.09137962 41.35608188
OS 34.07427272 41.3579818
OS 34.0609682 41.35988172
OS 34.05589836 41.36114918
OS 34.04766114 41.3643191
OS 34.03878892 41.36812148
OS 34.02991924 41.36938894
OS 34.0248494 41.37065386
OS 34.01661218 41.37382378
OS 34.00077274 41.38079354
OS 33.99190052 41.382061
OS 33.9842983 41.38332846
OS 33.97732854 41.38903076
OS 33.97415862 41.39219814
OS 33.96528894 41.39726798
OS 33.95895164 41.40360528
OS 33.95261434 41.40613766
OS 33.94437712 41.40930504
OS 33.9367749 41.41437488
OS 33.92980514 41.41754226
OS 33.919668 41.42134464
OS 33.91206324 41.4289494
OS 33.90952832 41.43021686
OS 33.9012911 41.43845408
OS 33.90065864 41.440354
OS 33.89812372 41.44162146
OS 33.84743294 41.49231224
OS 33.84489802 41.4935797
OS 33.83982818 41.50118446
OS 33.83285842 41.50815422
OS 33.8303235 41.51448898
OS 33.82652112 41.52462866
OS 33.82398874 41.52716104
OS 33.82272382 41.52969596
OS 33.81892144 41.53856564
OS 33.81575152 41.5468054
OS 33.8075143 41.55504262
OS 33.80624684 41.55757754
OS 33.79991208 41.56644722
OS 33.79737716 41.56898214
OS 33.79484224 41.57531944
OS 33.79357478 41.58418912
OS 33.79167232 41.59115888
OS 33.78913994 41.59749364
OS 33.78216764 41.61333562
OS 33.78026772 41.62537522
OS 33.77646534 41.6355149
OS 33.77456542 41.64248466
OS 33.77329796 41.64755196
OS 33.7713955 41.67733346
OS 33.77012804 41.7102798
OS 33.76949558 41.7463986
OS 33.77076304 41.75020098
OS 33.7720305 41.79582192
OS 33.77329796 41.7996243
OS 33.77456542 41.8173662
OS 33.7783678 41.82623334
OS 33.78090018 41.83510556
OS 33.78280264 41.8458777
OS 33.78533756 41.852215
OS 33.79230732 41.86678952
OS 33.79357478 41.8756592
OS 33.7954747 41.88389642
OS 33.79800962 41.89023118
OS 33.80117954 41.89339856
OS 33.80497938 41.90227078
OS 33.80624684 41.90734062
OS 33.81004922 41.91367792
OS 33.81638652 41.92001268
OS 33.81765398 41.9225476
OS 33.82335628 41.93078482
OS 33.8252562 41.93141982
OS 33.82652112 41.93395474
OS 33.8303235 41.94282442
OS 33.83539334 41.9516941
OS 33.84173064 41.9580314
OS 33.8429981 41.96056378
OS 33.89939118 42.01695686
OS 33.9012911 42.01759186
OS 33.90255856 42.02012678
OS 33.91079578 42.028364
OS 33.9133307 42.02963146
OS 33.919668 42.03596876
OS 33.92600276 42.03850114
OS 33.93424252 42.04167106
OS 33.93994482 42.04737336
OS 33.94247974 42.04864082
OS 33.94501212 42.05117574
OS 33.95134688 42.05497812
OS 33.95768418 42.06131288
OS 33.9716237 42.06638018
OS 33.98049592 42.07271748
OS 33.99253552 42.07715232
OS 33.99697036 42.07905478
OS 34.0071075 42.08538954
OS 34.02231448 42.08792446
OS 34.03435408 42.0923593
OS 34.04132384 42.09552922
OS 34.05146352 42.09806414
OS 34.06793542 42.0993316
OS 34.07300526 42.10059906
OS 34.08567732 42.10186652
OS 34.0894797 42.10313144
OS 34.10215176 42.10693382
OS 34.1072216 42.10820128
OS 34.1198962 42.10946874
OS 34.15411 42.11200366
OS 34.1952961 42.10883628
OE
SE
S P 0
OB -2.28224842 -38.48662356 I
OS -2.27485194 -38.48754812
OS -2.26560634 -38.48939724
OS -2.25543618 -38.49124636
OS -2.2434169 -38.49402004
OS -2.23232218 -38.49679372
OS -2.21937834 -38.50141652
OS -2.20735906 -38.50603932
OS -2.19441522 -38.51251124
OS -2.18147138 -38.51990772
OS -2.16852754 -38.52822876
OS -2.15650826 -38.53839892
OS -2.14541354 -38.54949364
OS -2.14448898 -38.5504182
OS -2.14263986 -38.55226732
OS -2.13986618 -38.55596556
OS -2.13616794 -38.56151292
OS -2.13154514 -38.56798484
OS -2.12692234 -38.57538132
OS -2.12137498 -38.58462692
OS -2.11582762 -38.59572164
OS -2.11028026 -38.60774092
OS -2.1047329 -38.62068476
OS -2.1001101 -38.63547772
OS -2.0954873 -38.65119524
OS -2.09178906 -38.66876188
OS -2.08901538 -38.68725308
OS -2.08716626 -38.70666884
OS -2.0862417 -38.72793372
OS -2.0862417 -38.72885828
OS -2.0862417 -38.73255652
OS -2.0862417 -38.73902844
OS -2.08716626 -38.74827404
OS -2.43387626 -38.74827404
OS -2.43387626 -38.7491986
OS -2.43387626 -38.75197228
OS -2.4329517 -38.75567052
OS -2.4329517 -38.76121788
OS -2.43202714 -38.7676898
OS -2.43017802 -38.77508628
OS -2.42740434 -38.79172836
OS -2.42185698 -38.81021956
OS -2.4144605 -38.83055988
OS -2.40429034 -38.84905108
OS -2.3913465 -38.86569316
OS -2.39042194 -38.86569316
OS -2.38949738 -38.86754228
OS -2.38395002 -38.87216508
OS -2.37562898 -38.878637
OS -2.36453426 -38.88510892
OS -2.3497413 -38.8925054
OS -2.33309922 -38.89897732
OS -2.31460802 -38.90360012
OS -2.30443786 -38.90452468
OS -2.29334314 -38.90544924
OS -2.28594666 -38.90544924
OS -2.27762562 -38.90452468
OS -2.26745546 -38.90267556
OS -2.25636074 -38.89990188
OS -2.2434169 -38.89620364
OS -2.23139762 -38.89065628
OS -2.21937834 -38.8832598
OS -2.21845378 -38.88233524
OS -2.21383098 -38.878637
OS -2.20828362 -38.87308964
OS -2.2018117 -38.86569316
OS -2.19441522 -38.855523
OS -2.18609418 -38.84257916
OS -2.17777314 -38.8277862
OS -2.17037666 -38.81021956
OS -2.08901538 -38.82038972
OS -2.08901538 -38.82131428
OS -2.08993994 -38.8231634
OS -2.0908645 -38.82686164
OS -2.09271362 -38.832409
OS -2.0954873 -38.83795636
OS -2.09826098 -38.84535284
OS -2.10565746 -38.86107036
OS -2.11490306 -38.878637
OS -2.1278469 -38.8971282
OS -2.14263986 -38.91469484
OS -2.16113106 -38.93133692
OS -2.16205562 -38.93133692
OS -2.16390474 -38.93318604
OS -2.16667842 -38.93503516
OS -2.17037666 -38.93780884
OS -2.17592402 -38.94058252
OS -2.18147138 -38.9433562
OS -2.18886786 -38.94705444
OS -2.1971889 -38.95075268
OS -2.2064345 -38.95445092
OS -2.2156801 -38.95814916
OS -2.2387941 -38.96369652
OS -2.26468178 -38.96831932
OS -2.29334314 -38.97016844
OS -2.3035133 -38.97016844
OS -2.30998522 -38.96924388
OS -2.31830626 -38.96831932
OS -2.32847642 -38.9664702
OS -2.33957114 -38.96462108
OS -2.35159042 -38.96277196
OS -2.3774781 -38.95537548
OS -2.3913465 -38.94982812
OS -2.40429034 -38.94428076
OS -2.41815874 -38.93688428
OS -2.43110258 -38.92856324
OS -2.44312186 -38.91931764
OS -2.45514114 -38.90822292
OS -2.4560657 -38.90729836
OS -2.45791482 -38.90544924
OS -2.4606885 -38.901751
OS -2.46438674 -38.89620364
OS -2.46900954 -38.88973172
OS -2.47363234 -38.88233524
OS -2.4791797 -38.87308964
OS -2.48472706 -38.86291948
OS -2.49027442 -38.8509002
OS -2.49582178 -38.83795636
OS -2.50044458 -38.8231634
OS -2.50506738 -38.80744588
OS -2.50876562 -38.7908038
OS -2.5115393 -38.7723126
OS -2.51338842 -38.75289684
OS -2.51431298 -38.73255652
OS -2.51431298 -38.73163196
OS -2.51431298 -38.72700916
OS -2.51431298 -38.7214618
OS -2.51338842 -38.71314076
OS -2.51246386 -38.7029706
OS -2.5115393 -38.69187588
OS -2.50969018 -38.67893204
OS -2.5069165 -38.6659882
OS -2.49952002 -38.63640228
OS -2.49489722 -38.62160932
OS -2.48934986 -38.6058918
OS -2.48195338 -38.59109884
OS -2.47363234 -38.57723044
OS -2.46438674 -38.56336204
OS -2.45421658 -38.5504182
OS -2.45329202 -38.54949364
OS -2.4514429 -38.54764452
OS -2.44774466 -38.54487084
OS -2.44312186 -38.54024804
OS -2.4375745 -38.53562524
OS -2.43017802 -38.53007788
OS -2.42185698 -38.52360596
OS -2.41168682 -38.5180586
OS -2.40151666 -38.51158668
OS -2.38949738 -38.50603932
OS -2.37655354 -38.50049196
OS -2.36268514 -38.49586916
OS -2.34789218 -38.49124636
OS -2.33217466 -38.48847268
OS -2.31553258 -38.48662356
OS -2.29796594 -38.485699
OS -2.28872034 -38.485699
OS -2.28224842 -38.48662356
OE
OB -3.95755114 -38.48662356 I
OS -3.94368274 -38.48754812
OS -3.92888978 -38.48939724
OS -3.91317226 -38.49309548
OS -3.89653018 -38.49679372
OS -3.88081266 -38.50234108
OS -3.8798881 -38.50234108
OS -3.87896354 -38.50326564
OS -3.87434074 -38.50511476
OS -3.86694426 -38.508813
OS -3.85769866 -38.5134358
OS -3.8475285 -38.51990772
OS -3.83735834 -38.5273042
OS -3.82811274 -38.53562524
OS -3.8197917 -38.54487084
OS -3.81886714 -38.5457954
OS -3.81701802 -38.54949364
OS -3.81331978 -38.55596556
OS -3.80869698 -38.56336204
OS -3.80407418 -38.57445676
OS -3.79945138 -38.58647604
OS -3.79575314 -38.60034444
OS -3.7920549 -38.61606196
OS -3.86879338 -38.62623212
OS -3.86879338 -38.624383
OS -3.86971794 -38.62068476
OS -3.87156706 -38.61421284
OS -3.87434074 -38.6058918
OS -3.87896354 -38.59757076
OS -3.8845109 -38.58832516
OS -3.89098282 -38.57907956
OS -3.90022842 -38.57075852
OS -3.90115298 -38.56983396
OS -3.90485122 -38.56798484
OS -3.91039858 -38.5642866
OS -3.91871962 -38.56058836
OS -3.92796522 -38.55689012
OS -3.9399845 -38.55319188
OS -3.95477746 -38.55134276
OS -3.97049498 -38.5504182
OS -3.97974058 -38.5504182
OS -3.98898618 -38.55134276
OS -4.00100546 -38.55226732
OS -4.01302474 -38.555041
OS -4.02596858 -38.55781468
OS -4.03798786 -38.56243748
OS -4.04815802 -38.5689094
OS -4.04908258 -38.56983396
OS -4.05185626 -38.57168308
OS -4.0555545 -38.57538132
OS -4.05925274 -38.58092868
OS -4.06387554 -38.58647604
OS -4.06757378 -38.59387252
OS -4.07034746 -38.60219356
OS -4.07127202 -38.6105146
OS -4.07127202 -38.61143916
OS -4.07127202 -38.61328828
OS -4.07034746 -38.61606196
OS -4.07034746 -38.6197602
OS -4.06757378 -38.6290058
OS -4.06202642 -38.6382514
OS -4.06110186 -38.63917596
OS -4.0601773 -38.64010052
OS -4.05832818 -38.6428742
OS -4.05462994 -38.64564788
OS -4.0509317 -38.64842156
OS -4.04538434 -38.6521198
OS -4.03891242 -38.65489348
OS -4.03151594 -38.65859172
OS -4.03059138 -38.65859172
OS -4.02874226 -38.65951628
OS -4.02504402 -38.66044084
OS -4.0185721 -38.66321452
OS -4.0093265 -38.6659882
OS -3.99730722 -38.66876188
OS -3.98991074 -38.67153556
OS -3.9815897 -38.67338468
OS -3.9723441 -38.67615836
OS -3.96217394 -38.67893204
OS -3.96124938 -38.67893204
OS -3.9584757 -38.6798566
OS -3.9538529 -38.68078116
OS -3.94830554 -38.68263028
OS -3.94183362 -38.6844794
OS -3.93351258 -38.68632852
OS -3.91594594 -38.69187588
OS -3.89653018 -38.69742324
OS -3.87711442 -38.70389516
OS -3.85954778 -38.71036708
OS -3.8521513 -38.71314076
OS -3.84567938 -38.71591444
OS -3.84383026 -38.716839
OS -3.84013202 -38.71868812
OS -3.83458466 -38.7214618
OS -3.82626362 -38.7260846
OS -3.81794258 -38.73163196
OS -3.80962154 -38.73902844
OS -3.8013005 -38.74734948
OS -3.79390402 -38.75659508
OS -3.79297946 -38.75751964
OS -3.79113034 -38.76121788
OS -3.7874321 -38.76676524
OS -3.78373386 -38.77508628
OS -3.78096018 -38.78525644
OS -3.77726194 -38.79635116
OS -3.77541282 -38.809295
OS -3.77448826 -38.82408796
OS -3.77448826 -38.82593708
OS -3.77448826 -38.83055988
OS -3.77541282 -38.83795636
OS -3.77726194 -38.84812652
OS -3.78003562 -38.85922124
OS -3.78465842 -38.87124052
OS -3.79020578 -38.88510892
OS -3.79760226 -38.89805276
OS -3.79852682 -38.89990188
OS -3.80222506 -38.90360012
OS -3.80684786 -38.91007204
OS -3.81424434 -38.91746852
OS -3.8244145 -38.92578956
OS -3.83550922 -38.93503516
OS -3.84845306 -38.9433562
OS -3.86417058 -38.95167724
OS -3.86509514 -38.95167724
OS -3.8660197 -38.9526018
OS -3.87156706 -38.95445092
OS -3.88081266 -38.9572246
OS -3.89283194 -38.96092284
OS -3.9076249 -38.96462108
OS -3.92426698 -38.96739476
OS -3.94183362 -38.96924388
OS -3.96217394 -38.97016844
OS -3.97049498 -38.97016844
OS -3.9769669 -38.96924388
OS -3.98436338 -38.96924388
OS -3.99360898 -38.96831932
OS -4.00285458 -38.96739476
OS -4.01302474 -38.96554564
OS -4.03521418 -38.96092284
OS -4.05832818 -38.95445092
OS -4.08051762 -38.94520532
OS -4.09068778 -38.93965796
OS -4.09993338 -38.93318604
OS -4.10085794 -38.93226148
OS -4.1017825 -38.93133692
OS -4.10732986 -38.92578956
OS -4.1156509 -38.91746852
OS -4.1248965 -38.90452468
OS -4.13506666 -38.88880716
OS -4.14523682 -38.87031596
OS -4.15355786 -38.84720196
OS -4.16002978 -38.82131428
OS -4.08236674 -38.809295
OS -4.08236674 -38.81021956
OS -4.08236674 -38.81114412
OS -4.08051762 -38.81669148
OS -4.0786685 -38.82593708
OS -4.07497026 -38.83610724
OS -4.07034746 -38.84720196
OS -4.0648001 -38.85922124
OS -4.05647906 -38.87124052
OS -4.0463089 -38.88141068
OS -4.04445978 -38.88233524
OS -4.04076154 -38.88510892
OS -4.03336506 -38.88880716
OS -4.02411946 -38.89342996
OS -4.01210018 -38.89805276
OS -3.99823178 -38.901751
OS -3.9815897 -38.90452468
OS -3.96217394 -38.90544924
OS -3.95292834 -38.90544924
OS -3.94368274 -38.90452468
OS -3.93166346 -38.90267556
OS -3.91871962 -38.89990188
OS -3.90485122 -38.89620364
OS -3.89283194 -38.89158084
OS -3.88173722 -38.88418436
OS -3.88081266 -38.8832598
OS -3.87711442 -38.88048612
OS -3.87341618 -38.87586332
OS -3.86786882 -38.8693914
OS -3.86324602 -38.86199492
OS -3.85862322 -38.85274932
OS -3.85584954 -38.84350372
OS -3.85492498 -38.832409
OS -3.85492498 -38.83148444
OS -3.85492498 -38.8277862
OS -3.85584954 -38.8231634
OS -3.85769866 -38.81669148
OS -3.86047234 -38.81021956
OS -3.86509514 -38.80374764
OS -3.8706425 -38.79635116
OS -3.87896354 -38.7908038
OS -3.8798881 -38.78987924
OS -3.88266178 -38.78895468
OS -3.88728458 -38.786181
OS -3.89468106 -38.78340732
OS -3.90577578 -38.77970908
OS -3.9122477 -38.7769354
OS -3.91964418 -38.77508628
OS -3.92796522 -38.7723126
OS -3.93721082 -38.76953892
OS -3.94738098 -38.76676524
OS -3.95940026 -38.76399156
OS -3.96032482 -38.76399156
OS -3.9630985 -38.763067
OS -3.9677213 -38.76214244
OS -3.97326866 -38.76029332
OS -3.98066514 -38.7584442
OS -3.98898618 -38.75567052
OS -4.00655282 -38.75104772
OS -4.02689314 -38.7445758
OS -4.0463089 -38.73902844
OS -4.0648001 -38.73255652
OS -4.07312114 -38.72885828
OS -4.07959306 -38.7260846
OS -4.08144218 -38.72516004
OS -4.08514042 -38.72331092
OS -4.09068778 -38.71961268
OS -4.09808426 -38.71498988
OS -4.1064053 -38.70851796
OS -4.11472634 -38.70112148
OS -4.12304738 -38.69280044
OS -4.13044386 -38.68263028
OS -4.13136842 -38.68170572
OS -4.13321754 -38.67800748
OS -4.13599122 -38.67153556
OS -4.1387649 -38.66413908
OS -4.14153858 -38.65489348
OS -4.14431226 -38.64379876
OS -4.14616138 -38.63270404
OS -4.14708594 -38.6197602
OS -4.14708594 -38.61791108
OS -4.14708594 -38.61421284
OS -4.14616138 -38.60866548
OS -4.14523682 -38.60034444
OS -4.1433877 -38.5920234
OS -4.14153858 -38.58185324
OS -4.13784034 -38.57260764
OS -4.13321754 -38.56243748
OS -4.13229298 -38.56151292
OS -4.13044386 -38.55781468
OS -4.12767018 -38.55319188
OS -4.12304738 -38.54671996
OS -4.11750002 -38.54024804
OS -4.1110281 -38.531927
OS -4.10363162 -38.52453052
OS -4.09438602 -38.5180586
OS -4.09346146 -38.51713404
OS -4.09068778 -38.51620948
OS -4.08698954 -38.5134358
OS -4.08144218 -38.51066212
OS -4.0740457 -38.50696388
OS -4.06572466 -38.50326564
OS -4.0555545 -38.4995674
OS -4.04445978 -38.49586916
OS -4.04261066 -38.4949446
OS -4.03891242 -38.49402004
OS -4.0324405 -38.49217092
OS -4.02411946 -38.4903218
OS -4.0139493 -38.48847268
OS -4.00285458 -38.48754812
OS -3.98991074 -38.485699
OS -3.9677213 -38.485699
OS -3.95755114 -38.48662356
OE
OB -4.17852098 -39.1375138 I
OS -4.69904826 -39.1375138
OS -4.69904826 -39.08111564
OS -4.17852098 -39.08111564
OS -4.17852098 -39.1375138
OE
OB -2.61231634 -38.95999828 I
OS -2.68535658 -38.95999828
OS -2.68535658 -38.901751
OS -2.68628114 -38.90267556
OS -2.6872057 -38.90452468
OS -2.68997938 -38.90822292
OS -2.69367762 -38.91284572
OS -2.69830042 -38.91746852
OS -2.70384778 -38.92301588
OS -2.7103197 -38.9294878
OS -2.71864074 -38.93595972
OS -2.72696178 -38.94243164
OS -2.73620738 -38.94890356
OS -2.7473021 -38.95445092
OS -2.75932138 -38.95907372
OS -2.77134066 -38.96369652
OS -2.78520906 -38.96739476
OS -2.80000202 -38.96924388
OS -2.81571954 -38.97016844
OS -2.8212669 -38.97016844
OS -2.82496514 -38.96924388
OS -2.83605986 -38.96831932
OS -2.8490037 -38.9664702
OS -2.86472122 -38.96277196
OS -2.88228786 -38.9572246
OS -2.8998545 -38.94982812
OS -2.91742114 -38.93965796
OS -2.9183457 -38.93965796
OS -2.91927026 -38.93780884
OS -2.92481762 -38.9341106
OS -2.93313866 -38.92671412
OS -2.94330882 -38.91746852
OS -2.9553281 -38.90544924
OS -2.96734738 -38.89065628
OS -2.97936666 -38.8740142
OS -2.98953682 -38.85459844
OS -2.98953682 -38.85367388
OS -2.99046138 -38.85182476
OS -2.99138594 -38.84905108
OS -2.99323506 -38.84535284
OS -2.99508418 -38.83980548
OS -2.99785786 -38.83333356
OS -2.99970698 -38.82686164
OS -3.0015561 -38.8185406
OS -3.0061789 -38.8000494
OS -3.0108017 -38.77878452
OS -3.01357538 -38.75474596
OS -3.01449994 -38.72885828
OS -3.01449994 -38.72793372
OS -3.01449994 -38.7260846
OS -3.01449994 -38.72238636
OS -3.01449994 -38.716839
OS -3.01357538 -38.71129164
OS -3.01357538 -38.70389516
OS -3.01172626 -38.68725308
OS -3.00895258 -38.66783732
OS -3.00432978 -38.64657244
OS -2.99878242 -38.624383
OS -2.99138594 -38.60311812
OS -2.99138594 -38.60219356
OS -2.99046138 -38.60034444
OS -2.98861226 -38.59757076
OS -2.98676314 -38.59387252
OS -2.98121578 -38.58370236
OS -2.9738193 -38.57075852
OS -2.9645737 -38.55689012
OS -2.95255442 -38.54302172
OS -2.93868602 -38.52822876
OS -2.92204394 -38.51620948
OS -2.92111938 -38.51620948
OS -2.92019482 -38.51528492
OS -2.91742114 -38.5134358
OS -2.9137229 -38.51158668
OS -2.9044773 -38.50696388
OS -2.89153346 -38.50049196
OS -2.8767405 -38.4949446
OS -2.85917386 -38.4903218
OS -2.8397581 -38.48662356
OS -2.81941778 -38.485699
OS -2.8120213 -38.485699
OS -2.80462482 -38.48662356
OS -2.79445466 -38.48754812
OS -2.78243538 -38.4903218
OS -2.76949154 -38.49309548
OS -2.7565477 -38.49771828
OS -2.74452842 -38.5041902
OS -2.7426793 -38.50511476
OS -2.73898106 -38.50696388
OS -2.7334337 -38.51158668
OS -2.72603722 -38.51620948
OS -2.71679162 -38.5226814
OS -2.70847058 -38.53100244
OS -2.69922498 -38.53932348
OS -2.69090394 -38.54949364
OS -2.69090394 -38.32020276
OS -2.61231634 -38.32020276
OS -2.61231634 -38.95999828
OE
OB -3.10695594 -38.95999828 I
OS -3.18554354 -38.95999828
OS -3.18554354 -38.32020276
OS -3.10695594 -38.32020276
OS -3.10695594 -38.95999828
OE
OB -3.4777045 -38.48662356 I
OS -3.46938346 -38.48754812
OS -3.46013786 -38.48939724
OS -3.4499677 -38.49124636
OS -3.43794842 -38.49309548
OS -3.4129853 -38.50141652
OS -3.40004146 -38.50603932
OS -3.38709762 -38.51251124
OS -3.37415378 -38.51898316
OS -3.36120994 -38.52822876
OS -3.34919066 -38.53747436
OS -3.33717138 -38.54856908
OS -3.33624682 -38.54949364
OS -3.3343977 -38.55134276
OS -3.33162402 -38.555041
OS -3.32792578 -38.5596638
OS -3.32330298 -38.56613572
OS -3.31775562 -38.57445676
OS -3.31220826 -38.58370236
OS -3.3066609 -38.59387252
OS -3.30111354 -38.60496724
OS -3.29556618 -38.61883564
OS -3.29001882 -38.63270404
OS -3.28539602 -38.64842156
OS -3.28169778 -38.66506364
OS -3.2789241 -38.68263028
OS -3.27707498 -38.70112148
OS -3.27615042 -38.7214618
OS -3.27615042 -38.72238636
OS -3.27615042 -38.72516004
OS -3.27615042 -38.72978284
OS -3.27615042 -38.73625476
OS -3.27707498 -38.74365124
OS -3.27799954 -38.75289684
OS -3.27799954 -38.76214244
OS -3.27984866 -38.7723126
OS -3.28262234 -38.7954266
OS -3.2881697 -38.8185406
OS -3.29464162 -38.8416546
OS -3.30388722 -38.86291948
OS -3.30388722 -38.86384404
OS -3.30481178 -38.8647686
OS -3.3066609 -38.86754228
OS -3.30851002 -38.87124052
OS -3.31498194 -38.88048612
OS -3.32330298 -38.89158084
OS -3.3343977 -38.90452468
OS -3.3482661 -38.91746852
OS -3.36398362 -38.93041236
OS -3.38247482 -38.94243164
OS -3.38339938 -38.94243164
OS -3.38432394 -38.9433562
OS -3.38709762 -38.94520532
OS -3.39172042 -38.94705444
OS -3.39634322 -38.94890356
OS -3.40189058 -38.95075268
OS -3.41575898 -38.95630004
OS -3.4314765 -38.96092284
OS -3.45089226 -38.96554564
OS -3.47123258 -38.96924388
OS -3.49342202 -38.97016844
OS -3.50266762 -38.97016844
OS -3.5100641 -38.96924388
OS -3.51838514 -38.96831932
OS -3.52763074 -38.9664702
OS -3.53872546 -38.96462108
OS -3.54982018 -38.96277196
OS -3.5747833 -38.95537548
OS -3.5886517 -38.94982812
OS -3.60159554 -38.94428076
OS -3.61453938 -38.93688428
OS -3.62748322 -38.92856324
OS -3.6395025 -38.91931764
OS -3.65152178 -38.90822292
OS -3.65244634 -38.90729836
OS -3.65429546 -38.90544924
OS -3.65706914 -38.901751
OS -3.66076738 -38.89620364
OS -3.66539018 -38.88973172
OS -3.67001298 -38.88233524
OS -3.67556034 -38.87308964
OS -3.6811077 -38.86199492
OS -3.68665506 -38.84997564
OS -3.69220242 -38.83610724
OS -3.69682522 -38.82131428
OS -3.70144802 -38.80559676
OS -3.70514626 -38.78803012
OS -3.70791994 -38.76953892
OS -3.70976906 -38.7491986
OS -3.71069362 -38.72793372
OS -3.71069362 -38.7260846
OS -3.71069362 -38.72238636
OS -3.70976906 -38.71591444
OS -3.70976906 -38.70666884
OS -3.7088445 -38.69649868
OS -3.70699538 -38.68355484
OS -3.70514626 -38.670611
OS -3.70144802 -38.65581804
OS -3.69774978 -38.64102508
OS -3.69312698 -38.62530756
OS -3.68757962 -38.60866548
OS -3.68018314 -38.59294796
OS -3.67278666 -38.578155
OS -3.6626165 -38.56336204
OS -3.65244634 -38.54949364
OS -3.6395025 -38.53747436
OS -3.63857794 -38.5365498
OS -3.63672882 -38.53562524
OS -3.63303058 -38.53285156
OS -3.62840778 -38.52915332
OS -3.62286042 -38.52545508
OS -3.61546394 -38.52083228
OS -3.60806746 -38.51620948
OS -3.59882186 -38.51158668
OS -3.5886517 -38.50696388
OS -3.57755698 -38.50234108
OS -3.55259386 -38.49402004
OS -3.5239325 -38.48754812
OS -3.50913954 -38.48662356
OS -3.49342202 -38.485699
OS -3.48417642 -38.485699
OS -3.4777045 -38.48662356
OE
OB -1.62211258 -38.42745172 I
OS -1.64337746 -38.54671996
OS -1.69237914 -38.54671996
OS -1.7117949 -38.42745172
OS -1.7117949 -38.32020276
OS -1.62211258 -38.32020276
OS -1.62211258 -38.42745172
OE
OB -5.97031826 -38.42745172 I
OS -5.99158314 -38.54671996
OS -6.04058482 -38.54671996
OS -6.06000058 -38.42745172
OS -6.06000058 -38.32020276
OS -5.97031826 -38.32020276
OS -5.97031826 -38.42745172
OE
OB -5.77800978 -38.49586916 I
OS -5.69849762 -38.49586916
OS -5.69849762 -38.55689012
OS -5.77800978 -38.55689012
OS -5.77800978 -38.82963532
OS -5.77800978 -38.83148444
OS -5.77800978 -38.83518268
OS -5.77800978 -38.84073004
OS -5.77708522 -38.84720196
OS -5.77616066 -38.86199492
OS -5.7752361 -38.86846684
OS -5.77431154 -38.87308964
OS -5.77338698 -38.87493876
OS -5.7706133 -38.878637
OS -5.76691506 -38.8832598
OS -5.76044314 -38.8878826
OS -5.75859402 -38.88880716
OS -5.75397122 -38.89065628
OS -5.74565018 -38.8925054
OS -5.7336309 -38.89342996
OS -5.7243853 -38.89342996
OS -5.7197625 -38.8925054
OS -5.71329058 -38.8925054
OS -5.7058941 -38.89158084
OS -5.69849762 -38.89065628
OS -5.68832746 -38.95999828
OS -5.69017658 -38.95999828
OS -5.69387482 -38.96092284
OS -5.70034674 -38.9618474
OS -5.70866778 -38.96277196
OS -5.71791338 -38.96462108
OS -5.72808354 -38.96554564
OS -5.74842386 -38.9664702
OS -5.75582034 -38.9664702
OS -5.76321682 -38.96554564
OS -5.77246242 -38.96462108
OS -5.78355714 -38.96369652
OS -5.79465186 -38.96092284
OS -5.80482202 -38.95814916
OS -5.81499218 -38.95352636
OS -5.81591674 -38.9526018
OS -5.81869042 -38.95075268
OS -5.82238866 -38.947979
OS -5.82793602 -38.9433562
OS -5.83255882 -38.9387334
OS -5.83810618 -38.93226148
OS -5.84365354 -38.92578956
OS -5.84735178 -38.91746852
OS -5.84735178 -38.91654396
OS -5.8492009 -38.91284572
OS -5.85012546 -38.9063738
OS -5.85197458 -38.8971282
OS -5.8538237 -38.88510892
OS -5.85474826 -38.87771244
OS -5.85474826 -38.8693914
OS -5.85567282 -38.85922124
OS -5.85659738 -38.84905108
OS -5.85659738 -38.83795636
OS -5.85659738 -38.82501252
OS -5.85659738 -38.55689012
OS -5.91484466 -38.55689012
OS -5.91484466 -38.49586916
OS -5.85659738 -38.49586916
OS -5.85659738 -38.38122372
OS -5.77800978 -38.33407116
OS -5.77800978 -38.49586916
OE
OB -1.80517546 -38.48662356 I
OS -1.7950053 -38.48847268
OS -1.78298602 -38.49217092
OS -1.77004218 -38.49679372
OS -1.75524922 -38.50326564
OS -1.7395317 -38.51158668
OS -1.76819306 -38.58370236
OS -1.76911762 -38.5827778
OS -1.77281586 -38.58092868
OS -1.77836322 -38.578155
OS -1.7857597 -38.57538132
OS -1.79408074 -38.57260764
OS -1.8042509 -38.56983396
OS -1.81442106 -38.56798484
OS -1.82459122 -38.56706028
OS -1.82921402 -38.56706028
OS -1.83383682 -38.56798484
OS -1.84030874 -38.5689094
OS -1.84678066 -38.57075852
OS -1.8551017 -38.5735322
OS -1.86342274 -38.57723044
OS -1.87081922 -38.5827778
OS -1.87174378 -38.58370236
OS -1.87451746 -38.58555148
OS -1.87729114 -38.58924972
OS -1.88191394 -38.59387252
OS -1.88653674 -38.60034444
OS -1.89115954 -38.60774092
OS -1.89578234 -38.61606196
OS -1.89948058 -38.62623212
OS -1.90040514 -38.62808124
OS -1.9013297 -38.6336286
OS -1.90317882 -38.64194964
OS -1.9059525 -38.65304436
OS -1.90872618 -38.66691276
OS -1.9105753 -38.68263028
OS -1.91149986 -38.69927236
OS -1.91242442 -38.71776356
OS -1.91242442 -38.95999828
OS -1.99101202 -38.95999828
OS -1.99101202 -38.49586916
OS -1.9198209 -38.49586916
OS -1.9198209 -38.56613572
OS -1.91889634 -38.56521116
OS -1.9151981 -38.55873924
OS -1.9105753 -38.5504182
OS -1.90317882 -38.54024804
OS -1.89578234 -38.53007788
OS -1.8874613 -38.51898316
OS -1.87914026 -38.50973756
OS -1.87081922 -38.50234108
OS -1.86989466 -38.50141652
OS -1.86712098 -38.4995674
OS -1.86157362 -38.49679372
OS -1.85602626 -38.49402004
OS -1.84862978 -38.49124636
OS -1.83938418 -38.48847268
OS -1.83013858 -38.48662356
OS -1.81996842 -38.485699
OS -1.8134965 -38.485699
OS -1.80517546 -38.48662356
OE
OB -4.90337602 -38.48662356 I
OS -4.8969041 -38.48754812
OS -4.8830357 -38.48939724
OS -4.86639362 -38.49309548
OS -4.84882698 -38.49864284
OS -4.83126034 -38.50696388
OS -4.8136937 -38.51713404
OS -4.81276914 -38.51713404
OS -4.81184458 -38.51898316
OS -4.80629722 -38.5226814
OS -4.79797618 -38.53007788
OS -4.78780602 -38.53932348
OS -4.7767113 -38.55134276
OS -4.76561658 -38.56613572
OS -4.75452186 -38.58370236
OS -4.74527626 -38.60311812
OS -4.74527626 -38.60404268
OS -4.7443517 -38.6058918
OS -4.74342714 -38.60866548
OS -4.74157802 -38.61236372
OS -4.7397289 -38.61791108
OS -4.73787978 -38.624383
OS -4.73325698 -38.63917596
OS -4.72863418 -38.65766716
OS -4.72493594 -38.67800748
OS -4.72216226 -38.70112148
OS -4.7212377 -38.72516004
OS -4.7212377 -38.7260846
OS -4.7212377 -38.72793372
OS -4.7212377 -38.73163196
OS -4.7212377 -38.73717932
OS -4.72216226 -38.74365124
OS -4.72216226 -38.75104772
OS -4.72401138 -38.7676898
OS -4.72770962 -38.78803012
OS -4.73233242 -38.809295
OS -4.73880434 -38.83148444
OS -4.74712538 -38.85367388
OS -4.74712538 -38.85459844
OS -4.74804994 -38.85644756
OS -4.74989906 -38.85922124
OS -4.75174818 -38.86291948
OS -4.7582201 -38.87308964
OS -4.76654114 -38.88603348
OS -4.7767113 -38.89990188
OS -4.78965514 -38.91377028
OS -4.8044481 -38.92763868
OS -4.82201474 -38.94058252
OS -4.8229393 -38.94058252
OS -4.82386386 -38.94150708
OS -4.82663754 -38.9433562
OS -4.83033578 -38.94520532
OS -4.83958138 -38.94982812
OS -4.85252522 -38.95537548
OS -4.86824274 -38.96092284
OS -4.88488482 -38.96554564
OS -4.90430058 -38.96924388
OS -4.92371634 -38.97016844
OS -4.93018826 -38.97016844
OS -4.93758474 -38.96924388
OS -4.94683034 -38.96831932
OS -4.95792506 -38.9664702
OS -4.96994434 -38.96369652
OS -4.98196362 -38.95999828
OS -4.9939829 -38.95445092
OS -4.99490746 -38.95352636
OS -4.99953026 -38.95167724
OS -5.00507762 -38.947979
OS -5.0124741 -38.94243164
OS -5.01987058 -38.93688428
OS -5.02911618 -38.9294878
OS -5.03743722 -38.92116676
OS -5.0448337 -38.91192116
OS -5.0448337 -39.1375138
OS -5.1234213 -39.1375138
OS -5.1234213 -38.49586916
OS -5.05223018 -38.49586916
OS -5.05223018 -38.55689012
OS -5.05130562 -38.555041
OS -5.04760738 -38.55134276
OS -5.04298458 -38.54487084
OS -5.0355881 -38.53747436
OS -5.02726706 -38.52822876
OS -5.01802146 -38.51990772
OS -5.00692674 -38.51158668
OS -4.99583202 -38.5041902
OS -4.9939829 -38.50326564
OS -4.99028466 -38.50141652
OS -4.98288818 -38.49864284
OS -4.97364258 -38.4949446
OS -4.96254786 -38.49124636
OS -4.94960402 -38.48847268
OS -4.93481106 -38.48662356
OS -4.91816898 -38.485699
OS -4.90799882 -38.485699
OS -4.90337602 -38.48662356
OE
OB -5.41743138 -38.48662356 I
OS -5.40911034 -38.48754812
OS -5.39986474 -38.48939724
OS -5.38969458 -38.49124636
OS -5.3776753 -38.49309548
OS -5.35271218 -38.50141652
OS -5.33976834 -38.50603932
OS -5.3268245 -38.51251124
OS -5.31388066 -38.51898316
OS -5.30093682 -38.52822876
OS -5.28891754 -38.53747436
OS -5.27689826 -38.54856908
OS -5.2759737 -38.54949364
OS -5.27412458 -38.55134276
OS -5.2713509 -38.555041
OS -5.26765266 -38.5596638
OS -5.26302986 -38.56613572
OS -5.2574825 -38.57445676
OS -5.25193514 -38.58370236
OS -5.24638778 -38.59387252
OS -5.24084042 -38.60496724
OS -5.23529306 -38.61883564
OS -5.2297457 -38.63270404
OS -5.2251229 -38.64842156
OS -5.22142466 -38.66506364
OS -5.21865098 -38.68263028
OS -5.21680186 -38.70112148
OS -5.2158773 -38.7214618
OS -5.2158773 -38.72238636
OS -5.2158773 -38.72516004
OS -5.2158773 -38.72978284
OS -5.2158773 -38.73625476
OS -5.21680186 -38.74365124
OS -5.21772642 -38.75289684
OS -5.21772642 -38.76214244
OS -5.21957554 -38.7723126
OS -5.22234922 -38.7954266
OS -5.22789658 -38.8185406
OS -5.2343685 -38.8416546
OS -5.2436141 -38.86291948
OS -5.2436141 -38.86384404
OS -5.24453866 -38.8647686
OS -5.24638778 -38.86754228
OS -5.2482369 -38.87124052
OS -5.25470882 -38.88048612
OS -5.26302986 -38.89158084
OS -5.27412458 -38.90452468
OS -5.28799298 -38.91746852
OS -5.3037105 -38.93041236
OS -5.3222017 -38.94243164
OS -5.32312626 -38.94243164
OS -5.32405082 -38.9433562
OS -5.3268245 -38.94520532
OS -5.3314473 -38.94705444
OS -5.3360701 -38.94890356
OS -5.34161746 -38.95075268
OS -5.35548586 -38.95630004
OS -5.37120338 -38.96092284
OS -5.39061914 -38.96554564
OS -5.41095946 -38.96924388
OS -5.4331489 -38.97016844
OS -5.4423945 -38.97016844
OS -5.44979098 -38.96924388
OS -5.45811202 -38.96831932
OS -5.46735762 -38.9664702
OS -5.47845234 -38.96462108
OS -5.48954706 -38.96277196
OS -5.51451018 -38.95537548
OS -5.52837858 -38.94982812
OS -5.54132242 -38.94428076
OS -5.55426626 -38.93688428
OS -5.5672101 -38.92856324
OS -5.57922938 -38.91931764
OS -5.59124866 -38.90822292
OS -5.59217322 -38.90729836
OS -5.59402234 -38.90544924
OS -5.59679602 -38.901751
OS -5.60049426 -38.89620364
OS -5.60511706 -38.88973172
OS -5.60973986 -38.88233524
OS -5.61528722 -38.87308964
OS -5.62083458 -38.86199492
OS -5.62638194 -38.84997564
OS -5.6319293 -38.83610724
OS -5.6365521 -38.82131428
OS -5.6411749 -38.80559676
OS -5.64487314 -38.78803012
OS -5.64764682 -38.76953892
OS -5.64949594 -38.7491986
OS -5.6504205 -38.72793372
OS -5.6504205 -38.7260846
OS -5.6504205 -38.72238636
OS -5.64949594 -38.71591444
OS -5.64949594 -38.70666884
OS -5.64857138 -38.69649868
OS -5.64672226 -38.68355484
OS -5.64487314 -38.670611
OS -5.6411749 -38.65581804
OS -5.63747666 -38.64102508
OS -5.63285386 -38.62530756
OS -5.6273065 -38.60866548
OS -5.61991002 -38.59294796
OS -5.61251354 -38.578155
OS -5.60234338 -38.56336204
OS -5.59217322 -38.54949364
OS -5.57922938 -38.53747436
OS -5.57830482 -38.5365498
OS -5.5764557 -38.53562524
OS -5.57275746 -38.53285156
OS -5.56813466 -38.52915332
OS -5.5625873 -38.52545508
OS -5.55519082 -38.52083228
OS -5.54779434 -38.51620948
OS -5.53854874 -38.51158668
OS -5.52837858 -38.50696388
OS -5.51728386 -38.50234108
OS -5.49232074 -38.49402004
OS -5.46365938 -38.48754812
OS -5.44886642 -38.48662356
OS -5.4331489 -38.485699
OS -5.4239033 -38.485699
OS -5.41743138 -38.48662356
OE
OB -2.29704138 -38.5504182 H
OS -2.30258874 -38.5504182
OS -2.30628698 -38.55134276
OS -2.31645714 -38.55226732
OS -2.32847642 -38.555041
OS -2.34326938 -38.5596638
OS -2.3589869 -38.56613572
OS -2.37377986 -38.57538132
OS -2.38857282 -38.5874006
OS -2.39042194 -38.58924972
OS -2.39412018 -38.59387252
OS -2.4005921 -38.60219356
OS -2.40706402 -38.61328828
OS -2.4144605 -38.62623212
OS -2.42093242 -38.6428742
OS -2.42647978 -38.66228996
OS -2.42925346 -38.68355484
OS -2.1694521 -38.68355484
OS -2.1694521 -38.68263028
OS -2.1694521 -38.68078116
OS -2.17037666 -38.67800748
OS -2.17037666 -38.67430924
OS -2.17222578 -38.66321452
OS -2.17499946 -38.65119524
OS -2.17962226 -38.63640228
OS -2.18424506 -38.62253388
OS -2.19164154 -38.60866548
OS -2.19996258 -38.5966462
OS -2.19996258 -38.59572164
OS -2.2018117 -38.59479708
OS -2.2064345 -38.58924972
OS -2.21475554 -38.58185324
OS -2.22585026 -38.5735322
OS -2.23971866 -38.56521116
OS -2.25636074 -38.55781468
OS -2.2757765 -38.55226732
OS -2.28594666 -38.55134276
OS -2.29704138 -38.5504182
OE
OB -4.92556546 -38.54764452 H
OS -4.93018826 -38.54764452
OS -4.9338865 -38.54856908
OS -4.9431321 -38.5504182
OS -4.95515138 -38.55319188
OS -4.96901978 -38.55873924
OS -4.98381274 -38.56706028
OS -4.99213378 -38.57260764
OS -4.99953026 -38.57907956
OS -5.00692674 -38.58647604
OS -5.01432322 -38.59479708
OS -5.01432322 -38.59572164
OS -5.01617234 -38.5966462
OS -5.01802146 -38.59941988
OS -5.01987058 -38.60311812
OS -5.02264426 -38.60866548
OS -5.0263425 -38.61421284
OS -5.03004074 -38.62160932
OS -5.03281442 -38.6290058
OS -5.03651266 -38.6382514
OS -5.0402109 -38.64842156
OS -5.04298458 -38.65951628
OS -5.04668282 -38.67153556
OS -5.04853194 -38.68540396
OS -5.05038106 -38.69927236
OS -5.05223018 -38.71406532
OS -5.05223018 -38.7307074
OS -5.05223018 -38.73163196
OS -5.05223018 -38.73440564
OS -5.05223018 -38.73902844
OS -5.05130562 -38.74550036
OS -5.05130562 -38.75289684
OS -5.05038106 -38.76121788
OS -5.04760738 -38.78063364
OS -5.04298458 -38.80282308
OS -5.03743722 -38.82408796
OS -5.02819162 -38.84535284
OS -5.02264426 -38.85459844
OS -5.01617234 -38.86291948
OS -5.01432322 -38.8647686
OS -5.00970042 -38.8693914
OS -5.00230394 -38.87678788
OS -4.99213378 -38.88418436
OS -4.97918994 -38.89158084
OS -4.96439698 -38.89897732
OS -4.9477549 -38.90360012
OS -4.9385093 -38.90452468
OS -4.9292637 -38.90544924
OS -4.92371634 -38.90544924
OS -4.9200181 -38.90452468
OS -4.9107725 -38.90267556
OS -4.89782866 -38.89990188
OS -4.88396026 -38.89435452
OS -4.8691673 -38.88695804
OS -4.85437434 -38.87586332
OS -4.84697786 -38.8693914
OS -4.83958138 -38.86199492
OS -4.83958138 -38.86107036
OS -4.83773226 -38.8601458
OS -4.83588314 -38.85737212
OS -4.83403402 -38.85367388
OS -4.83033578 -38.84905108
OS -4.8275621 -38.84257916
OS -4.82386386 -38.83610724
OS -4.82016562 -38.8277862
OS -4.81739194 -38.81946516
OS -4.8136937 -38.80837044
OS -4.80999546 -38.79727572
OS -4.80722178 -38.78525644
OS -4.80537266 -38.77138804
OS -4.80352354 -38.75659508
OS -4.80167442 -38.74087756
OS -4.80167442 -38.72423548
OS -4.80167442 -38.72331092
OS -4.80167442 -38.72053724
OS -4.80167442 -38.71591444
OS -4.80259898 -38.70944252
OS -4.80259898 -38.70204604
OS -4.80352354 -38.693725
OS -4.80629722 -38.67430924
OS -4.81092002 -38.65304436
OS -4.81739194 -38.63177948
OS -4.82663754 -38.6105146
OS -4.8321849 -38.60034444
OS -4.83865682 -38.5920234
OS -4.83865682 -38.59109884
OS -4.84050594 -38.59017428
OS -4.84512874 -38.58462692
OS -4.85252522 -38.578155
OS -4.86269538 -38.56983396
OS -4.87563922 -38.56151292
OS -4.89043218 -38.55411644
OS -4.90707426 -38.54949364
OS -4.91631986 -38.54856908
OS -4.92556546 -38.54764452
OE
OB -5.4331489 -38.5504182 H
OS -5.43869626 -38.5504182
OS -5.44331906 -38.55134276
OS -5.45348922 -38.55226732
OS -5.46735762 -38.55596556
OS -5.48307514 -38.56151292
OS -5.49971722 -38.5689094
OS -5.51543474 -38.58000412
OS -5.52375578 -38.5874006
OS -5.53115226 -38.59479708
OS -5.53115226 -38.59572164
OS -5.53300138 -38.5966462
OS -5.5348505 -38.59941988
OS -5.53762418 -38.60311812
OS -5.54039786 -38.60774092
OS -5.54317154 -38.61328828
OS -5.54686978 -38.62068476
OS -5.55056802 -38.62808124
OS -5.55426626 -38.63732684
OS -5.5579645 -38.64657244
OS -5.56073818 -38.65766716
OS -5.56351186 -38.66968644
OS -5.56628554 -38.68263028
OS -5.56813466 -38.69649868
OS -5.56905922 -38.7122162
OS -5.56998378 -38.72793372
OS -5.56998378 -38.72885828
OS -5.56998378 -38.73163196
OS -5.56998378 -38.73625476
OS -5.56905922 -38.74272668
OS -5.56905922 -38.75012316
OS -5.56813466 -38.7584442
OS -5.56536098 -38.77785996
OS -5.56073818 -38.8000494
OS -5.5533417 -38.82223884
OS -5.5440961 -38.84350372
OS -5.53762418 -38.85274932
OS -5.53115226 -38.86199492
OS -5.5302277 -38.86199492
OS -5.52930314 -38.86384404
OS -5.52375578 -38.86846684
OS -5.51543474 -38.87586332
OS -5.50434002 -38.8832598
OS -5.49047162 -38.89158084
OS -5.47382954 -38.89897732
OS -5.45441378 -38.90360012
OS -5.44424362 -38.90452468
OS -5.4331489 -38.90544924
OS -5.42760154 -38.90544924
OS -5.42297874 -38.90452468
OS -5.41280858 -38.90267556
OS -5.39894018 -38.89990188
OS -5.38414722 -38.89435452
OS -5.36750514 -38.88695804
OS -5.35178762 -38.87586332
OS -5.34346658 -38.86846684
OS -5.3360701 -38.86107036
OS -5.33514554 -38.8601458
OS -5.33422098 -38.85922124
OS -5.33237186 -38.85644756
OS -5.32959818 -38.85274932
OS -5.3268245 -38.84812652
OS -5.32312626 -38.84257916
OS -5.31942802 -38.83518268
OS -5.31572978 -38.8277862
OS -5.31203154 -38.8185406
OS -5.30925786 -38.80837044
OS -5.30555962 -38.79727572
OS -5.30278594 -38.78525644
OS -5.30001226 -38.77138804
OS -5.29816314 -38.75751964
OS -5.29631402 -38.74180212
OS -5.29631402 -38.72516004
OS -5.29631402 -38.72423548
OS -5.29631402 -38.7214618
OS -5.29631402 -38.716839
OS -5.29723858 -38.71129164
OS -5.29723858 -38.70389516
OS -5.29816314 -38.69557412
OS -5.30093682 -38.67615836
OS -5.30555962 -38.65581804
OS -5.3129561 -38.6336286
OS -5.32312626 -38.61328828
OS -5.32867362 -38.60311812
OS -5.3360701 -38.59479708
OS -5.3360701 -38.59387252
OS -5.33791922 -38.59294796
OS -5.34346658 -38.5874006
OS -5.35178762 -38.58092868
OS -5.36288234 -38.57260764
OS -5.37675074 -38.5642866
OS -5.39339282 -38.55689012
OS -5.41188402 -38.55226732
OS -5.42205418 -38.55134276
OS -5.4331489 -38.5504182
OE
OB -2.81109674 -38.5504182 H
OS -2.81571954 -38.5504182
OS -2.81941778 -38.55134276
OS -2.82958794 -38.55226732
OS -2.84160722 -38.55596556
OS -2.85547562 -38.56058836
OS -2.87026858 -38.5689094
OS -2.88506154 -38.57907956
OS -2.89245802 -38.58647604
OS -2.89892994 -38.59387252
OS -2.89892994 -38.59479708
OS -2.90077906 -38.59572164
OS -2.90170362 -38.59849532
OS -2.9044773 -38.60219356
OS -2.90725098 -38.60681636
OS -2.91002466 -38.61236372
OS -2.91279834 -38.61883564
OS -2.91649658 -38.62623212
OS -2.92019482 -38.63547772
OS -2.9229685 -38.64564788
OS -2.92574218 -38.6567426
OS -2.92851586 -38.66876188
OS -2.93036498 -38.68170572
OS -2.9322141 -38.69649868
OS -2.93406322 -38.7122162
OS -2.93406322 -38.72885828
OS -2.93406322 -38.72978284
OS -2.93406322 -38.73255652
OS -2.93406322 -38.73717932
OS -2.93313866 -38.74365124
OS -2.93313866 -38.75104772
OS -2.9322141 -38.75936876
OS -2.92944042 -38.77878452
OS -2.92481762 -38.8000494
OS -2.9183457 -38.82223884
OS -2.9091001 -38.84350372
OS -2.90355274 -38.85274932
OS -2.89708082 -38.86199492
OS -2.89615626 -38.86199492
OS -2.8952317 -38.86384404
OS -2.8906089 -38.86846684
OS -2.88228786 -38.87586332
OS -2.8721177 -38.8832598
OS -2.85917386 -38.89158084
OS -2.84345634 -38.89897732
OS -2.82681426 -38.90360012
OS -2.81756866 -38.90452468
OS -2.80832306 -38.90544924
OS -2.80370026 -38.90544924
OS -2.80000202 -38.90452468
OS -2.78983186 -38.90360012
OS -2.77781258 -38.89990188
OS -2.76394418 -38.89527908
OS -2.74915122 -38.8878826
OS -2.73435826 -38.87771244
OS -2.72696178 -38.87124052
OS -2.72048986 -38.86384404
OS -2.72048986 -38.86291948
OS -2.71864074 -38.86199492
OS -2.71679162 -38.85922124
OS -2.7149425 -38.855523
OS -2.71216882 -38.8509002
OS -2.70847058 -38.8462774
OS -2.7056969 -38.83888092
OS -2.70199866 -38.83148444
OS -2.69830042 -38.8231634
OS -2.69552674 -38.8139178
OS -2.6918285 -38.80282308
OS -2.68905482 -38.79172836
OS -2.6872057 -38.77878452
OS -2.68535658 -38.76584068
OS -2.68350746 -38.75104772
OS -2.68350746 -38.7353302
OS -2.68350746 -38.73440564
OS -2.68350746 -38.7307074
OS -2.68350746 -38.7260846
OS -2.68443202 -38.71961268
OS -2.68443202 -38.7122162
OS -2.68535658 -38.7029706
OS -2.68628114 -38.69280044
OS -2.68813026 -38.68170572
OS -2.69275306 -38.65951628
OS -2.69922498 -38.63640228
OS -2.70847058 -38.61421284
OS -2.71401794 -38.60496724
OS -2.72048986 -38.59572164
OS -2.72048986 -38.59479708
OS -2.72233898 -38.59387252
OS -2.72696178 -38.58832516
OS -2.73528282 -38.58092868
OS -2.74545298 -38.57260764
OS -2.75839682 -38.5642866
OS -2.77411434 -38.55781468
OS -2.79168098 -38.55226732
OS -2.80092658 -38.55134276
OS -2.81109674 -38.5504182
OE
OB -3.49342202 -38.5504182 H
OS -3.49896938 -38.5504182
OS -3.50359218 -38.55134276
OS -3.51376234 -38.55226732
OS -3.52763074 -38.55596556
OS -3.54334826 -38.56151292
OS -3.55999034 -38.5689094
OS -3.57570786 -38.58000412
OS -3.5840289 -38.5874006
OS -3.59142538 -38.59479708
OS -3.59142538 -38.59572164
OS -3.5932745 -38.5966462
OS -3.59512362 -38.59941988
OS -3.5978973 -38.60311812
OS -3.60067098 -38.60774092
OS -3.60344466 -38.61328828
OS -3.6071429 -38.62068476
OS -3.61084114 -38.62808124
OS -3.61453938 -38.63732684
OS -3.61823762 -38.64657244
OS -3.6210113 -38.65766716
OS -3.62378498 -38.66968644
OS -3.62655866 -38.68263028
OS -3.62840778 -38.69649868
OS -3.62933234 -38.7122162
OS -3.6302569 -38.72793372
OS -3.6302569 -38.72885828
OS -3.6302569 -38.73163196
OS -3.6302569 -38.73625476
OS -3.62933234 -38.74272668
OS -3.62933234 -38.75012316
OS -3.62840778 -38.7584442
OS -3.6256341 -38.77785996
OS -3.6210113 -38.8000494
OS -3.61361482 -38.82223884
OS -3.60436922 -38.84350372
OS -3.5978973 -38.85274932
OS -3.59142538 -38.86199492
OS -3.59050082 -38.86199492
OS -3.58957626 -38.86384404
OS -3.5840289 -38.86846684
OS -3.57570786 -38.87586332
OS -3.56461314 -38.8832598
OS -3.55074474 -38.89158084
OS -3.53410266 -38.89897732
OS -3.5146869 -38.90360012
OS -3.50451674 -38.90452468
OS -3.49342202 -38.90544924
OS -3.48787466 -38.90544924
OS -3.48325186 -38.90452468
OS -3.4730817 -38.90267556
OS -3.4592133 -38.89990188
OS -3.44442034 -38.89435452
OS -3.42777826 -38.88695804
OS -3.41206074 -38.87586332
OS -3.4037397 -38.86846684
OS -3.39634322 -38.86107036
OS -3.39541866 -38.8601458
OS -3.3944941 -38.85922124
OS -3.39264498 -38.85644756
OS -3.3898713 -38.85274932
OS -3.38709762 -38.84812652
OS -3.38339938 -38.84257916
OS -3.37970114 -38.83518268
OS -3.3760029 -38.8277862
OS -3.37230466 -38.8185406
OS -3.36953098 -38.80837044
OS -3.36583274 -38.79727572
OS -3.36305906 -38.78525644
OS -3.36028538 -38.77138804
OS -3.35843626 -38.75751964
OS -3.35658714 -38.74180212
OS -3.35658714 -38.72516004
OS -3.35658714 -38.72423548
OS -3.35658714 -38.7214618
OS -3.35658714 -38.716839
OS -3.3575117 -38.71129164
OS -3.3575117 -38.70389516
OS -3.35843626 -38.69557412
OS -3.36120994 -38.67615836
OS -3.36583274 -38.65581804
OS -3.37322922 -38.6336286
OS -3.38339938 -38.61328828
OS -3.38894674 -38.60311812
OS -3.39634322 -38.59479708
OS -3.39634322 -38.59387252
OS -3.39819234 -38.59294796
OS -3.4037397 -38.5874006
OS -3.41206074 -38.58092868
OS -3.42315546 -38.57260764
OS -3.43702386 -38.5642866
OS -3.45366594 -38.55689012
OS -3.47215714 -38.55226732
OS -3.4823273 -38.55134276
OS -3.49342202 -38.5504182
OE
SE
S P 0
OB -4.66714078 -36.5016923 I
OS -4.65465922 -36.5016923
OS -4.62553558 -36.50307914
OS -4.5950251 -36.50723966
OS -4.56174094 -36.51140018
OS -4.53123046 -36.51833438
OS -4.51597522 -36.5224949
OS -4.50349366 -36.52665542
OS -4.50210682 -36.52665542
OS -4.50071998 -36.52804226
OS -4.49239894 -36.53220278
OS -4.47991738 -36.53775014
OS -4.46466214 -36.54745802
OS -4.44802006 -36.55993958
OS -4.42999114 -36.57658166
OS -4.41334906 -36.59599742
OS -4.39670698 -36.61818686
OS -4.39670698 -36.6195737
OS -4.39532014 -36.62096054
OS -4.38977278 -36.62928158
OS -4.38422542 -36.64314998
OS -4.37590438 -36.6611789
OS -4.36897018 -36.6819815
OS -4.36203598 -36.70694462
OS -4.35787546 -36.73329458
OS -4.35648862 -36.76241822
OS -4.35648862 -36.76380506
OS -4.35648862 -36.76657874
OS -4.35648862 -36.7721261
OS -4.35787546 -36.7790603
OS -4.35787546 -36.78876818
OS -4.3592623 -36.79847606
OS -4.36480966 -36.82205234
OS -4.3731307 -36.84978914
OS -4.38422542 -36.87891278
OS -4.4008675 -36.90803642
OS -4.41196222 -36.92190482
OS -4.42305694 -36.93577322
OS -4.42444378 -36.93716006
OS -4.42583062 -36.9385469
OS -4.42999114 -36.94270742
OS -4.4355385 -36.94686794
OS -4.4424727 -36.9524153
OS -4.45079374 -36.95796266
OS -4.46188846 -36.96489686
OS -4.47298318 -36.9732179
OS -4.48685158 -36.9801521
OS -4.50210682 -36.9870863
OS -4.5187489 -36.99540734
OS -4.53677782 -37.00234154
OS -4.55758042 -37.0078889
OS -4.57838302 -37.0148231
OS -4.6019593 -37.01898362
OS -4.62692242 -37.02314414
OS -4.62414874 -37.02453098
OS -4.61860138 -37.02730466
OS -4.61028034 -37.03285202
OS -4.59918562 -37.03839938
OS -4.5742225 -37.05365462
OS -4.56174094 -37.0633625
OS -4.55064622 -37.07168354
OS -4.54787254 -37.07445722
OS -4.54093834 -37.08139142
OS -4.52984362 -37.09248614
OS -4.51597522 -37.10635454
OS -4.50071998 -37.1257703
OS -4.48269106 -37.1465729
OS -4.46466214 -37.17153602
OS -4.44524638 -37.19927282
OS -4.28021242 -37.45999874
OS -4.43831218 -37.45999874
OS -4.56451462 -37.26029378
OS -4.56451462 -37.25890694
OS -4.5672883 -37.25613326
OS -4.57006198 -37.25197274
OS -4.5742225 -37.24642538
OS -4.58393038 -37.23117014
OS -4.59641194 -37.21175438
OS -4.61166718 -37.19095178
OS -4.62692242 -37.16876234
OS -4.64217766 -37.14795974
OS -4.65604606 -37.12854398
OS -4.6574329 -37.12715714
OS -4.66159342 -37.12160978
OS -4.66852762 -37.11328874
OS -4.6782355 -37.10358086
OS -4.6990381 -37.08277826
OS -4.71013282 -37.07307038
OS -4.72122754 -37.06474934
OS -4.72261438 -37.0633625
OS -4.72538806 -37.06197566
OS -4.73093542 -37.05920198
OS -4.73925646 -37.05504146
OS -4.7475775 -37.05088094
OS -4.75728538 -37.04672042
OS -4.77947482 -37.03978622
OS -4.78086166 -37.03978622
OS -4.78363534 -37.03839938
OS -4.7891827 -37.03839938
OS -4.7961169 -37.03701254
OS -4.80582478 -37.0356257
OS -4.8169195 -37.0356257
OS -4.83217474 -37.03423886
OS -4.99582186 -37.03423886
OS -4.99582186 -37.45999874
OS -5.12341114 -37.45999874
OS -5.12341114 -36.50030546
OS -4.6782355 -36.50030546
OS -4.66714078 -36.5016923
OE
OB -1.0100437 -37.45999874 I
OS -1.13208562 -37.45999874
OS -1.13208562 -36.65701838
OS -1.4122273 -37.45999874
OS -1.52594818 -37.45999874
OS -1.80331618 -36.64314998
OS -1.80331618 -37.45999874
OS -1.9253581 -37.45999874
OS -1.9253581 -36.50030546
OS -1.73536102 -36.50030546
OS -1.50791926 -37.1812439
OS -1.50791926 -37.18263074
OS -1.50653242 -37.18540442
OS -1.50514558 -37.18956494
OS -1.5023719 -37.19649914
OS -1.49682454 -37.21314122
OS -1.48989034 -37.23394382
OS -1.48295614 -37.2575201
OS -1.4746351 -37.28109638
OS -1.4677009 -37.30328582
OS -1.46215354 -37.32270158
OS -1.4607667 -37.3199279
OS -1.45937986 -37.3129937
OS -1.45521934 -37.30051214
OS -1.44967198 -37.28387006
OS -1.44273778 -37.26168062
OS -1.4330299 -37.23533066
OS -1.42332202 -37.20482018
OS -1.41084046 -37.16876234
OS -1.18062502 -36.50030546
OS -1.0100437 -36.50030546
OS -1.0100437 -37.45999874
OE
OB -2.02382374 -37.45999874 I
OS -2.1680551 -37.45999874
OS -2.28038914 -37.16876234
OS -2.68257274 -37.16876234
OS -2.78658574 -37.45999874
OS -2.92110922 -37.45999874
OS -2.55498346 -36.50030546
OS -2.41629946 -36.50030546
OS -2.02382374 -37.45999874
OE
OB -3.02928274 -37.45999874 I
OS -3.16103254 -37.45999874
OS -3.66306862 -36.70694462
OS -3.66306862 -37.45999874
OS -3.78511054 -37.45999874
OS -3.78511054 -36.50030546
OS -3.65474758 -36.50030546
OS -3.15132466 -37.25474642
OS -3.15132466 -36.50030546
OS -3.02928274 -36.50030546
OS -3.02928274 -37.45999874
OE
OB -5.3231161 -36.61402634 I
OS -5.89033366 -36.61402634
OS -5.89033366 -36.90664958
OS -5.35917394 -36.90664958
OS -5.35917394 -37.02037046
OS -5.89033366 -37.02037046
OS -5.89033366 -37.34627786
OS -5.30092666 -37.34627786
OS -5.30092666 -37.45999874
OS -6.01792294 -37.45999874
OS -6.01792294 -36.50030546
OS -5.3231161 -36.50030546
OS -5.3231161 -36.61402634
OE
OB -0.10721086 -36.61402634 I
OS -0.67442842 -36.61402634
OS -0.67442842 -36.90664958
OS -0.1432687 -36.90664958
OS -0.1432687 -37.02037046
OS -0.67442842 -37.02037046
OS -0.67442842 -37.34627786
OS -0.08502142 -37.34627786
OS -0.08502142 -37.45999874
OS -0.8020177 -37.45999874
OS -0.8020177 -36.50030546
OS -0.10721086 -36.50030546
OS -0.10721086 -36.61402634
OE
OB -8.43241138 -37.34627786 I
OS -7.95949894 -37.34627786
OS -7.95949894 -37.45999874
OS -8.56000066 -37.45999874
OS -8.56000066 -36.50030546
OS -8.43241138 -36.50030546
OS -8.43241138 -37.34627786
OE
OB -6.51718534 -37.05365462 I
OS -6.51718534 -37.45999874
OS -6.64477462 -37.45999874
OS -6.64477462 -37.05365462
OS -7.0150609 -36.50030546
OS -6.86112166 -36.50030546
OS -6.67251142 -36.79154186
OS -6.67251142 -36.7929287
OS -6.66973774 -36.79570238
OS -6.66696406 -36.7998629
OS -6.66419038 -36.80541026
OS -6.65864302 -36.81234446
OS -6.65309566 -36.8206655
OS -6.6406141 -36.8414681
OS -6.62535886 -36.86643122
OS -6.60871678 -36.89416802
OS -6.59068786 -36.92329166
OS -6.57404578 -36.95380214
OS -6.57404578 -36.9524153
OS -6.57265894 -36.94964162
OS -6.56988526 -36.9454811
OS -6.56572474 -36.93993374
OS -6.56156422 -36.93299954
OS -6.55601686 -36.9246785
OS -6.5435353 -36.9038759
OS -6.52828006 -36.87891278
OS -6.51025114 -36.84978914
OS -6.48944854 -36.81789182
OS -6.4672591 -36.78322082
OS -6.28280938 -36.50030546
OS -6.1344175 -36.50030546
OS -6.51718534 -37.05365462
OE
OB -7.01644774 -37.45999874 I
OS -7.1606791 -37.45999874
OS -7.27301314 -37.16876234
OS -7.67519674 -37.16876234
OS -7.77920974 -37.45999874
OS -7.91373322 -37.45999874
OS -7.54760746 -36.50030546
OS -7.40892346 -36.50030546
OS -7.01644774 -37.45999874
OE
OB -7.48103914 -36.60015794 H
OS -7.48103914 -36.60154478
OS -7.48242598 -36.60431846
OS -7.48242598 -36.60986582
OS -7.48519966 -36.61541318
OS -7.4865865 -36.62512106
OS -7.48936018 -36.63482894
OS -7.49490754 -36.65840522
OS -7.50184174 -36.68614202
OS -7.51154962 -36.7166525
OS -7.5212575 -36.74993666
OS -7.53373906 -36.78460766
OS -7.63775206 -37.06474934
OS -7.3132315 -37.06474934
OS -7.41308398 -36.80124974
OS -7.41308398 -36.7998629
OS -7.41447082 -36.79570238
OS -7.4172445 -36.78876818
OS -7.42001818 -36.78044714
OS -7.4241787 -36.77073926
OS -7.42833922 -36.7582577
OS -7.43249974 -36.7443893
OS -7.4380471 -36.7305209
OS -7.44914182 -36.69862358
OS -7.46023654 -36.66533942
OS -7.47133126 -36.63205526
OS -7.48103914 -36.60015794
OE
OB -4.69349074 -36.60709214 H
OS -4.99582186 -36.60709214
OS -4.99582186 -36.9246785
OS -4.71013282 -36.9246785
OS -4.69349074 -36.92329166
OS -4.67407498 -36.92190482
OS -4.65188554 -36.92051798
OS -4.6296961 -36.9177443
OS -4.60750666 -36.91358378
OS -4.5880909 -36.90803642
OS -4.58531722 -36.90664958
OS -4.57976986 -36.9038759
OS -4.57144882 -36.89971538
OS -4.5603541 -36.89416802
OS -4.54787254 -36.88584698
OS -4.53539098 -36.8761391
OS -4.52290942 -36.86365754
OS -4.51320154 -36.84978914
OS -4.5118147 -36.8484023
OS -4.50904102 -36.84285494
OS -4.5048805 -36.8345339
OS -4.49933314 -36.82343918
OS -4.49517262 -36.81095762
OS -4.4910121 -36.79708922
OS -4.48823842 -36.78044714
OS -4.48685158 -36.76380506
OS -4.48685158 -36.76241822
OS -4.48685158 -36.76103138
OS -4.48823842 -36.75271034
OS -4.48962526 -36.74022878
OS -4.49239894 -36.7235867
OS -4.49933314 -36.70694462
OS -4.50765418 -36.68752886
OS -4.52013574 -36.66949994
OS -4.53677782 -36.65147102
OS -4.5395515 -36.65008418
OS -4.5464857 -36.64453682
OS -4.55758042 -36.63760262
OS -4.57560934 -36.62928158
OS -4.59641194 -36.62096054
OS -4.62414874 -36.61402634
OS -4.65604606 -36.60847898
OS -4.69349074 -36.60709214
OE
OB -2.48841514 -36.60015794 H
OS -2.48841514 -36.60154478
OS -2.48980198 -36.60431846
OS -2.48980198 -36.60986582
OS -2.49257566 -36.61541318
OS -2.4939625 -36.62512106
OS -2.49673618 -36.63482894
OS -2.50228354 -36.65840522
OS -2.50921774 -36.68614202
OS -2.51892562 -36.7166525
OS -2.5286335 -36.74993666
OS -2.54111506 -36.78460766
OS -2.64512806 -37.06474934
OS -2.3206075 -37.06474934
OS -2.42045998 -36.80124974
OS -2.42045998 -36.7998629
OS -2.42184682 -36.79570238
OS -2.4246205 -36.78876818
OS -2.42739418 -36.78044714
OS -2.4315547 -36.77073926
OS -2.43571522 -36.7582577
OS -2.43987574 -36.7443893
OS -2.4454231 -36.7305209
OS -2.45651782 -36.69862358
OS -2.46761254 -36.66533942
OS -2.47870726 -36.63205526
OS -2.48841514 -36.60015794
OE
SE
S P 0
OB 35.73690338 -37.45999874 I
OS 35.61486146 -37.45999874
OS 35.61486146 -36.65701838
OS 35.33471978 -37.45999874
OS 35.2209989 -37.45999874
OS 34.9436309 -36.64314998
OS 34.9436309 -37.45999874
OS 34.82158898 -37.45999874
OS 34.82158898 -36.50030546
OS 35.01158606 -36.50030546
OS 35.23902782 -37.1812439
OS 35.23902782 -37.18263074
OS 35.24041466 -37.18540442
OS 35.2418015 -37.18956494
OS 35.24457518 -37.19649914
OS 35.25012254 -37.21314122
OS 35.25705674 -37.23394382
OS 35.26399094 -37.2575201
OS 35.27231198 -37.28109638
OS 35.27924618 -37.30328582
OS 35.28479354 -37.32270158
OS 35.28618038 -37.3199279
OS 35.28756722 -37.3129937
OS 35.29172774 -37.30051214
OS 35.2972751 -37.28387006
OS 35.3042093 -37.26168062
OS 35.31391718 -37.23533066
OS 35.32362506 -37.20482018
OS 35.33610662 -37.16876234
OS 35.56632206 -36.50030546
OS 35.73690338 -36.50030546
OS 35.73690338 -37.45999874
OE
OB 34.61356298 -37.05504146 I
OS 34.61356298 -37.0564283
OS 34.61356298 -37.06197566
OS 34.61356298 -37.06890986
OS 34.61356298 -37.07861774
OS 34.61217614 -37.0910993
OS 34.61217614 -37.1049677
OS 34.6107893 -37.12160978
OS 34.60940246 -37.13825186
OS 34.60524194 -37.17569654
OS 34.59969458 -37.21452806
OS 34.59137354 -37.25197274
OS 34.58582618 -37.27000166
OS 34.58027882 -37.28664374
OS 34.58027882 -37.28803058
OS 34.57889198 -37.29080426
OS 34.5761183 -37.29496478
OS 34.57334462 -37.30051214
OS 34.56502358 -37.31576738
OS 34.55254202 -37.33518314
OS 34.53589994 -37.35737258
OS 34.51648418 -37.37956202
OS 34.49152106 -37.4031383
OS 34.46101058 -37.4239409
OS 34.45962374 -37.4239409
OS 34.45685006 -37.42671458
OS 34.45268954 -37.42810142
OS 34.44575534 -37.43226194
OS 34.4374343 -37.43642246
OS 34.42633958 -37.44058298
OS 34.41524486 -37.4447435
OS 34.40137646 -37.45029086
OS 34.38612122 -37.45583822
OS 34.36947914 -37.45999874
OS 34.35145022 -37.46415926
OS 34.33064762 -37.46831978
OS 34.30984502 -37.47109346
OS 34.28765558 -37.47386714
OS 34.23772934 -37.47664082
OS 34.22524778 -37.47664082
OS 34.2155399 -37.47525398
OS 34.20444518 -37.47525398
OS 34.19057678 -37.47386714
OS 34.17532154 -37.4724803
OS 34.1600663 -37.47109346
OS 34.1253953 -37.4655461
OS 34.08795062 -37.45722506
OS 34.05189278 -37.44613034
OS 34.01722178 -37.4308751
OS 34.01583494 -37.4308751
OS 34.01306126 -37.42810142
OS 34.00890074 -37.42532774
OS 34.00335338 -37.42255406
OS 33.98809814 -37.41145934
OS 33.97006922 -37.3962041
OS 33.94926662 -37.37678834
OS 33.92985086 -37.3545989
OS 33.9104351 -37.3268621
OS 33.89517986 -37.29635162
OS 33.89517986 -37.29496478
OS 33.89379302 -37.2921911
OS 33.89240618 -37.28664374
OS 33.8896325 -37.27970954
OS 33.88685882 -37.2713885
OS 33.88408514 -37.26029378
OS 33.87992462 -37.24781222
OS 33.87715094 -37.23255698
OS 33.87437726 -37.2159149
OS 33.87021674 -37.19788598
OS 33.86744306 -37.17847022
OS 33.86466938 -37.15766762
OS 33.8618957 -37.13409134
OS 33.86050886 -37.10912822
OS 33.85912202 -37.08277826
OS 33.85912202 -37.05504146
OS 33.85912202 -36.50030546
OS 33.9867113 -36.50030546
OS 33.9867113 -37.05504146
OS 33.9867113 -37.0564283
OS 33.9867113 -37.06058882
OS 33.9867113 -37.06752302
OS 33.9867113 -37.07584406
OS 33.98809814 -37.08555194
OS 33.98809814 -37.0980335
OS 33.98948498 -37.12438346
OS 33.99225866 -37.15489394
OS 33.99641918 -37.18540442
OS 34.00196654 -37.21452806
OS 34.00474022 -37.22700962
OS 34.00890074 -37.23949118
OS 34.01028758 -37.24226486
OS 34.01306126 -37.24919906
OS 34.01999546 -37.25890694
OS 34.0283165 -37.27277534
OS 34.03802438 -37.28664374
OS 34.05189278 -37.30189898
OS 34.06853486 -37.31715422
OS 34.08795062 -37.32963578
OS 34.0907243 -37.33102262
OS 34.0976585 -37.33518314
OS 34.11014006 -37.33934366
OS 34.12678214 -37.34489102
OS 34.1461979 -37.35182522
OS 34.17116102 -37.35598574
OS 34.19751098 -37.36014626
OS 34.22663462 -37.3615331
OS 34.24050302 -37.3615331
OS 34.24882406 -37.36014626
OS 34.26130562 -37.36014626
OS 34.27378718 -37.35875942
OS 34.30429766 -37.35321206
OS 34.33758182 -37.34627786
OS 34.36947914 -37.33518314
OS 34.39998962 -37.3199279
OS 34.41385802 -37.31022002
OS 34.42633958 -37.2991253
OS 34.42772642 -37.29773846
OS 34.42911326 -37.29635162
OS 34.43188694 -37.2921911
OS 34.43604746 -37.28664374
OS 34.44020798 -37.2783227
OS 34.44575534 -37.27000166
OS 34.4513027 -37.2575201
OS 34.45685006 -37.24503854
OS 34.46239742 -37.2297833
OS 34.46655794 -37.21175438
OS 34.4721053 -37.19095178
OS 34.47626582 -37.16876234
OS 34.48042634 -37.14379922
OS 34.48320002 -37.11744926
OS 34.4859737 -37.08693878
OS 34.4859737 -37.05504146
OS 34.4859737 -36.50030546
OS 34.61356298 -36.50030546
OS 34.61356298 -37.05504146
OE
OB 33.64416182 -37.45999874 I
OS 33.51241202 -37.45999874
OS 33.01037594 -36.70694462
OS 33.01037594 -37.45999874
OS 32.88833402 -37.45999874
OS 32.88833402 -36.50030546
OS 33.01869698 -36.50030546
OS 33.5221199 -37.25474642
OS 33.5221199 -36.50030546
OS 33.64416182 -36.50030546
OS 33.64416182 -37.45999874
OE
OB 38.19022334 -36.5016923 I
OS 38.2027049 -36.5016923
OS 38.23182854 -36.50307914
OS 38.26233902 -36.50723966
OS 38.29562318 -36.51140018
OS 38.32613366 -36.51833438
OS 38.3413889 -36.5224949
OS 38.35387046 -36.52665542
OS 38.3552573 -36.52665542
OS 38.35664414 -36.52804226
OS 38.36496518 -36.53220278
OS 38.37744674 -36.53775014
OS 38.39270198 -36.54745802
OS 38.40934406 -36.55993958
OS 38.42737298 -36.57658166
OS 38.44401506 -36.59599742
OS 38.46065714 -36.61818686
OS 38.46065714 -36.6195737
OS 38.46204398 -36.62096054
OS 38.46759134 -36.62928158
OS 38.4731387 -36.64314998
OS 38.48145974 -36.6611789
OS 38.48839394 -36.6819815
OS 38.49532814 -36.70694462
OS 38.49948866 -36.73329458
OS 38.5008755 -36.76241822
OS 38.5008755 -36.76380506
OS 38.5008755 -36.76657874
OS 38.5008755 -36.7721261
OS 38.49948866 -36.7790603
OS 38.49948866 -36.78876818
OS 38.49810182 -36.79847606
OS 38.49255446 -36.82205234
OS 38.48423342 -36.84978914
OS 38.4731387 -36.87891278
OS 38.45649662 -36.90803642
OS 38.4454019 -36.92190482
OS 38.43430718 -36.93577322
OS 38.43292034 -36.93716006
OS 38.4315335 -36.9385469
OS 38.42737298 -36.94270742
OS 38.42182562 -36.94686794
OS 38.41489142 -36.9524153
OS 38.40657038 -36.95796266
OS 38.39547566 -36.96489686
OS 38.38438094 -36.9732179
OS 38.37051254 -36.9801521
OS 38.3552573 -36.9870863
OS 38.33861522 -36.99540734
OS 38.3205863 -37.00234154
OS 38.2997837 -37.0078889
OS 38.2789811 -37.0148231
OS 38.25540482 -37.01898362
OS 38.2304417 -37.02314414
OS 38.23321538 -37.02453098
OS 38.23876274 -37.02730466
OS 38.24708378 -37.03285202
OS 38.2581785 -37.03839938
OS 38.28314162 -37.05365462
OS 38.29562318 -37.0633625
OS 38.3067179 -37.07168354
OS 38.30949158 -37.07445722
OS 38.31642578 -37.08139142
OS 38.3275205 -37.09248614
OS 38.3413889 -37.10635454
OS 38.35664414 -37.1257703
OS 38.37467306 -37.1465729
OS 38.39270198 -37.17153602
OS 38.41211774 -37.19927282
OS 38.5771517 -37.45999874
OS 38.41905194 -37.45999874
OS 38.2928495 -37.26029378
OS 38.2928495 -37.25890694
OS 38.29007582 -37.25613326
OS 38.28730214 -37.25197274
OS 38.28314162 -37.24642538
OS 38.27343374 -37.23117014
OS 38.26095218 -37.21175438
OS 38.24569694 -37.19095178
OS 38.2304417 -37.16876234
OS 38.21518646 -37.14795974
OS 38.20131806 -37.12854398
OS 38.19993122 -37.12715714
OS 38.1957707 -37.12160978
OS 38.1888365 -37.11328874
OS 38.17912862 -37.10358086
OS 38.15832602 -37.08277826
OS 38.1472313 -37.07307038
OS 38.13613658 -37.06474934
OS 38.13474974 -37.0633625
OS 38.13197606 -37.06197566
OS 38.1264287 -37.05920198
OS 38.11810766 -37.05504146
OS 38.10978662 -37.05088094
OS 38.10007874 -37.04672042
OS 38.0778893 -37.03978622
OS 38.07650246 -37.03978622
OS 38.07372878 -37.03839938
OS 38.06818142 -37.03839938
OS 38.06124722 -37.03701254
OS 38.05153934 -37.0356257
OS 38.04044462 -37.0356257
OS 38.02518938 -37.03423886
OS 37.86154226 -37.03423886
OS 37.86154226 -37.45999874
OS 37.73395298 -37.45999874
OS 37.73395298 -36.50030546
OS 38.17912862 -36.50030546
OS 38.19022334 -36.5016923
OE
OB 37.53424802 -36.61402634 I
OS 36.96703046 -36.61402634
OS 36.96703046 -36.90664958
OS 37.49819018 -36.90664958
OS 37.49819018 -37.02037046
OS 36.96703046 -37.02037046
OS 36.96703046 -37.34627786
OS 37.55643746 -37.34627786
OS 37.55643746 -37.45999874
OS 36.83944118 -37.45999874
OS 36.83944118 -36.50030546
OS 37.53424802 -36.50030546
OS 37.53424802 -36.61402634
OE
OB 36.32492354 -36.5016923 I
OS 36.33601826 -36.5016923
OS 36.36098138 -36.50446598
OS 36.38871818 -36.50723966
OS 36.41784182 -36.51278702
OS 36.44696546 -36.51972122
OS 36.47331542 -36.5294291
OS 36.47470226 -36.5294291
OS 36.4760891 -36.53081594
OS 36.48441014 -36.53497646
OS 36.4968917 -36.54191066
OS 36.5107601 -36.55161854
OS 36.52740218 -36.5641001
OS 36.5454311 -36.57935534
OS 36.56207318 -36.5987711
OS 36.57732842 -36.6195737
OS 36.57871526 -36.62234738
OS 36.58287578 -36.63066842
OS 36.58980998 -36.64176314
OS 36.59674418 -36.65840522
OS 36.60367838 -36.67782098
OS 36.61061258 -36.69862358
OS 36.6147731 -36.72219986
OS 36.61615994 -36.74577614
OS 36.61615994 -36.74854982
OS 36.61615994 -36.75548402
OS 36.6147731 -36.76796558
OS 36.61199942 -36.78322082
OS 36.6078389 -36.80124974
OS 36.6009047 -36.8206655
OS 36.59258366 -36.84008126
OS 36.58148894 -36.86088386
OS 36.5801021 -36.86365754
OS 36.57594158 -36.8692049
OS 36.56762054 -36.88029962
OS 36.55652582 -36.89139434
OS 36.54265742 -36.90526274
OS 36.52601534 -36.92051798
OS 36.50521274 -36.93438638
OS 36.48163646 -36.94825478
OS 36.4830233 -36.94825478
OS 36.48579698 -36.94964162
OS 36.4899575 -36.95102846
OS 36.49550486 -36.95380214
OS 36.51214694 -36.9593495
OS 36.5315627 -36.96905738
OS 36.5523653 -36.98153894
OS 36.57594158 -36.99679418
OS 36.59674418 -37.0148231
OS 36.61615994 -37.03701254
OS 36.61754678 -37.03978622
OS 36.62309414 -37.04810726
OS 36.63141518 -37.06058882
OS 36.63973622 -37.0772309
OS 36.64805726 -37.09942034
OS 36.6563783 -37.12299662
OS 36.66192566 -37.15073342
OS 36.6633125 -37.1812439
OS 36.6633125 -37.18263074
OS 36.6633125 -37.18401758
OS 36.6633125 -37.19233862
OS 36.66192566 -37.20620702
OS 36.65915198 -37.2228491
OS 36.6563783 -37.24226486
OS 36.65083094 -37.26306746
OS 36.64389674 -37.2852569
OS 36.63418886 -37.30744634
OS 36.63280202 -37.31022002
OS 36.6286415 -37.31715422
OS 36.62309414 -37.3268621
OS 36.6147731 -37.3407305
OS 36.60367838 -37.3545989
OS 36.59258366 -37.36985414
OS 36.57871526 -37.38510938
OS 36.56346002 -37.39759094
OS 36.56207318 -37.39897778
OS 36.55652582 -37.4031383
OS 36.54681794 -37.40868566
OS 36.53433638 -37.41423302
OS 36.51908114 -37.42255406
OS 36.50105222 -37.4308751
OS 36.48163646 -37.4378093
OS 36.45806018 -37.4447435
OS 36.4552865 -37.4447435
OS 36.44696546 -37.44751718
OS 36.43309706 -37.44890402
OS 36.41506814 -37.4516777
OS 36.3928787 -37.45445138
OS 36.36652874 -37.45722506
OS 36.3374051 -37.4586119
OS 36.30412094 -37.45999874
OS 35.93799518 -37.45999874
OS 35.93799518 -36.50030546
OS 36.31521566 -36.50030546
OS 36.32492354 -36.5016923
OE
OB 32.3849111 -36.61402634 I
OS 32.06871158 -36.61402634
OS 32.06871158 -37.45999874
OS 31.9411223 -37.45999874
OS 31.9411223 -36.61402634
OS 31.62492278 -36.61402634
OS 31.62492278 -36.50030546
OS 32.3849111 -36.50030546
OS 32.3849111 -36.61402634
OE
OB 30.62639798 -37.45999874 I
OS 30.48216662 -37.45999874
OS 30.36983258 -37.16876234
OS 29.96764898 -37.16876234
OS 29.86363598 -37.45999874
OS 29.7291125 -37.45999874
OS 30.09523826 -36.50030546
OS 30.23392226 -36.50030546
OS 30.62639798 -37.45999874
OE
OB 29.3546657 -36.5016923 I
OS 29.37824198 -36.50307914
OS 29.4032051 -36.50446598
OS 29.42678138 -36.50723966
OS 29.44758398 -36.51001334
OS 29.45035766 -36.51001334
OS 29.46006554 -36.51278702
OS 29.4725471 -36.5155607
OS 29.48918918 -36.51972122
OS 29.5072181 -36.52665542
OS 29.52663386 -36.53497646
OS 29.54743646 -36.54468434
OS 29.56546538 -36.55577906
OS 29.56823906 -36.5571659
OS 29.57378642 -36.56132642
OS 29.58210746 -36.56964746
OS 29.59320218 -36.57935534
OS 29.60568374 -36.5918369
OS 29.6181653 -36.60847898
OS 29.6320337 -36.6265079
OS 29.64312842 -36.6473105
OS 29.64451526 -36.65008418
OS 29.64728894 -36.65701838
OS 29.6528363 -36.66949994
OS 29.65838366 -36.68614202
OS 29.66254418 -36.70555778
OS 29.66809154 -36.72774722
OS 29.67086522 -36.75271034
OS 29.67225206 -36.7790603
OS 29.67225206 -36.78044714
OS 29.67225206 -36.78460766
OS 29.67225206 -36.79015502
OS 29.67086522 -36.7998629
OS 29.66947838 -36.80957078
OS 29.66809154 -36.82205234
OS 29.66531786 -36.83592074
OS 29.66254418 -36.85117598
OS 29.6528363 -36.8830733
OS 29.64728894 -36.89971538
OS 29.6389679 -36.9177443
OS 29.62926002 -36.93577322
OS 29.61955214 -36.9524153
OS 29.60707058 -36.96905738
OS 29.59320218 -36.98569946
OS 29.59181534 -36.9870863
OS 29.58904166 -36.98985998
OS 29.58488114 -36.9940205
OS 29.57794694 -36.99818102
OS 29.5696259 -37.00511522
OS 29.55853118 -37.01204942
OS 29.54466278 -37.02037046
OS 29.52940754 -37.02730466
OS 29.51137862 -37.0356257
OS 29.49057602 -37.04394674
OS 29.46838658 -37.05088094
OS 29.44203662 -37.0564283
OS 29.41429982 -37.06197566
OS 29.38378934 -37.06613618
OS 29.34911834 -37.06890986
OS 29.3130605 -37.0702967
OS 29.06758982 -37.0702967
OS 29.06758982 -37.45999874
OS 28.94000054 -37.45999874
OS 28.94000054 -36.50030546
OS 29.3338631 -36.50030546
OS 29.3546657 -36.5016923
OE
OB 31.18668134 -36.5016923 I
OS 31.1991629 -36.5016923
OS 31.22828654 -36.50307914
OS 31.25879702 -36.50723966
OS 31.29208118 -36.51140018
OS 31.32259166 -36.51833438
OS 31.3378469 -36.5224949
OS 31.35032846 -36.52665542
OS 31.3517153 -36.52665542
OS 31.35310214 -36.52804226
OS 31.36142318 -36.53220278
OS 31.37390474 -36.53775014
OS 31.38915998 -36.54745802
OS 31.40580206 -36.55993958
OS 31.42383098 -36.57658166
OS 31.44047306 -36.59599742
OS 31.45711514 -36.61818686
OS 31.45711514 -36.6195737
OS 31.45850198 -36.62096054
OS 31.46404934 -36.62928158
OS 31.4695967 -36.64314998
OS 31.47791774 -36.6611789
OS 31.48485194 -36.6819815
OS 31.49178614 -36.70694462
OS 31.49594666 -36.73329458
OS 31.4973335 -36.76241822
OS 31.4973335 -36.76380506
OS 31.4973335 -36.76657874
OS 31.4973335 -36.7721261
OS 31.49594666 -36.7790603
OS 31.49594666 -36.78876818
OS 31.49455982 -36.79847606
OS 31.48901246 -36.82205234
OS 31.48069142 -36.84978914
OS 31.4695967 -36.87891278
OS 31.45295462 -36.90803642
OS 31.4418599 -36.92190482
OS 31.43076518 -36.93577322
OS 31.42937834 -36.93716006
OS 31.4279915 -36.9385469
OS 31.42383098 -36.94270742
OS 31.41828362 -36.94686794
OS 31.41134942 -36.9524153
OS 31.40302838 -36.95796266
OS 31.39193366 -36.96489686
OS 31.38083894 -36.9732179
OS 31.36697054 -36.9801521
OS 31.3517153 -36.9870863
OS 31.33507322 -36.99540734
OS 31.3170443 -37.00234154
OS 31.2962417 -37.0078889
OS 31.2754391 -37.0148231
OS 31.25186282 -37.01898362
OS 31.2268997 -37.02314414
OS 31.22967338 -37.02453098
OS 31.23522074 -37.02730466
OS 31.24354178 -37.03285202
OS 31.2546365 -37.03839938
OS 31.27959962 -37.05365462
OS 31.29208118 -37.0633625
OS 31.3031759 -37.07168354
OS 31.30594958 -37.07445722
OS 31.31288378 -37.08139142
OS 31.3239785 -37.09248614
OS 31.3378469 -37.10635454
OS 31.35310214 -37.1257703
OS 31.37113106 -37.1465729
OS 31.38915998 -37.17153602
OS 31.40857574 -37.19927282
OS 31.5736097 -37.45999874
OS 31.41550994 -37.45999874
OS 31.2893075 -37.26029378
OS 31.2893075 -37.25890694
OS 31.28653382 -37.25613326
OS 31.28376014 -37.25197274
OS 31.27959962 -37.24642538
OS 31.26989174 -37.23117014
OS 31.25741018 -37.21175438
OS 31.24215494 -37.19095178
OS 31.2268997 -37.16876234
OS 31.21164446 -37.14795974
OS 31.19777606 -37.12854398
OS 31.19638922 -37.12715714
OS 31.1922287 -37.12160978
OS 31.1852945 -37.11328874
OS 31.17558662 -37.10358086
OS 31.15478402 -37.08277826
OS 31.1436893 -37.07307038
OS 31.13259458 -37.06474934
OS 31.13120774 -37.0633625
OS 31.12843406 -37.06197566
OS 31.1228867 -37.05920198
OS 31.11456566 -37.05504146
OS 31.10624462 -37.05088094
OS 31.09653674 -37.04672042
OS 31.0743473 -37.03978622
OS 31.07296046 -37.03978622
OS 31.07018678 -37.03839938
OS 31.06463942 -37.03839938
OS 31.05770522 -37.03701254
OS 31.04799734 -37.0356257
OS 31.03690262 -37.0356257
OS 31.02164738 -37.03423886
OS 30.85800026 -37.03423886
OS 30.85800026 -37.45999874
OS 30.73041098 -37.45999874
OS 30.73041098 -36.50030546
OS 31.17558662 -36.50030546
OS 31.18668134 -36.5016923
OE
OB 38.16387338 -36.60709214 H
OS 37.86154226 -36.60709214
OS 37.86154226 -36.9246785
OS 38.1472313 -36.9246785
OS 38.16387338 -36.92329166
OS 38.18328914 -36.92190482
OS 38.20547858 -36.92051798
OS 38.22766802 -36.9177443
OS 38.24985746 -36.91358378
OS 38.26927322 -36.90803642
OS 38.2720469 -36.90664958
OS 38.27759426 -36.9038759
OS 38.2859153 -36.89971538
OS 38.29701002 -36.89416802
OS 38.30949158 -36.88584698
OS 38.32197314 -36.8761391
OS 38.3344547 -36.86365754
OS 38.34416258 -36.84978914
OS 38.34554942 -36.8484023
OS 38.3483231 -36.84285494
OS 38.35248362 -36.8345339
OS 38.35803098 -36.82343918
OS 38.3621915 -36.81095762
OS 38.36635202 -36.79708922
OS 38.3691257 -36.78044714
OS 38.37051254 -36.76380506
OS 38.37051254 -36.76241822
OS 38.37051254 -36.76103138
OS 38.3691257 -36.75271034
OS 38.36773886 -36.74022878
OS 38.36496518 -36.7235867
OS 38.35803098 -36.70694462
OS 38.34970994 -36.68752886
OS 38.33722838 -36.66949994
OS 38.3205863 -36.65147102
OS 38.31781262 -36.65008418
OS 38.31087842 -36.64453682
OS 38.2997837 -36.63760262
OS 38.28175478 -36.62928158
OS 38.26095218 -36.62096054
OS 38.23321538 -36.61402634
OS 38.20131806 -36.60847898
OS 38.16387338 -36.60709214
OE
OB 29.34218414 -36.61402634 H
OS 29.06758982 -36.61402634
OS 29.06758982 -36.95657582
OS 29.32554206 -36.95657582
OS 29.33524994 -36.95518898
OS 29.34495782 -36.95518898
OS 29.35605254 -36.95380214
OS 29.3824025 -36.95102846
OS 29.41152614 -36.9454811
OS 29.44064978 -36.93716006
OS 29.46699974 -36.92606534
OS 29.4794813 -36.91913114
OS 29.48918918 -36.9108101
OS 29.49196286 -36.90803642
OS 29.49751022 -36.90248906
OS 29.50583126 -36.89139434
OS 29.51553914 -36.87752594
OS 29.52524702 -36.85949702
OS 29.53356806 -36.83730758
OS 29.53911542 -36.81234446
OS 29.5418891 -36.78322082
OS 29.5418891 -36.78183398
OS 29.5418891 -36.78044714
OS 29.5418891 -36.77351294
OS 29.54050226 -36.76103138
OS 29.53772858 -36.74716298
OS 29.5349549 -36.73190774
OS 29.52940754 -36.71387882
OS 29.5210865 -36.69723674
OS 29.51137862 -36.68059466
OS 29.50999178 -36.67920782
OS 29.50583126 -36.67366046
OS 29.49889706 -36.66672626
OS 29.49057602 -36.65701838
OS 29.47809446 -36.6473105
OS 29.46422606 -36.63898946
OS 29.44897082 -36.63066842
OS 29.4309419 -36.62373422
OS 29.42955506 -36.62373422
OS 29.4240077 -36.62234738
OS 29.41568666 -36.62096054
OS 29.40459194 -36.61818686
OS 29.38794986 -36.61680002
OS 29.36714726 -36.61541318
OS 29.34218414 -36.61402634
OE
OB 30.16180658 -36.60015794 H
OS 30.16180658 -36.60154478
OS 30.16041974 -36.60431846
OS 30.16041974 -36.60986582
OS 30.15764606 -36.61541318
OS 30.15625922 -36.62512106
OS 30.15348554 -36.63482894
OS 30.14793818 -36.65840522
OS 30.14100398 -36.68614202
OS 30.1312961 -36.7166525
OS 30.12158822 -36.74993666
OS 30.10910666 -36.78460766
OS 30.00509366 -37.06474934
OS 30.32961422 -37.06474934
OS 30.22976174 -36.80124974
OS 30.22976174 -36.7998629
OS 30.2283749 -36.79570238
OS 30.22560122 -36.78876818
OS 30.22282754 -36.78044714
OS 30.21866702 -36.77073926
OS 30.2145065 -36.7582577
OS 30.21034598 -36.7443893
OS 30.20479862 -36.7305209
OS 30.1937039 -36.69862358
OS 30.18260918 -36.66533942
OS 30.17151446 -36.63205526
OS 30.16180658 -36.60015794
OE
OB 31.16033138 -36.60709214 H
OS 30.85800026 -36.60709214
OS 30.85800026 -36.9246785
OS 31.1436893 -36.9246785
OS 31.16033138 -36.92329166
OS 31.17974714 -36.92190482
OS 31.20193658 -36.92051798
OS 31.22412602 -36.9177443
OS 31.24631546 -36.91358378
OS 31.26573122 -36.90803642
OS 31.2685049 -36.90664958
OS 31.27405226 -36.9038759
OS 31.2823733 -36.89971538
OS 31.29346802 -36.89416802
OS 31.30594958 -36.88584698
OS 31.31843114 -36.8761391
OS 31.3309127 -36.86365754
OS 31.34062058 -36.84978914
OS 31.34200742 -36.8484023
OS 31.3447811 -36.84285494
OS 31.34894162 -36.8345339
OS 31.35448898 -36.82343918
OS 31.3586495 -36.81095762
OS 31.36281002 -36.79708922
OS 31.3655837 -36.78044714
OS 31.36697054 -36.76380506
OS 31.36697054 -36.76241822
OS 31.36697054 -36.76103138
OS 31.3655837 -36.75271034
OS 31.36419686 -36.74022878
OS 31.36142318 -36.7235867
OS 31.35448898 -36.70694462
OS 31.34616794 -36.68752886
OS 31.33368638 -36.66949994
OS 31.3170443 -36.65147102
OS 31.31427062 -36.65008418
OS 31.30733642 -36.64453682
OS 31.2962417 -36.63760262
OS 31.27821278 -36.62928158
OS 31.25741018 -36.62096054
OS 31.22967338 -36.61402634
OS 31.19777606 -36.60847898
OS 31.16033138 -36.60709214
OE
OB 36.29302622 -36.61402634 H
OS 36.06558446 -36.61402634
OS 36.06558446 -36.90248906
OS 36.30134726 -36.90248906
OS 36.31937618 -36.90110222
OS 36.33879194 -36.89971538
OS 36.3582077 -36.89832854
OS 36.37762346 -36.89555486
OS 36.3928787 -36.89278118
OS 36.39565238 -36.89139434
OS 36.40119974 -36.8900075
OS 36.40952078 -36.88584698
OS 36.4206155 -36.88029962
OS 36.43171022 -36.87475226
OS 36.44419178 -36.86643122
OS 36.45667334 -36.8553365
OS 36.46638122 -36.84424178
OS 36.46776806 -36.84285494
OS 36.47054174 -36.83869442
OS 36.47470226 -36.83037338
OS 36.47886278 -36.8206655
OS 36.4830233 -36.80957078
OS 36.48718382 -36.79570238
OS 36.4899575 -36.7790603
OS 36.49134434 -36.76103138
OS 36.49134434 -36.7582577
OS 36.49134434 -36.75271034
OS 36.4899575 -36.7443893
OS 36.48857066 -36.73329458
OS 36.48579698 -36.71942618
OS 36.48163646 -36.70555778
OS 36.4760891 -36.69168938
OS 36.46776806 -36.67782098
OS 36.46638122 -36.67643414
OS 36.46360754 -36.67227362
OS 36.45806018 -36.66533942
OS 36.45112598 -36.65840522
OS 36.4414181 -36.65008418
OS 36.43032338 -36.64176314
OS 36.41645498 -36.6334421
OS 36.40119974 -36.62789474
OS 36.3998129 -36.62789474
OS 36.3928787 -36.62512106
OS 36.38317082 -36.62373422
OS 36.36791558 -36.62096054
OS 36.34711298 -36.61818686
OS 36.3235367 -36.61680002
OS 36.29302622 -36.61402634
OE
OB 36.31798934 -37.01620994 H
OS 36.06558446 -37.01620994
OS 36.06558446 -37.34627786
OS 36.33879194 -37.34627786
OS 36.36791558 -37.34489102
OS 36.38039714 -37.34350418
OS 36.39149186 -37.34211734
OS 36.3928787 -37.34211734
OS 36.39842606 -37.3407305
OS 36.4067471 -37.33934366
OS 36.41645498 -37.33656998
OS 36.44003126 -37.32824894
OS 36.46360754 -37.31715422
OS 36.46499438 -37.31576738
OS 36.4691549 -37.3129937
OS 36.47470226 -37.30883318
OS 36.48163646 -37.30328582
OS 36.48857066 -37.29496478
OS 36.49827854 -37.28664374
OS 36.50521274 -37.27554902
OS 36.51353378 -37.26306746
OS 36.51492062 -37.26168062
OS 36.51630746 -37.2575201
OS 36.51908114 -37.24919906
OS 36.52324166 -37.23949118
OS 36.52740218 -37.22839646
OS 36.53017586 -37.21452806
OS 36.5315627 -37.19788598
OS 36.53294954 -37.1812439
OS 36.53294954 -37.17847022
OS 36.53294954 -37.17292286
OS 36.5315627 -37.16182814
OS 36.52878902 -37.14934658
OS 36.52601534 -37.13547818
OS 36.52046798 -37.12022294
OS 36.51353378 -37.1049677
OS 36.5038259 -37.08971246
OS 36.50243906 -37.08832562
OS 36.49827854 -37.08277826
OS 36.49273118 -37.07584406
OS 36.48441014 -37.06752302
OS 36.47331542 -37.05781514
OS 36.45944702 -37.04810726
OS 36.44419178 -37.03978622
OS 36.42616286 -37.03285202
OS 36.42338918 -37.03146518
OS 36.41784182 -37.03007834
OS 36.40536026 -37.02730466
OS 36.39010502 -37.02453098
OS 36.37068926 -37.0217573
OS 36.34711298 -37.01898362
OS 36.31798934 -37.01620994
OE
SE
S P 0
OB 40.9056459 -38.32112732 I
OS 40.92136342 -38.32205188
OS 40.9380055 -38.32297644
OS 40.95372302 -38.32482556
OS 40.96759142 -38.32667468
OS 40.96944054 -38.32667468
OS 40.97591246 -38.3285238
OS 40.9842335 -38.33037292
OS 40.99532822 -38.3331466
OS 41.0073475 -38.3377694
OS 41.02029134 -38.34331676
OS 41.03415974 -38.34978868
OS 41.04617902 -38.35718516
OS 41.04802814 -38.35810972
OS 41.05172638 -38.3608834
OS 41.05727374 -38.36643076
OS 41.06467022 -38.37290268
OS 41.07299126 -38.38122372
OS 41.0813123 -38.39231844
OS 41.0905579 -38.40433772
OS 41.09795438 -38.41820612
OS 41.09887894 -38.42005524
OS 41.10072806 -38.42467804
OS 41.1044263 -38.43299908
OS 41.10812454 -38.4440938
OS 41.11089822 -38.45703764
OS 41.11459646 -38.4718306
OS 41.11644558 -38.48847268
OS 41.11737014 -38.50603932
OS 41.11737014 -38.50696388
OS 41.11737014 -38.50973756
OS 41.11737014 -38.5134358
OS 41.11644558 -38.51990772
OS 41.11552102 -38.52637964
OS 41.11459646 -38.53470068
OS 41.11274734 -38.54394628
OS 41.11089822 -38.55411644
OS 41.1044263 -38.57538132
OS 41.10072806 -38.58647604
OS 41.0951807 -38.59849532
OS 41.08870878 -38.6105146
OS 41.08223686 -38.62160932
OS 41.07391582 -38.63270404
OS 41.06467022 -38.64379876
OS 41.06374566 -38.64472332
OS 41.06189654 -38.64657244
OS 41.05912286 -38.64934612
OS 41.05450006 -38.6521198
OS 41.0489527 -38.6567426
OS 41.04155622 -38.6613654
OS 41.03231062 -38.66691276
OS 41.02214046 -38.67153556
OS 41.01012118 -38.67708292
OS 40.99625278 -38.68263028
OS 40.98145982 -38.68725308
OS 40.96389318 -38.69095132
OS 40.94540198 -38.69464956
OS 40.92506166 -38.69742324
OS 40.90194766 -38.69927236
OS 40.8779091 -38.70019692
OS 40.71426198 -38.70019692
OS 40.71426198 -38.95999828
OS 40.62920246 -38.95999828
OS 40.62920246 -38.32020276
OS 40.8917775 -38.32020276
OS 40.9056459 -38.32112732
OE
OB 40.49791494 -38.98403684 I
OS 40.49791494 -38.9849614
OS 40.49791494 -38.98773508
OS 40.49791494 -38.99235788
OS 40.49791494 -38.99790524
OS 40.49699038 -39.00530172
OS 40.49699038 -39.0126982
OS 40.49514126 -39.0311894
OS 40.49236758 -39.05060516
OS 40.48866934 -39.07094548
OS 40.48312198 -39.08851212
OS 40.47942374 -39.09683316
OS 40.4757255 -39.10330508
OS 40.4757255 -39.10422964
OS 40.47480094 -39.1051542
OS 40.47017814 -39.109777
OS 40.46278166 -39.11717348
OS 40.45353606 -39.12549452
OS 40.44059222 -39.13381556
OS 40.42395014 -39.14028748
OS 40.40453438 -39.14583484
OS 40.39343966 -39.1467594
OS 40.38142038 -39.14768396
OS 40.37587302 -39.14768396
OS 40.37032566 -39.1467594
OS 40.36200462 -39.1467594
OS 40.35275902 -39.14583484
OS 40.34258886 -39.14398572
OS 40.32039942 -39.13843836
OS 40.33519238 -39.07187004
OS 40.33611694 -39.07187004
OS 40.33889062 -39.0727946
OS 40.34351342 -39.07371916
OS 40.34813622 -39.07464372
OS 40.3601555 -39.0774174
OS 40.36570286 -39.07834196
OS 40.37494846 -39.07834196
OS 40.37957126 -39.0774174
OS 40.38511862 -39.07649284
OS 40.39066598 -39.07464372
OS 40.39621334 -39.07094548
OS 40.40268526 -39.06724724
OS 40.40730806 -39.06169988
OS 40.40823262 -39.06077532
OS 40.40915718 -39.05800164
OS 40.4110063 -39.05337884
OS 40.41377998 -39.04598236
OS 40.4156291 -39.0358122
OS 40.41655366 -39.02841572
OS 40.41747822 -39.0219438
OS 40.41840278 -39.01362276
OS 40.41840278 -39.0034526
OS 40.41932734 -38.99328244
OS 40.41932734 -38.98218772
OS 40.41932734 -38.49586916
OS 40.49791494 -38.49586916
OS 40.49791494 -38.98403684
OE
OB 41.51770462 -38.3100326 I
OS 41.52602566 -38.31095716
OS 41.53619582 -38.31188172
OS 41.54636598 -38.31280628
OS 41.55838526 -38.31557996
OS 41.58334838 -38.32112732
OS 41.61108518 -38.32944836
OS 41.62495358 -38.33499572
OS 41.63789742 -38.34146764
OS 41.65084126 -38.34978868
OS 41.6637851 -38.35810972
OS 41.66470966 -38.35903428
OS 41.66655878 -38.35995884
OS 41.67025702 -38.36273252
OS 41.67487982 -38.36735532
OS 41.67950262 -38.37197812
OS 41.68597454 -38.37845004
OS 41.69244646 -38.38584652
OS 41.69984294 -38.393243
OS 41.70723942 -38.4024886
OS 41.7146359 -38.41358332
OS 41.72295694 -38.42467804
OS 41.73035342 -38.43669732
OS 41.73682534 -38.45056572
OS 41.74422182 -38.46443412
OS 41.74976918 -38.47922708
OS 41.75531654 -38.49586916
OS 41.67210614 -38.51528492
OS 41.67210614 -38.51436036
OS 41.67118158 -38.51251124
OS 41.66933246 -38.508813
OS 41.66748334 -38.5041902
OS 41.66563422 -38.49864284
OS 41.66286054 -38.49124636
OS 41.65546406 -38.4764534
OS 41.64621846 -38.45981132
OS 41.63512374 -38.44316924
OS 41.62125534 -38.42745172
OS 41.60646238 -38.41358332
OS 41.60461326 -38.4117342
OS 41.5990659 -38.40803596
OS 41.5898203 -38.40341316
OS 41.57780102 -38.39694124
OS 41.5620835 -38.39139388
OS 41.54451686 -38.38584652
OS 41.52325198 -38.38214828
OS 41.50013798 -38.38122372
OS 41.4927415 -38.38122372
OS 41.4881187 -38.38214828
OS 41.48164678 -38.38214828
OS 41.4742503 -38.38307284
OS 41.45668366 -38.38584652
OS 41.4372679 -38.38954476
OS 41.41692758 -38.39601668
OS 41.3956627 -38.40526228
OS 41.37624694 -38.41728156
OS 41.37532238 -38.41728156
OS 41.37439782 -38.41913068
OS 41.3679259 -38.42375348
OS 41.35960486 -38.43114996
OS 41.3494347 -38.44224468
OS 41.33741542 -38.45611308
OS 41.3263207 -38.4718306
OS 41.31615054 -38.49124636
OS 41.30690494 -38.51251124
OS 41.30690494 -38.5134358
OS 41.30598038 -38.51528492
OS 41.30505582 -38.5180586
OS 41.30413126 -38.5226814
OS 41.30228214 -38.52822876
OS 41.30043302 -38.53470068
OS 41.29765934 -38.5504182
OS 41.2939611 -38.5689094
OS 41.29026286 -38.58924972
OS 41.28841374 -38.61143916
OS 41.28748918 -38.63547772
OS 41.28748918 -38.63640228
OS 41.28748918 -38.63917596
OS 41.28748918 -38.64379876
OS 41.28748918 -38.64934612
OS 41.28841374 -38.65581804
OS 41.28841374 -38.66413908
OS 41.2893383 -38.67338468
OS 41.29026286 -38.68355484
OS 41.29303654 -38.70574428
OS 41.29765934 -38.72978284
OS 41.3032067 -38.7538214
OS 41.31060318 -38.77785996
OS 41.31060318 -38.77878452
OS 41.31152774 -38.78063364
OS 41.31337686 -38.78340732
OS 41.31522598 -38.78803012
OS 41.32077334 -38.79912484
OS 41.32909438 -38.81206868
OS 41.33926454 -38.82686164
OS 41.35220838 -38.84257916
OS 41.36700134 -38.85644756
OS 41.38456798 -38.8693914
OS 41.38549254 -38.8693914
OS 41.38734166 -38.87031596
OS 41.39011534 -38.87216508
OS 41.39381358 -38.8740142
OS 41.39843638 -38.87586332
OS 41.40398374 -38.878637
OS 41.41692758 -38.88418436
OS 41.43356966 -38.88973172
OS 41.45206086 -38.89435452
OS 41.47240118 -38.89805276
OS 41.49366606 -38.89897732
OS 41.50013798 -38.89897732
OS 41.50568534 -38.89805276
OS 41.51215726 -38.89805276
OS 41.51862918 -38.8971282
OS 41.53527126 -38.89342996
OS 41.55468702 -38.88880716
OS 41.57410278 -38.88141068
OS 41.5944431 -38.87124052
OS 41.60461326 -38.86569316
OS 41.61385886 -38.85829668
OS 41.61478342 -38.85737212
OS 41.61570798 -38.85644756
OS 41.61848166 -38.85367388
OS 41.6221799 -38.8509002
OS 41.62587814 -38.8462774
OS 41.63050094 -38.84073004
OS 41.6360483 -38.83518268
OS 41.6406711 -38.8277862
OS 41.64621846 -38.81946516
OS 41.65269038 -38.81021956
OS 41.65823774 -38.80097396
OS 41.6637851 -38.78987924
OS 41.6684079 -38.77785996
OS 41.6730307 -38.76491612
OS 41.6776535 -38.75104772
OS 41.68135174 -38.73625476
OS 41.76641126 -38.75751964
OS 41.76641126 -38.7584442
OS 41.7654867 -38.76214244
OS 41.76363758 -38.7676898
OS 41.7608639 -38.77508628
OS 41.75809022 -38.78340732
OS 41.75439198 -38.79357748
OS 41.74976918 -38.8046722
OS 41.74422182 -38.81669148
OS 41.73127798 -38.84257916
OS 41.7146359 -38.86846684
OS 41.70446574 -38.88141068
OS 41.69429558 -38.89435452
OS 41.68320086 -38.90544924
OS 41.67025702 -38.91654396
OS 41.66933246 -38.91746852
OS 41.66748334 -38.91931764
OS 41.66286054 -38.92116676
OS 41.65823774 -38.924865
OS 41.65084126 -38.9294878
OS 41.64344478 -38.9341106
OS 41.63327462 -38.9387334
OS 41.62310446 -38.9433562
OS 41.61108518 -38.94890356
OS 41.59814134 -38.95352636
OS 41.58427294 -38.95814916
OS 41.56947998 -38.96277196
OS 41.55376246 -38.9664702
OS 41.53712038 -38.96831932
OS 41.51955374 -38.97016844
OS 41.50106254 -38.971093
OS 41.49089238 -38.971093
OS 41.4834959 -38.97016844
OS 41.47517486 -38.97016844
OS 41.4650047 -38.96924388
OS 41.45390998 -38.96739476
OS 41.44096614 -38.96554564
OS 41.4141539 -38.96092284
OS 41.3864171 -38.95352636
OS 41.3586803 -38.9433562
OS 41.34573646 -38.93688428
OS 41.33279262 -38.9294878
OS 41.33186806 -38.92856324
OS 41.33001894 -38.92763868
OS 41.3263207 -38.924865
OS 41.32262246 -38.92116676
OS 41.3170751 -38.91746852
OS 41.31060318 -38.91192116
OS 41.3032067 -38.90544924
OS 41.29581022 -38.89805276
OS 41.28841374 -38.88973172
OS 41.2800927 -38.88141068
OS 41.26345062 -38.8601458
OS 41.2477331 -38.83518268
OS 41.2338647 -38.80744588
OS 41.2338647 -38.80652132
OS 41.23201558 -38.80374764
OS 41.23109102 -38.79912484
OS 41.22831734 -38.79357748
OS 41.22646822 -38.786181
OS 41.22369454 -38.7769354
OS 41.2199963 -38.76676524
OS 41.21722262 -38.75567052
OS 41.21444894 -38.74365124
OS 41.2107507 -38.72978284
OS 41.2061279 -38.70112148
OS 41.20242966 -38.66876188
OS 41.20058054 -38.63547772
OS 41.20058054 -38.63455316
OS 41.20058054 -38.63085492
OS 41.20058054 -38.62530756
OS 41.2015051 -38.61883564
OS 41.2015051 -38.60959004
OS 41.20242966 -38.60034444
OS 41.20335422 -38.58832516
OS 41.20520334 -38.57630588
OS 41.20982614 -38.54949364
OS 41.21629806 -38.51990772
OS 41.22554366 -38.4903218
OS 41.2384875 -38.46166044
OS 41.23941206 -38.46073588
OS 41.24033662 -38.4579622
OS 41.24218574 -38.45426396
OS 41.24588398 -38.44964116
OS 41.24958222 -38.44316924
OS 41.25420502 -38.43577276
OS 41.2662243 -38.41913068
OS 41.28194182 -38.40063948
OS 41.30043302 -38.38214828
OS 41.3216979 -38.36365708
OS 41.34666102 -38.34793956
OS 41.34758558 -38.347015
OS 41.35035926 -38.34609044
OS 41.3540575 -38.34424132
OS 41.3586803 -38.34146764
OS 41.36607678 -38.33869396
OS 41.37347326 -38.33592028
OS 41.38271886 -38.33222204
OS 41.39288902 -38.3285238
OS 41.40398374 -38.32482556
OS 41.41600302 -38.32112732
OS 41.4418907 -38.31557996
OS 41.47147662 -38.31095716
OS 41.5019871 -38.30910804
OS 41.5112327 -38.30910804
OS 41.51770462 -38.3100326
OE
OB 42.90454462 -39.1375138 I
OS 42.38401734 -39.1375138
OS 42.38401734 -39.08111564
OS 42.90454462 -39.08111564
OS 42.90454462 -39.1375138
OE
OB 42.12514054 -38.32112732 I
OS 42.13253702 -38.32112732
OS 42.1491791 -38.32297644
OS 42.1676703 -38.32482556
OS 42.18708606 -38.3285238
OS 42.20650182 -38.3331466
OS 42.22406846 -38.33961852
OS 42.22499302 -38.33961852
OS 42.22591758 -38.34054308
OS 42.23146494 -38.34331676
OS 42.23978598 -38.34793956
OS 42.24903158 -38.35441148
OS 42.2601263 -38.36273252
OS 42.27214558 -38.37290268
OS 42.2832403 -38.38584652
OS 42.29341046 -38.39971492
OS 42.29433502 -38.40156404
OS 42.2971087 -38.4071114
OS 42.3017315 -38.41450788
OS 42.3063543 -38.4256026
OS 42.3109771 -38.43854644
OS 42.3155999 -38.45241484
OS 42.31837358 -38.46813236
OS 42.31929814 -38.48384988
OS 42.31929814 -38.485699
OS 42.31929814 -38.4903218
OS 42.31837358 -38.49864284
OS 42.31652446 -38.508813
OS 42.31375078 -38.52083228
OS 42.30912798 -38.53377612
OS 42.30358062 -38.54671996
OS 42.29618414 -38.56058836
OS 42.29525958 -38.56243748
OS 42.2924859 -38.56613572
OS 42.28693854 -38.5735322
OS 42.27954206 -38.58092868
OS 42.27029646 -38.59017428
OS 42.25920174 -38.60034444
OS 42.24533334 -38.60959004
OS 42.22961582 -38.61883564
OS 42.23054038 -38.61883564
OS 42.2323895 -38.6197602
OS 42.23516318 -38.62068476
OS 42.23886142 -38.62253388
OS 42.24995614 -38.62623212
OS 42.26289998 -38.63270404
OS 42.27676838 -38.64102508
OS 42.2924859 -38.65119524
OS 42.3063543 -38.66321452
OS 42.31929814 -38.67800748
OS 42.3202227 -38.6798566
OS 42.32392094 -38.68540396
OS 42.3294683 -38.693725
OS 42.33501566 -38.70481972
OS 42.34056302 -38.71961268
OS 42.34611038 -38.7353302
OS 42.34980862 -38.7538214
OS 42.35073318 -38.77416172
OS 42.35073318 -38.77508628
OS 42.35073318 -38.77601084
OS 42.35073318 -38.7815582
OS 42.34980862 -38.7908038
OS 42.3479595 -38.80189852
OS 42.34611038 -38.81484236
OS 42.34241214 -38.82871076
OS 42.33778934 -38.84350372
OS 42.33131742 -38.85829668
OS 42.33039286 -38.8601458
OS 42.32761918 -38.8647686
OS 42.32392094 -38.87124052
OS 42.31837358 -38.88048612
OS 42.3109771 -38.88973172
OS 42.30358062 -38.89990188
OS 42.29433502 -38.91007204
OS 42.28416486 -38.91839308
OS 42.2832403 -38.91931764
OS 42.27954206 -38.92209132
OS 42.27307014 -38.92578956
OS 42.2647491 -38.9294878
OS 42.25457894 -38.93503516
OS 42.24255966 -38.94058252
OS 42.22961582 -38.94520532
OS 42.2138983 -38.94982812
OS 42.21204918 -38.94982812
OS 42.20650182 -38.95167724
OS 42.19725622 -38.9526018
OS 42.18523694 -38.95445092
OS 42.17044398 -38.95630004
OS 42.15287734 -38.95814916
OS 42.13346158 -38.95907372
OS 42.11127214 -38.95999828
OS 41.8671883 -38.95999828
OS 41.8671883 -38.32020276
OS 42.11866862 -38.32020276
OS 42.12514054 -38.32112732
OE
OB 40.30745558 -38.48662356 I
OS 40.31762574 -38.48847268
OS 40.32964502 -38.49217092
OS 40.34258886 -38.49679372
OS 40.35738182 -38.50326564
OS 40.37309934 -38.51158668
OS 40.34443798 -38.58370236
OS 40.34351342 -38.5827778
OS 40.33981518 -38.58092868
OS 40.33426782 -38.578155
OS 40.32687134 -38.57538132
OS 40.3185503 -38.57260764
OS 40.30838014 -38.56983396
OS 40.29820998 -38.56798484
OS 40.28803982 -38.56706028
OS 40.28341702 -38.56706028
OS 40.27879422 -38.56798484
OS 40.2723223 -38.5689094
OS 40.26585038 -38.57075852
OS 40.25752934 -38.5735322
OS 40.2492083 -38.57723044
OS 40.24181182 -38.5827778
OS 40.24088726 -38.58370236
OS 40.23811358 -38.58555148
OS 40.2353399 -38.58924972
OS 40.2307171 -38.59387252
OS 40.2260943 -38.60034444
OS 40.2214715 -38.60774092
OS 40.2168487 -38.61606196
OS 40.21315046 -38.62623212
OS 40.2122259 -38.62808124
OS 40.21130134 -38.6336286
OS 40.20945222 -38.64194964
OS 40.20667854 -38.65304436
OS 40.20390486 -38.66691276
OS 40.20205574 -38.68263028
OS 40.20113118 -38.69927236
OS 40.20020662 -38.71776356
OS 40.20020662 -38.95999828
OS 40.12161902 -38.95999828
OS 40.12161902 -38.49586916
OS 40.19281014 -38.49586916
OS 40.19281014 -38.56613572
OS 40.1937347 -38.56521116
OS 40.19743294 -38.55873924
OS 40.20205574 -38.5504182
OS 40.20945222 -38.54024804
OS 40.2168487 -38.53007788
OS 40.22516974 -38.51898316
OS 40.23349078 -38.50973756
OS 40.24181182 -38.50234108
OS 40.24273638 -38.50141652
OS 40.24551006 -38.4995674
OS 40.25105742 -38.49679372
OS 40.25660478 -38.49402004
OS 40.26400126 -38.49124636
OS 40.27324686 -38.48847268
OS 40.28249246 -38.48662356
OS 40.29266262 -38.485699
OS 40.29913454 -38.485699
OS 40.30745558 -38.48662356
OE
OB 39.48829542 -38.95999828 I
OS 39.3986131 -38.95999828
OS 39.3986131 -38.87031596
OS 39.48829542 -38.87031596
OS 39.48829542 -38.95999828
OE
OB 38.6404739 -38.95999828 I
OS 38.55171614 -38.95999828
OS 38.30393406 -38.32020276
OS 38.39639006 -38.32020276
OS 38.56281086 -38.78525644
OS 38.56281086 -38.786181
OS 38.56373542 -38.78803012
OS 38.56465998 -38.7908038
OS 38.5665091 -38.79450204
OS 38.56743366 -38.8000494
OS 38.56928278 -38.80559676
OS 38.57390558 -38.81946516
OS 38.57945294 -38.83518268
OS 38.5850003 -38.85274932
OS 38.59609502 -38.88973172
OS 38.59609502 -38.88880716
OS 38.59701958 -38.88695804
OS 38.59794414 -38.88418436
OS 38.5988687 -38.88048612
OS 38.60164238 -38.87031596
OS 38.60626518 -38.85644756
OS 38.61088798 -38.84073004
OS 38.61643534 -38.8231634
OS 38.62290726 -38.8046722
OS 38.63030374 -38.78525644
OS 38.80412102 -38.32020276
OS 38.8901051 -38.32020276
OS 38.6404739 -38.95999828
OE
OB 39.27564662 -38.42745172 I
OS 39.25438174 -38.54671996
OS 39.20538006 -38.54671996
OS 39.1859643 -38.42745172
OS 39.1859643 -38.32020276
OS 39.27564662 -38.32020276
OS 39.27564662 -38.42745172
OE
OB 40.49791494 -38.4117342 I
OS 40.41932734 -38.4117342
OS 40.41932734 -38.32020276
OS 40.49791494 -38.32020276
OS 40.49791494 -38.4117342
OE
OB 39.84517558 -38.48662356 I
OS 39.8516475 -38.48754812
OS 39.8655159 -38.48939724
OS 39.88215798 -38.49309548
OS 39.89972462 -38.49864284
OS 39.91729126 -38.50696388
OS 39.9348579 -38.51713404
OS 39.93578246 -38.51713404
OS 39.93670702 -38.51898316
OS 39.94225438 -38.5226814
OS 39.95057542 -38.53007788
OS 39.96074558 -38.53932348
OS 39.9718403 -38.55134276
OS 39.98293502 -38.56613572
OS 39.99402974 -38.58370236
OS 40.00327534 -38.60311812
OS 40.00327534 -38.60404268
OS 40.0041999 -38.6058918
OS 40.00512446 -38.60866548
OS 40.00697358 -38.61236372
OS 40.0088227 -38.61791108
OS 40.01067182 -38.624383
OS 40.01529462 -38.63917596
OS 40.01991742 -38.65766716
OS 40.02361566 -38.67800748
OS 40.02638934 -38.70112148
OS 40.0273139 -38.72516004
OS 40.0273139 -38.7260846
OS 40.0273139 -38.72793372
OS 40.0273139 -38.73163196
OS 40.0273139 -38.73717932
OS 40.02638934 -38.74365124
OS 40.02638934 -38.75104772
OS 40.02454022 -38.7676898
OS 40.02084198 -38.78803012
OS 40.01621918 -38.809295
OS 40.00974726 -38.83148444
OS 40.00142622 -38.85367388
OS 40.00142622 -38.85459844
OS 40.00050166 -38.85644756
OS 39.99865254 -38.85922124
OS 39.99680342 -38.86291948
OS 39.9903315 -38.87308964
OS 39.98201046 -38.88603348
OS 39.9718403 -38.89990188
OS 39.95889646 -38.91377028
OS 39.9441035 -38.92763868
OS 39.92653686 -38.94058252
OS 39.9256123 -38.94058252
OS 39.92468774 -38.94150708
OS 39.92191406 -38.9433562
OS 39.91821582 -38.94520532
OS 39.90897022 -38.94982812
OS 39.89602638 -38.95537548
OS 39.88030886 -38.96092284
OS 39.86366678 -38.96554564
OS 39.84425102 -38.96924388
OS 39.82483526 -38.97016844
OS 39.81836334 -38.97016844
OS 39.81096686 -38.96924388
OS 39.80172126 -38.96831932
OS 39.79062654 -38.9664702
OS 39.77860726 -38.96369652
OS 39.76658798 -38.95999828
OS 39.7545687 -38.95445092
OS 39.75364414 -38.95352636
OS 39.74902134 -38.95167724
OS 39.74347398 -38.947979
OS 39.7360775 -38.94243164
OS 39.72868102 -38.93688428
OS 39.71943542 -38.9294878
OS 39.71111438 -38.92116676
OS 39.7037179 -38.91192116
OS 39.7037179 -39.1375138
OS 39.6251303 -39.1375138
OS 39.6251303 -38.49586916
OS 39.69632142 -38.49586916
OS 39.69632142 -38.55689012
OS 39.69724598 -38.555041
OS 39.70094422 -38.55134276
OS 39.70556702 -38.54487084
OS 39.7129635 -38.53747436
OS 39.72128454 -38.52822876
OS 39.73053014 -38.51990772
OS 39.74162486 -38.51158668
OS 39.75271958 -38.5041902
OS 39.7545687 -38.50326564
OS 39.75826694 -38.50141652
OS 39.76566342 -38.49864284
OS 39.77490902 -38.4949446
OS 39.78600374 -38.49124636
OS 39.79894758 -38.48847268
OS 39.81374054 -38.48662356
OS 39.83038262 -38.485699
OS 39.84055278 -38.485699
OS 39.84517558 -38.48662356
OE
OB 44.92193454 -38.40988508 I
OS 44.84334694 -38.40988508
OS 44.84334694 -38.32020276
OS 44.92193454 -38.32020276
OS 44.92193454 -38.40988508
OE
OB 45.24553054 -38.48662356 I
OS 45.25385158 -38.48754812
OS 45.26309718 -38.48939724
OS 45.27326734 -38.49124636
OS 45.28528662 -38.49309548
OS 45.31024974 -38.50141652
OS 45.32319358 -38.50603932
OS 45.33613742 -38.51251124
OS 45.34908126 -38.51898316
OS 45.3620251 -38.52822876
OS 45.37404438 -38.53747436
OS 45.38606366 -38.54856908
OS 45.38698822 -38.54949364
OS 45.38883734 -38.55134276
OS 45.39161102 -38.555041
OS 45.39530926 -38.5596638
OS 45.39993206 -38.56613572
OS 45.40547942 -38.57445676
OS 45.41102678 -38.58370236
OS 45.41657414 -38.59387252
OS 45.4221215 -38.60496724
OS 45.42766886 -38.61883564
OS 45.43321622 -38.63270404
OS 45.43783902 -38.64842156
OS 45.44153726 -38.66506364
OS 45.44431094 -38.68263028
OS 45.44616006 -38.70112148
OS 45.44708462 -38.7214618
OS 45.44708462 -38.72238636
OS 45.44708462 -38.72516004
OS 45.44708462 -38.72978284
OS 45.44708462 -38.73625476
OS 45.44616006 -38.74365124
OS 45.4452355 -38.75289684
OS 45.4452355 -38.76214244
OS 45.44338638 -38.7723126
OS 45.4406127 -38.7954266
OS 45.43506534 -38.8185406
OS 45.42859342 -38.8416546
OS 45.41934782 -38.86291948
OS 45.41934782 -38.86384404
OS 45.41842326 -38.8647686
OS 45.41657414 -38.86754228
OS 45.41472502 -38.87124052
OS 45.4082531 -38.88048612
OS 45.39993206 -38.89158084
OS 45.38883734 -38.90452468
OS 45.37496894 -38.91746852
OS 45.35925142 -38.93041236
OS 45.34076022 -38.94243164
OS 45.33983566 -38.94243164
OS 45.3389111 -38.9433562
OS 45.33613742 -38.94520532
OS 45.33151462 -38.94705444
OS 45.32689182 -38.94890356
OS 45.32134446 -38.95075268
OS 45.30747606 -38.95630004
OS 45.29175854 -38.96092284
OS 45.27234278 -38.96554564
OS 45.25200246 -38.96924388
OS 45.22981302 -38.97016844
OS 45.22056742 -38.97016844
OS 45.21317094 -38.96924388
OS 45.2048499 -38.96831932
OS 45.1956043 -38.9664702
OS 45.18450958 -38.96462108
OS 45.17341486 -38.96277196
OS 45.14845174 -38.95537548
OS 45.13458334 -38.94982812
OS 45.1216395 -38.94428076
OS 45.10869566 -38.93688428
OS 45.09575182 -38.92856324
OS 45.08373254 -38.91931764
OS 45.07171326 -38.90822292
OS 45.0707887 -38.90729836
OS 45.06893958 -38.90544924
OS 45.0661659 -38.901751
OS 45.06246766 -38.89620364
OS 45.05784486 -38.88973172
OS 45.05322206 -38.88233524
OS 45.0476747 -38.87308964
OS 45.04212734 -38.86199492
OS 45.03657998 -38.84997564
OS 45.03103262 -38.83610724
OS 45.02640982 -38.82131428
OS 45.02178702 -38.80559676
OS 45.01808878 -38.78803012
OS 45.0153151 -38.76953892
OS 45.01346598 -38.7491986
OS 45.01254142 -38.72793372
OS 45.01254142 -38.7260846
OS 45.01254142 -38.72238636
OS 45.01346598 -38.71591444
OS 45.01346598 -38.70666884
OS 45.01439054 -38.69649868
OS 45.01623966 -38.68355484
OS 45.01808878 -38.670611
OS 45.02178702 -38.65581804
OS 45.02548526 -38.64102508
OS 45.03010806 -38.62530756
OS 45.03565542 -38.60866548
OS 45.0430519 -38.59294796
OS 45.05044838 -38.578155
OS 45.06061854 -38.56336204
OS 45.0707887 -38.54949364
OS 45.08373254 -38.53747436
OS 45.0846571 -38.5365498
OS 45.08650622 -38.53562524
OS 45.09020446 -38.53285156
OS 45.09482726 -38.52915332
OS 45.10037462 -38.52545508
OS 45.1077711 -38.52083228
OS 45.11516758 -38.51620948
OS 45.12441318 -38.51158668
OS 45.13458334 -38.50696388
OS 45.14567806 -38.50234108
OS 45.17064118 -38.49402004
OS 45.19930254 -38.48754812
OS 45.2140955 -38.48662356
OS 45.22981302 -38.485699
OS 45.23905862 -38.485699
OS 45.24553054 -38.48662356
OE
OB 44.92193454 -38.95999828 I
OS 44.84334694 -38.95999828
OS 44.84334694 -38.49586916
OS 44.92193454 -38.49586916
OS 44.92193454 -38.95999828
OE
OB 46.10722046 -38.42745172 I
OS 46.08595558 -38.54671996
OS 46.0369539 -38.54671996
OS 46.01753814 -38.42745172
OS 46.01753814 -38.32020276
OS 46.10722046 -38.32020276
OS 46.10722046 -38.42745172
OE
OB 45.77160518 -38.48662356 I
OS 45.78177534 -38.48754812
OS 45.79379462 -38.48939724
OS 45.80673846 -38.49217092
OS 45.82060686 -38.49586916
OS 45.8335507 -38.50141652
OS 45.83539982 -38.50234108
OS 45.83909806 -38.5041902
OS 45.84556998 -38.50696388
OS 45.85296646 -38.51158668
OS 45.86221206 -38.51713404
OS 45.8705331 -38.52453052
OS 45.87885414 -38.531927
OS 45.88625062 -38.5411726
OS 45.88717518 -38.54209716
OS 45.8890243 -38.5457954
OS 45.89179798 -38.5504182
OS 45.89642078 -38.55689012
OS 45.90011902 -38.56613572
OS 45.90381726 -38.57538132
OS 45.90844006 -38.58647604
OS 45.91121374 -38.59849532
OS 45.91121374 -38.59941988
OS 45.9121383 -38.60311812
OS 45.91306286 -38.60866548
OS 45.91398742 -38.61606196
OS 45.91398742 -38.62715668
OS 45.91491198 -38.64010052
OS 45.91583654 -38.65581804
OS 45.91583654 -38.6752338
OS 45.91583654 -38.95999828
OS 45.83724894 -38.95999828
OS 45.83724894 -38.67893204
OS 45.83724894 -38.67800748
OS 45.83724894 -38.67708292
OS 45.83724894 -38.670611
OS 45.83724894 -38.66228996
OS 45.83632438 -38.6521198
OS 45.83539982 -38.64010052
OS 45.8335507 -38.62808124
OS 45.83077702 -38.61698652
OS 45.82800334 -38.60681636
OS 45.82800334 -38.6058918
OS 45.82615422 -38.60311812
OS 45.82338054 -38.59849532
OS 45.82060686 -38.59294796
OS 45.81598406 -38.5874006
OS 45.8104367 -38.58092868
OS 45.80304022 -38.57445676
OS 45.79471918 -38.5689094
OS 45.79379462 -38.56798484
OS 45.79102094 -38.56613572
OS 45.78547358 -38.5642866
OS 45.77900166 -38.56151292
OS 45.77160518 -38.55873924
OS 45.76235958 -38.55596556
OS 45.75126486 -38.555041
OS 45.74017014 -38.55411644
OS 45.73554734 -38.55411644
OS 45.7318491 -38.555041
OS 45.7226035 -38.55596556
OS 45.71058422 -38.55781468
OS 45.69764038 -38.56243748
OS 45.68284742 -38.56798484
OS 45.66805446 -38.57538132
OS 45.65418606 -38.58647604
OS 45.65233694 -38.58832516
OS 45.6486387 -38.59294796
OS 45.64586502 -38.5966462
OS 45.64309134 -38.601269
OS 45.6393931 -38.60681636
OS 45.63661942 -38.61328828
OS 45.63292118 -38.62068476
OS 45.62922294 -38.62993036
OS 45.62644926 -38.64010052
OS 45.62367558 -38.65119524
OS 45.62182646 -38.66321452
OS 45.61997734 -38.67615836
OS 45.61812822 -38.69187588
OS 45.61812822 -38.7075934
OS 45.61812822 -38.95999828
OS 45.53954062 -38.95999828
OS 45.53954062 -38.49586916
OS 45.60980718 -38.49586916
OS 45.60980718 -38.56243748
OS 45.61073174 -38.56151292
OS 45.61258086 -38.55873924
OS 45.61535454 -38.555041
OS 45.61905278 -38.5504182
OS 45.62460014 -38.54487084
OS 45.63107206 -38.53839892
OS 45.63846854 -38.53100244
OS 45.64771414 -38.52360596
OS 45.65695974 -38.51713404
OS 45.66805446 -38.50973756
OS 45.68007374 -38.50326564
OS 45.69301758 -38.49771828
OS 45.70781054 -38.49309548
OS 45.7226035 -38.48939724
OS 45.73924558 -38.48662356
OS 45.75681222 -38.485699
OS 45.7642087 -38.485699
OS 45.77160518 -38.48662356
OE
OB 44.2756671 -38.95999828 I
OS 44.1970795 -38.95999828
OS 44.1970795 -38.49586916
OS 44.2756671 -38.49586916
OS 44.2756671 -38.95999828
OE
OB 43.4574315 -38.48662356 I
OS 43.46482798 -38.48754812
OS 43.47407358 -38.48939724
OS 43.48424374 -38.49124636
OS 43.49626302 -38.49402004
OS 43.50735774 -38.49679372
OS 43.52030158 -38.50141652
OS 43.53232086 -38.50603932
OS 43.5452647 -38.51251124
OS 43.55820854 -38.51990772
OS 43.57115238 -38.52822876
OS 43.58317166 -38.53839892
OS 43.59426638 -38.54949364
OS 43.59519094 -38.5504182
OS 43.59704006 -38.55226732
OS 43.59981374 -38.55596556
OS 43.60351198 -38.56151292
OS 43.60813478 -38.56798484
OS 43.61275758 -38.57538132
OS 43.61830494 -38.58462692
OS 43.6238523 -38.59572164
OS 43.62939966 -38.60774092
OS 43.63494702 -38.62068476
OS 43.63956982 -38.63547772
OS 43.64419262 -38.65119524
OS 43.64789086 -38.66876188
OS 43.65066454 -38.68725308
OS 43.65251366 -38.70666884
OS 43.65343822 -38.72793372
OS 43.65343822 -38.72885828
OS 43.65343822 -38.73255652
OS 43.65343822 -38.73902844
OS 43.65251366 -38.74827404
OS 43.30580366 -38.74827404
OS 43.30580366 -38.7491986
OS 43.30580366 -38.75197228
OS 43.30672822 -38.75567052
OS 43.30672822 -38.76121788
OS 43.30765278 -38.7676898
OS 43.3095019 -38.77508628
OS 43.31227558 -38.79172836
OS 43.31782294 -38.81021956
OS 43.32521942 -38.83055988
OS 43.33538958 -38.84905108
OS 43.34833342 -38.86569316
OS 43.34925798 -38.86569316
OS 43.35018254 -38.86754228
OS 43.3557299 -38.87216508
OS 43.36405094 -38.878637
OS 43.37514566 -38.88510892
OS 43.38993862 -38.8925054
OS 43.4065807 -38.89897732
OS 43.4250719 -38.90360012
OS 43.43524206 -38.90452468
OS 43.44633678 -38.90544924
OS 43.45373326 -38.90544924
OS 43.4620543 -38.90452468
OS 43.47222446 -38.90267556
OS 43.48331918 -38.89990188
OS 43.49626302 -38.89620364
OS 43.5082823 -38.89065628
OS 43.52030158 -38.8832598
OS 43.52122614 -38.88233524
OS 43.52584894 -38.878637
OS 43.5313963 -38.87308964
OS 43.53786822 -38.86569316
OS 43.5452647 -38.855523
OS 43.55358574 -38.84257916
OS 43.56190678 -38.8277862
OS 43.56930326 -38.81021956
OS 43.65066454 -38.82038972
OS 43.65066454 -38.82131428
OS 43.64973998 -38.8231634
OS 43.64881542 -38.82686164
OS 43.6469663 -38.832409
OS 43.64419262 -38.83795636
OS 43.64141894 -38.84535284
OS 43.63402246 -38.86107036
OS 43.62477686 -38.878637
OS 43.61183302 -38.8971282
OS 43.59704006 -38.91469484
OS 43.57854886 -38.93133692
OS 43.5776243 -38.93133692
OS 43.57577518 -38.93318604
OS 43.5730015 -38.93503516
OS 43.56930326 -38.93780884
OS 43.5637559 -38.94058252
OS 43.55820854 -38.9433562
OS 43.55081206 -38.94705444
OS 43.54249102 -38.95075268
OS 43.53324542 -38.95445092
OS 43.52399982 -38.95814916
OS 43.50088582 -38.96369652
OS 43.47499814 -38.96831932
OS 43.44633678 -38.97016844
OS 43.43616662 -38.97016844
OS 43.4296947 -38.96924388
OS 43.42137366 -38.96831932
OS 43.4112035 -38.9664702
OS 43.40010878 -38.96462108
OS 43.3880895 -38.96277196
OS 43.36220182 -38.95537548
OS 43.34833342 -38.94982812
OS 43.33538958 -38.94428076
OS 43.32152118 -38.93688428
OS 43.30857734 -38.92856324
OS 43.29655806 -38.91931764
OS 43.28453878 -38.90822292
OS 43.28361422 -38.90729836
OS 43.2817651 -38.90544924
OS 43.27899142 -38.901751
OS 43.27529318 -38.89620364
OS 43.27067038 -38.88973172
OS 43.26604758 -38.88233524
OS 43.26050022 -38.87308964
OS 43.25495286 -38.86291948
OS 43.2494055 -38.8509002
OS 43.24385814 -38.83795636
OS 43.23923534 -38.8231634
OS 43.23461254 -38.80744588
OS 43.2309143 -38.7908038
OS 43.22814062 -38.7723126
OS 43.2262915 -38.75289684
OS 43.22536694 -38.73255652
OS 43.22536694 -38.73163196
OS 43.22536694 -38.72700916
OS 43.22536694 -38.7214618
OS 43.2262915 -38.71314076
OS 43.22721606 -38.7029706
OS 43.22814062 -38.69187588
OS 43.22998974 -38.67893204
OS 43.23276342 -38.6659882
OS 43.2401599 -38.63640228
OS 43.2447827 -38.62160932
OS 43.25033006 -38.6058918
OS 43.25772654 -38.59109884
OS 43.26604758 -38.57723044
OS 43.27529318 -38.56336204
OS 43.28546334 -38.5504182
OS 43.2863879 -38.54949364
OS 43.28823702 -38.54764452
OS 43.29193526 -38.54487084
OS 43.29655806 -38.54024804
OS 43.30210542 -38.53562524
OS 43.3095019 -38.53007788
OS 43.31782294 -38.52360596
OS 43.3279931 -38.5180586
OS 43.33816326 -38.51158668
OS 43.35018254 -38.50603932
OS 43.36312638 -38.50049196
OS 43.37699478 -38.49586916
OS 43.39178774 -38.49124636
OS 43.40750526 -38.48847268
OS 43.42414734 -38.48662356
OS 43.44171398 -38.485699
OS 43.45095958 -38.485699
OS 43.4574315 -38.48662356
OE
OB 43.13938286 -38.48662356 I
OS 43.14955302 -38.48847268
OS 43.1615723 -38.49217092
OS 43.17451614 -38.49679372
OS 43.1893091 -38.50326564
OS 43.20502662 -38.51158668
OS 43.17636526 -38.58370236
OS 43.1754407 -38.5827778
OS 43.17174246 -38.58092868
OS 43.1661951 -38.578155
OS 43.15879862 -38.57538132
OS 43.15047758 -38.57260764
OS 43.14030742 -38.56983396
OS 43.13013726 -38.56798484
OS 43.1199671 -38.56706028
OS 43.1153443 -38.56706028
OS 43.1107215 -38.56798484
OS 43.10424958 -38.5689094
OS 43.09777766 -38.57075852
OS 43.08945662 -38.5735322
OS 43.08113558 -38.57723044
OS 43.0737391 -38.5827778
OS 43.07281454 -38.58370236
OS 43.07004086 -38.58555148
OS 43.06726718 -38.58924972
OS 43.06264438 -38.59387252
OS 43.05802158 -38.60034444
OS 43.05339878 -38.60774092
OS 43.04877598 -38.61606196
OS 43.04507774 -38.62623212
OS 43.04415318 -38.62808124
OS 43.04322862 -38.6336286
OS 43.0413795 -38.64194964
OS 43.03860582 -38.65304436
OS 43.03583214 -38.66691276
OS 43.03398302 -38.68263028
OS 43.03305846 -38.69927236
OS 43.0321339 -38.71776356
OS 43.0321339 -38.95999828
OS 42.9535463 -38.95999828
OS 42.9535463 -38.49586916
OS 43.02473742 -38.49586916
OS 43.02473742 -38.56613572
OS 43.02566198 -38.56521116
OS 43.02936022 -38.55873924
OS 43.03398302 -38.5504182
OS 43.0413795 -38.54024804
OS 43.04877598 -38.53007788
OS 43.05709702 -38.51898316
OS 43.06541806 -38.50973756
OS 43.0737391 -38.50234108
OS 43.07466366 -38.50141652
OS 43.07743734 -38.4995674
OS 43.0829847 -38.49679372
OS 43.08853206 -38.49402004
OS 43.09592854 -38.49124636
OS 43.10517414 -38.48847268
OS 43.11441974 -38.48662356
OS 43.1245899 -38.485699
OS 43.13106182 -38.485699
OS 43.13938286 -38.48662356
OE
OB 43.95022198 -38.95999828 I
OS 43.87533262 -38.95999828
OS 43.70059078 -38.49586916
OS 43.78380118 -38.49586916
OS 43.88365366 -38.77416172
OS 43.88365366 -38.77508628
OS 43.88457822 -38.77601084
OS 43.88550278 -38.77878452
OS 43.88642734 -38.7815582
OS 43.88920102 -38.7908038
OS 43.89289926 -38.80282308
OS 43.89752206 -38.81669148
OS 43.90306942 -38.832409
OS 43.90769222 -38.84997564
OS 43.91323958 -38.86754228
OS 43.91416414 -38.86569316
OS 43.9150887 -38.86107036
OS 43.91786238 -38.85367388
OS 43.92063606 -38.84257916
OS 43.92525886 -38.83055988
OS 43.92988166 -38.81484236
OS 43.93635358 -38.79820028
OS 43.9428255 -38.77970908
OS 44.04545166 -38.49586916
OS 44.12681294 -38.49586916
OS 43.95022198 -38.95999828
OE
OB 44.2756671 -38.40988508 I
OS 44.1970795 -38.40988508
OS 44.1970795 -38.32020276
OS 44.2756671 -38.32020276
OS 44.2756671 -38.40988508
OE
OB 44.5669035 -38.48662356 I
OS 44.5807719 -38.48754812
OS 44.59556486 -38.48939724
OS 44.61128238 -38.49309548
OS 44.62792446 -38.49679372
OS 44.64364198 -38.50234108
OS 44.64456654 -38.50234108
OS 44.6454911 -38.50326564
OS 44.6501139 -38.50511476
OS 44.65751038 -38.508813
OS 44.66675598 -38.5134358
OS 44.67692614 -38.51990772
OS 44.6870963 -38.5273042
OS 44.6963419 -38.53562524
OS 44.70466294 -38.54487084
OS 44.7055875 -38.5457954
OS 44.70743662 -38.54949364
OS 44.71113486 -38.55596556
OS 44.71575766 -38.56336204
OS 44.72038046 -38.57445676
OS 44.72500326 -38.58647604
OS 44.7287015 -38.60034444
OS 44.73239974 -38.61606196
OS 44.65566126 -38.62623212
OS 44.65566126 -38.624383
OS 44.6547367 -38.62068476
OS 44.65288758 -38.61421284
OS 44.6501139 -38.6058918
OS 44.6454911 -38.59757076
OS 44.63994374 -38.58832516
OS 44.63347182 -38.57907956
OS 44.62422622 -38.57075852
OS 44.62330166 -38.56983396
OS 44.61960342 -38.56798484
OS 44.61405606 -38.5642866
OS 44.60573502 -38.56058836
OS 44.59648942 -38.55689012
OS 44.58447014 -38.55319188
OS 44.56967718 -38.55134276
OS 44.55395966 -38.5504182
OS 44.54471406 -38.5504182
OS 44.53546846 -38.55134276
OS 44.52344918 -38.55226732
OS 44.5114299 -38.555041
OS 44.49848606 -38.55781468
OS 44.48646678 -38.56243748
OS 44.47629662 -38.5689094
OS 44.47537206 -38.56983396
OS 44.47259838 -38.57168308
OS 44.46890014 -38.57538132
OS 44.4652019 -38.58092868
OS 44.4605791 -38.58647604
OS 44.45688086 -38.59387252
OS 44.45410718 -38.60219356
OS 44.45318262 -38.6105146
OS 44.45318262 -38.61143916
OS 44.45318262 -38.61328828
OS 44.45410718 -38.61606196
OS 44.45410718 -38.6197602
OS 44.45688086 -38.6290058
OS 44.46242822 -38.6382514
OS 44.46335278 -38.63917596
OS 44.46427734 -38.64010052
OS 44.46612646 -38.6428742
OS 44.4698247 -38.64564788
OS 44.47352294 -38.64842156
OS 44.4790703 -38.6521198
OS 44.48554222 -38.65489348
OS 44.4929387 -38.65859172
OS 44.49386326 -38.65859172
OS 44.49571238 -38.65951628
OS 44.49941062 -38.66044084
OS 44.50588254 -38.66321452
OS 44.51512814 -38.6659882
OS 44.52714742 -38.66876188
OS 44.5345439 -38.67153556
OS 44.54286494 -38.67338468
OS 44.55211054 -38.67615836
OS 44.5622807 -38.67893204
OS 44.56320526 -38.67893204
OS 44.56597894 -38.6798566
OS 44.57060174 -38.68078116
OS 44.5761491 -38.68263028
OS 44.58262102 -38.6844794
OS 44.59094206 -38.68632852
OS 44.6085087 -38.69187588
OS 44.62792446 -38.69742324
OS 44.64734022 -38.70389516
OS 44.66490686 -38.71036708
OS 44.67230334 -38.71314076
OS 44.67877526 -38.71591444
OS 44.68062438 -38.716839
OS 44.68432262 -38.71868812
OS 44.68986998 -38.7214618
OS 44.69819102 -38.7260846
OS 44.70651206 -38.73163196
OS 44.7148331 -38.73902844
OS 44.72315414 -38.74734948
OS 44.73055062 -38.75659508
OS 44.73147518 -38.75751964
OS 44.7333243 -38.76121788
OS 44.73702254 -38.76676524
OS 44.74072078 -38.77508628
OS 44.74349446 -38.78525644
OS 44.7471927 -38.79635116
OS 44.74904182 -38.809295
OS 44.74996638 -38.82408796
OS 44.74996638 -38.82593708
OS 44.74996638 -38.83055988
OS 44.74904182 -38.83795636
OS 44.7471927 -38.84812652
OS 44.74441902 -38.85922124
OS 44.73979622 -38.87124052
OS 44.73424886 -38.88510892
OS 44.72685238 -38.89805276
OS 44.72592782 -38.89990188
OS 44.72222958 -38.90360012
OS 44.71760678 -38.91007204
OS 44.7102103 -38.91746852
OS 44.70004014 -38.92578956
OS 44.68894542 -38.93503516
OS 44.67600158 -38.9433562
OS 44.66028406 -38.95167724
OS 44.6593595 -38.95167724
OS 44.65843494 -38.9526018
OS 44.65288758 -38.95445092
OS 44.64364198 -38.9572246
OS 44.6316227 -38.96092284
OS 44.61682974 -38.96462108
OS 44.60018766 -38.96739476
OS 44.58262102 -38.96924388
OS 44.5622807 -38.97016844
OS 44.55395966 -38.97016844
OS 44.54748774 -38.96924388
OS 44.54009126 -38.96924388
OS 44.53084566 -38.96831932
OS 44.52160006 -38.96739476
OS 44.5114299 -38.96554564
OS 44.48924046 -38.96092284
OS 44.46612646 -38.95445092
OS 44.44393702 -38.94520532
OS 44.43376686 -38.93965796
OS 44.42452126 -38.93318604
OS 44.4235967 -38.93226148
OS 44.42267214 -38.93133692
OS 44.41712478 -38.92578956
OS 44.40880374 -38.91746852
OS 44.39955814 -38.90452468
OS 44.38938798 -38.88880716
OS 44.37921782 -38.87031596
OS 44.37089678 -38.84720196
OS 44.36442486 -38.82131428
OS 44.4420879 -38.809295
OS 44.4420879 -38.81021956
OS 44.4420879 -38.81114412
OS 44.44393702 -38.81669148
OS 44.44578614 -38.82593708
OS 44.44948438 -38.83610724
OS 44.45410718 -38.84720196
OS 44.45965454 -38.85922124
OS 44.46797558 -38.87124052
OS 44.47814574 -38.88141068
OS 44.47999486 -38.88233524
OS 44.4836931 -38.88510892
OS 44.49108958 -38.88880716
OS 44.50033518 -38.89342996
OS 44.51235446 -38.89805276
OS 44.52622286 -38.901751
OS 44.54286494 -38.90452468
OS 44.5622807 -38.90544924
OS 44.5715263 -38.90544924
OS 44.5807719 -38.90452468
OS 44.59279118 -38.90267556
OS 44.60573502 -38.89990188
OS 44.61960342 -38.89620364
OS 44.6316227 -38.89158084
OS 44.64271742 -38.88418436
OS 44.64364198 -38.8832598
OS 44.64734022 -38.88048612
OS 44.65103846 -38.87586332
OS 44.65658582 -38.8693914
OS 44.66120862 -38.86199492
OS 44.66583142 -38.85274932
OS 44.6686051 -38.84350372
OS 44.66952966 -38.832409
OS 44.66952966 -38.83148444
OS 44.66952966 -38.8277862
OS 44.6686051 -38.8231634
OS 44.66675598 -38.81669148
OS 44.6639823 -38.81021956
OS 44.6593595 -38.80374764
OS 44.65381214 -38.79635116
OS 44.6454911 -38.7908038
OS 44.64456654 -38.78987924
OS 44.64179286 -38.78895468
OS 44.63717006 -38.786181
OS 44.62977358 -38.78340732
OS 44.61867886 -38.77970908
OS 44.61220694 -38.7769354
OS 44.60481046 -38.77508628
OS 44.59648942 -38.7723126
OS 44.58724382 -38.76953892
OS 44.57707366 -38.76676524
OS 44.56505438 -38.76399156
OS 44.56412982 -38.76399156
OS 44.56135614 -38.763067
OS 44.55673334 -38.76214244
OS 44.55118598 -38.76029332
OS 44.5437895 -38.7584442
OS 44.53546846 -38.75567052
OS 44.51790182 -38.75104772
OS 44.4975615 -38.7445758
OS 44.47814574 -38.73902844
OS 44.45965454 -38.73255652
OS 44.4513335 -38.72885828
OS 44.44486158 -38.7260846
OS 44.44301246 -38.72516004
OS 44.43931422 -38.72331092
OS 44.43376686 -38.71961268
OS 44.42637038 -38.71498988
OS 44.41804934 -38.70851796
OS 44.4097283 -38.70112148
OS 44.40140726 -38.69280044
OS 44.39401078 -38.68263028
OS 44.39308622 -38.68170572
OS 44.3912371 -38.67800748
OS 44.38846342 -38.67153556
OS 44.38568974 -38.66413908
OS 44.38291606 -38.65489348
OS 44.38014238 -38.64379876
OS 44.37829326 -38.63270404
OS 44.3773687 -38.6197602
OS 44.3773687 -38.61791108
OS 44.3773687 -38.61421284
OS 44.37829326 -38.60866548
OS 44.37921782 -38.60034444
OS 44.38106694 -38.5920234
OS 44.38291606 -38.58185324
OS 44.3866143 -38.57260764
OS 44.3912371 -38.56243748
OS 44.39216166 -38.56151292
OS 44.39401078 -38.55781468
OS 44.39678446 -38.55319188
OS 44.40140726 -38.54671996
OS 44.40695462 -38.54024804
OS 44.41342654 -38.531927
OS 44.42082302 -38.52453052
OS 44.43006862 -38.5180586
OS 44.43099318 -38.51713404
OS 44.43376686 -38.51620948
OS 44.4374651 -38.5134358
OS 44.44301246 -38.51066212
OS 44.45040894 -38.50696388
OS 44.45872998 -38.50326564
OS 44.46890014 -38.4995674
OS 44.47999486 -38.49586916
OS 44.48184398 -38.4949446
OS 44.48554222 -38.49402004
OS 44.49201414 -38.49217092
OS 44.50033518 -38.4903218
OS 44.51050534 -38.48847268
OS 44.52160006 -38.48754812
OS 44.5345439 -38.485699
OS 44.55673334 -38.485699
OS 44.5669035 -38.48662356
OE
OB 33.15968222 -38.32112732 I
OS 33.17539974 -38.32205188
OS 33.19204182 -38.32297644
OS 33.20775934 -38.32482556
OS 33.22162774 -38.32667468
OS 33.22347686 -38.32667468
OS 33.22994878 -38.3285238
OS 33.23826982 -38.33037292
OS 33.24936454 -38.3331466
OS 33.26138382 -38.3377694
OS 33.27432766 -38.34331676
OS 33.28819606 -38.34978868
OS 33.30021534 -38.35718516
OS 33.30206446 -38.35810972
OS 33.3057627 -38.3608834
OS 33.31131006 -38.36643076
OS 33.31870654 -38.37290268
OS 33.32702758 -38.38122372
OS 33.33534862 -38.39231844
OS 33.34459422 -38.40433772
OS 33.3519907 -38.41820612
OS 33.35291526 -38.42005524
OS 33.35476438 -38.42467804
OS 33.35846262 -38.43299908
OS 33.36216086 -38.4440938
OS 33.36493454 -38.45703764
OS 33.36863278 -38.4718306
OS 33.3704819 -38.48847268
OS 33.37140646 -38.50603932
OS 33.37140646 -38.50696388
OS 33.37140646 -38.50973756
OS 33.37140646 -38.5134358
OS 33.3704819 -38.51990772
OS 33.36955734 -38.52637964
OS 33.36863278 -38.53470068
OS 33.36678366 -38.54394628
OS 33.36493454 -38.55411644
OS 33.35846262 -38.57538132
OS 33.35476438 -38.58647604
OS 33.34921702 -38.59849532
OS 33.3427451 -38.6105146
OS 33.33627318 -38.62160932
OS 33.32795214 -38.63270404
OS 33.31870654 -38.64379876
OS 33.31778198 -38.64472332
OS 33.31593286 -38.64657244
OS 33.31315918 -38.64934612
OS 33.30853638 -38.6521198
OS 33.30298902 -38.6567426
OS 33.29559254 -38.6613654
OS 33.28634694 -38.66691276
OS 33.27617678 -38.67153556
OS 33.2641575 -38.67708292
OS 33.2502891 -38.68263028
OS 33.23549614 -38.68725308
OS 33.2179295 -38.69095132
OS 33.1994383 -38.69464956
OS 33.17909798 -38.69742324
OS 33.15598398 -38.69927236
OS 33.13194542 -38.70019692
OS 32.9682983 -38.70019692
OS 32.9682983 -38.95999828
OS 32.88323878 -38.95999828
OS 32.88323878 -38.32020276
OS 33.14581382 -38.32020276
OS 33.15968222 -38.32112732
OE
OB 32.75195126 -38.98403684 I
OS 32.75195126 -38.9849614
OS 32.75195126 -38.98773508
OS 32.75195126 -38.99235788
OS 32.75195126 -38.99790524
OS 32.7510267 -39.00530172
OS 32.7510267 -39.0126982
OS 32.74917758 -39.0311894
OS 32.7464039 -39.05060516
OS 32.74270566 -39.07094548
OS 32.7371583 -39.08851212
OS 32.73346006 -39.09683316
OS 32.72976182 -39.10330508
OS 32.72976182 -39.10422964
OS 32.72883726 -39.1051542
OS 32.72421446 -39.109777
OS 32.71681798 -39.11717348
OS 32.70757238 -39.12549452
OS 32.69462854 -39.13381556
OS 32.67798646 -39.14028748
OS 32.6585707 -39.14583484
OS 32.64747598 -39.1467594
OS 32.6354567 -39.14768396
OS 32.62990934 -39.14768396
OS 32.62436198 -39.1467594
OS 32.61604094 -39.1467594
OS 32.60679534 -39.14583484
OS 32.59662518 -39.14398572
OS 32.57443574 -39.13843836
OS 32.5892287 -39.07187004
OS 32.59015326 -39.07187004
OS 32.59292694 -39.0727946
OS 32.59754974 -39.07371916
OS 32.60217254 -39.07464372
OS 32.61419182 -39.0774174
OS 32.61973918 -39.07834196
OS 32.62898478 -39.07834196
OS 32.63360758 -39.0774174
OS 32.63915494 -39.07649284
OS 32.6447023 -39.07464372
OS 32.65024966 -39.07094548
OS 32.65672158 -39.06724724
OS 32.66134438 -39.06169988
OS 32.66226894 -39.06077532
OS 32.6631935 -39.05800164
OS 32.66504262 -39.05337884
OS 32.6678163 -39.04598236
OS 32.66966542 -39.0358122
OS 32.67058998 -39.02841572
OS 32.67151454 -39.0219438
OS 32.6724391 -39.01362276
OS 32.6724391 -39.0034526
OS 32.67336366 -38.99328244
OS 32.67336366 -38.98218772
OS 32.67336366 -38.49586916
OS 32.75195126 -38.49586916
OS 32.75195126 -38.98403684
OE
OB 33.77174094 -38.3100326 I
OS 33.78006198 -38.31095716
OS 33.79023214 -38.31188172
OS 33.8004023 -38.31280628
OS 33.81242158 -38.31557996
OS 33.8373847 -38.32112732
OS 33.8651215 -38.32944836
OS 33.8789899 -38.33499572
OS 33.89193374 -38.34146764
OS 33.90487758 -38.34978868
OS 33.91782142 -38.35810972
OS 33.91874598 -38.35903428
OS 33.9205951 -38.35995884
OS 33.92429334 -38.36273252
OS 33.92891614 -38.36735532
OS 33.93353894 -38.37197812
OS 33.94001086 -38.37845004
OS 33.94648278 -38.38584652
OS 33.95387926 -38.393243
OS 33.96127574 -38.4024886
OS 33.96867222 -38.41358332
OS 33.97699326 -38.42467804
OS 33.98438974 -38.43669732
OS 33.99086166 -38.45056572
OS 33.99825814 -38.46443412
OS 34.0038055 -38.47922708
OS 34.00935286 -38.49586916
OS 33.92614246 -38.51528492
OS 33.92614246 -38.51436036
OS 33.9252179 -38.51251124
OS 33.92336878 -38.508813
OS 33.92151966 -38.5041902
OS 33.91967054 -38.49864284
OS 33.91689686 -38.49124636
OS 33.90950038 -38.4764534
OS 33.90025478 -38.45981132
OS 33.88916006 -38.44316924
OS 33.87529166 -38.42745172
OS 33.8604987 -38.41358332
OS 33.85864958 -38.4117342
OS 33.85310222 -38.40803596
OS 33.84385662 -38.40341316
OS 33.83183734 -38.39694124
OS 33.81611982 -38.39139388
OS 33.79855318 -38.38584652
OS 33.7772883 -38.38214828
OS 33.7541743 -38.38122372
OS 33.74677782 -38.38122372
OS 33.74215502 -38.38214828
OS 33.7356831 -38.38214828
OS 33.72828662 -38.38307284
OS 33.71071998 -38.38584652
OS 33.69130422 -38.38954476
OS 33.6709639 -38.39601668
OS 33.64969902 -38.40526228
OS 33.63028326 -38.41728156
OS 33.6293587 -38.41728156
OS 33.62843414 -38.41913068
OS 33.62196222 -38.42375348
OS 33.61364118 -38.43114996
OS 33.60347102 -38.44224468
OS 33.59145174 -38.45611308
OS 33.58035702 -38.4718306
OS 33.57018686 -38.49124636
OS 33.56094126 -38.51251124
OS 33.56094126 -38.5134358
OS 33.5600167 -38.51528492
OS 33.55909214 -38.5180586
OS 33.55816758 -38.5226814
OS 33.55631846 -38.52822876
OS 33.55446934 -38.53470068
OS 33.55169566 -38.5504182
OS 33.54799742 -38.5689094
OS 33.54429918 -38.58924972
OS 33.54245006 -38.61143916
OS 33.5415255 -38.63547772
OS 33.5415255 -38.63640228
OS 33.5415255 -38.63917596
OS 33.5415255 -38.64379876
OS 33.5415255 -38.64934612
OS 33.54245006 -38.65581804
OS 33.54245006 -38.66413908
OS 33.54337462 -38.67338468
OS 33.54429918 -38.68355484
OS 33.54707286 -38.70574428
OS 33.55169566 -38.72978284
OS 33.55724302 -38.7538214
OS 33.5646395 -38.77785996
OS 33.5646395 -38.77878452
OS 33.56556406 -38.78063364
OS 33.56741318 -38.78340732
OS 33.5692623 -38.78803012
OS 33.57480966 -38.79912484
OS 33.5831307 -38.81206868
OS 33.59330086 -38.82686164
OS 33.6062447 -38.84257916
OS 33.62103766 -38.85644756
OS 33.6386043 -38.8693914
OS 33.63952886 -38.8693914
OS 33.64137798 -38.87031596
OS 33.64415166 -38.87216508
OS 33.6478499 -38.8740142
OS 33.6524727 -38.87586332
OS 33.65802006 -38.878637
OS 33.6709639 -38.88418436
OS 33.68760598 -38.88973172
OS 33.70609718 -38.89435452
OS 33.7264375 -38.89805276
OS 33.74770238 -38.89897732
OS 33.7541743 -38.89897732
OS 33.75972166 -38.89805276
OS 33.76619358 -38.89805276
OS 33.7726655 -38.8971282
OS 33.78930758 -38.89342996
OS 33.80872334 -38.88880716
OS 33.8281391 -38.88141068
OS 33.84847942 -38.87124052
OS 33.85864958 -38.86569316
OS 33.86789518 -38.85829668
OS 33.86881974 -38.85737212
OS 33.8697443 -38.85644756
OS 33.87251798 -38.85367388
OS 33.87621622 -38.8509002
OS 33.87991446 -38.8462774
OS 33.88453726 -38.84073004
OS 33.89008462 -38.83518268
OS 33.89470742 -38.8277862
OS 33.90025478 -38.81946516
OS 33.9067267 -38.81021956
OS 33.91227406 -38.80097396
OS 33.91782142 -38.78987924
OS 33.92244422 -38.77785996
OS 33.92706702 -38.76491612
OS 33.93168982 -38.75104772
OS 33.93538806 -38.73625476
OS 34.02044758 -38.75751964
OS 34.02044758 -38.7584442
OS 34.01952302 -38.76214244
OS 34.0176739 -38.7676898
OS 34.01490022 -38.77508628
OS 34.01212654 -38.78340732
OS 34.0084283 -38.79357748
OS 34.0038055 -38.8046722
OS 33.99825814 -38.81669148
OS 33.9853143 -38.84257916
OS 33.96867222 -38.86846684
OS 33.95850206 -38.88141068
OS 33.9483319 -38.89435452
OS 33.93723718 -38.90544924
OS 33.92429334 -38.91654396
OS 33.92336878 -38.91746852
OS 33.92151966 -38.91931764
OS 33.91689686 -38.92116676
OS 33.91227406 -38.924865
OS 33.90487758 -38.9294878
OS 33.8974811 -38.9341106
OS 33.88731094 -38.9387334
OS 33.87714078 -38.9433562
OS 33.8651215 -38.94890356
OS 33.85217766 -38.95352636
OS 33.83830926 -38.95814916
OS 33.8235163 -38.96277196
OS 33.80779878 -38.9664702
OS 33.7911567 -38.96831932
OS 33.77359006 -38.97016844
OS 33.75509886 -38.971093
OS 33.7449287 -38.971093
OS 33.73753222 -38.97016844
OS 33.72921118 -38.97016844
OS 33.71904102 -38.96924388
OS 33.7079463 -38.96739476
OS 33.69500246 -38.96554564
OS 33.66819022 -38.96092284
OS 33.64045342 -38.95352636
OS 33.61271662 -38.9433562
OS 33.59977278 -38.93688428
OS 33.58682894 -38.9294878
OS 33.58590438 -38.92856324
OS 33.58405526 -38.92763868
OS 33.58035702 -38.924865
OS 33.57665878 -38.92116676
OS 33.57111142 -38.91746852
OS 33.5646395 -38.91192116
OS 33.55724302 -38.90544924
OS 33.54984654 -38.89805276
OS 33.54245006 -38.88973172
OS 33.53412902 -38.88141068
OS 33.51748694 -38.8601458
OS 33.50176942 -38.83518268
OS 33.48790102 -38.80744588
OS 33.48790102 -38.80652132
OS 33.4860519 -38.80374764
OS 33.48512734 -38.79912484
OS 33.48235366 -38.79357748
OS 33.48050454 -38.786181
OS 33.47773086 -38.7769354
OS 33.47403262 -38.76676524
OS 33.47125894 -38.75567052
OS 33.46848526 -38.74365124
OS 33.46478702 -38.72978284
OS 33.46016422 -38.70112148
OS 33.45646598 -38.66876188
OS 33.45461686 -38.63547772
OS 33.45461686 -38.63455316
OS 33.45461686 -38.63085492
OS 33.45461686 -38.62530756
OS 33.45554142 -38.61883564
OS 33.45554142 -38.60959004
OS 33.45646598 -38.60034444
OS 33.45739054 -38.58832516
OS 33.45923966 -38.57630588
OS 33.46386246 -38.54949364
OS 33.47033438 -38.51990772
OS 33.47957998 -38.4903218
OS 33.49252382 -38.46166044
OS 33.49344838 -38.46073588
OS 33.49437294 -38.4579622
OS 33.49622206 -38.45426396
OS 33.4999203 -38.44964116
OS 33.50361854 -38.44316924
OS 33.50824134 -38.43577276
OS 33.52026062 -38.41913068
OS 33.53597814 -38.40063948
OS 33.55446934 -38.38214828
OS 33.57573422 -38.36365708
OS 33.60069734 -38.34793956
OS 33.6016219 -38.347015
OS 33.60439558 -38.34609044
OS 33.60809382 -38.34424132
OS 33.61271662 -38.34146764
OS 33.6201131 -38.33869396
OS 33.62750958 -38.33592028
OS 33.63675518 -38.33222204
OS 33.64692534 -38.3285238
OS 33.65802006 -38.32482556
OS 33.67003934 -38.32112732
OS 33.69592702 -38.31557996
OS 33.72551294 -38.31095716
OS 33.75602342 -38.30910804
OS 33.76526902 -38.30910804
OS 33.77174094 -38.3100326
OE
OB 35.15858094 -39.1375138 I
OS 34.63805366 -39.1375138
OS 34.63805366 -39.08111564
OS 35.15858094 -39.08111564
OS 35.15858094 -39.1375138
OE
OB 34.37917686 -38.32112732 I
OS 34.38657334 -38.32112732
OS 34.40321542 -38.32297644
OS 34.42170662 -38.32482556
OS 34.44112238 -38.3285238
OS 34.46053814 -38.3331466
OS 34.47810478 -38.33961852
OS 34.47902934 -38.33961852
OS 34.4799539 -38.34054308
OS 34.48550126 -38.34331676
OS 34.4938223 -38.34793956
OS 34.5030679 -38.35441148
OS 34.51416262 -38.36273252
OS 34.5261819 -38.37290268
OS 34.53727662 -38.38584652
OS 34.54744678 -38.39971492
OS 34.54837134 -38.40156404
OS 34.55114502 -38.4071114
OS 34.55576782 -38.41450788
OS 34.56039062 -38.4256026
OS 34.56501342 -38.43854644
OS 34.56963622 -38.45241484
OS 34.5724099 -38.46813236
OS 34.57333446 -38.48384988
OS 34.57333446 -38.485699
OS 34.57333446 -38.4903218
OS 34.5724099 -38.49864284
OS 34.57056078 -38.508813
OS 34.5677871 -38.52083228
OS 34.5631643 -38.53377612
OS 34.55761694 -38.54671996
OS 34.55022046 -38.56058836
OS 34.5492959 -38.56243748
OS 34.54652222 -38.56613572
OS 34.54097486 -38.5735322
OS 34.53357838 -38.58092868
OS 34.52433278 -38.59017428
OS 34.51323806 -38.60034444
OS 34.49936966 -38.60959004
OS 34.48365214 -38.61883564
OS 34.4845767 -38.61883564
OS 34.48642582 -38.6197602
OS 34.4891995 -38.62068476
OS 34.49289774 -38.62253388
OS 34.50399246 -38.62623212
OS 34.5169363 -38.63270404
OS 34.5308047 -38.64102508
OS 34.54652222 -38.65119524
OS 34.56039062 -38.66321452
OS 34.57333446 -38.67800748
OS 34.57425902 -38.6798566
OS 34.57795726 -38.68540396
OS 34.58350462 -38.693725
OS 34.58905198 -38.70481972
OS 34.59459934 -38.71961268
OS 34.6001467 -38.7353302
OS 34.60384494 -38.7538214
OS 34.6047695 -38.77416172
OS 34.6047695 -38.77508628
OS 34.6047695 -38.77601084
OS 34.6047695 -38.7815582
OS 34.60384494 -38.7908038
OS 34.60199582 -38.80189852
OS 34.6001467 -38.81484236
OS 34.59644846 -38.82871076
OS 34.59182566 -38.84350372
OS 34.58535374 -38.85829668
OS 34.58442918 -38.8601458
OS 34.5816555 -38.8647686
OS 34.57795726 -38.87124052
OS 34.5724099 -38.88048612
OS 34.56501342 -38.88973172
OS 34.55761694 -38.89990188
OS 34.54837134 -38.91007204
OS 34.53820118 -38.91839308
OS 34.53727662 -38.91931764
OS 34.53357838 -38.92209132
OS 34.52710646 -38.92578956
OS 34.51878542 -38.9294878
OS 34.50861526 -38.93503516
OS 34.49659598 -38.94058252
OS 34.48365214 -38.94520532
OS 34.46793462 -38.94982812
OS 34.4660855 -38.94982812
OS 34.46053814 -38.95167724
OS 34.45129254 -38.9526018
OS 34.43927326 -38.95445092
OS 34.4244803 -38.95630004
OS 34.40691366 -38.95814916
OS 34.3874979 -38.95907372
OS 34.36530846 -38.95999828
OS 34.12122462 -38.95999828
OS 34.12122462 -38.32020276
OS 34.37270494 -38.32020276
OS 34.37917686 -38.32112732
OE
OB 31.74233174 -38.95999828 I
OS 31.65264942 -38.95999828
OS 31.65264942 -38.87031596
OS 31.74233174 -38.87031596
OS 31.74233174 -38.95999828
OE
OB 31.52968294 -38.42745172 I
OS 31.50841806 -38.54671996
OS 31.45941638 -38.54671996
OS 31.44000062 -38.42745172
OS 31.44000062 -38.32020276
OS 31.52968294 -38.32020276
OS 31.52968294 -38.42745172
OE
OB 32.0992119 -38.48662356 I
OS 32.10568382 -38.48754812
OS 32.11955222 -38.48939724
OS 32.1361943 -38.49309548
OS 32.15376094 -38.49864284
OS 32.17132758 -38.50696388
OS 32.18889422 -38.51713404
OS 32.18981878 -38.51713404
OS 32.19074334 -38.51898316
OS 32.1962907 -38.5226814
OS 32.20461174 -38.53007788
OS 32.2147819 -38.53932348
OS 32.22587662 -38.55134276
OS 32.23697134 -38.56613572
OS 32.24806606 -38.58370236
OS 32.25731166 -38.60311812
OS 32.25731166 -38.60404268
OS 32.25823622 -38.6058918
OS 32.25916078 -38.60866548
OS 32.2610099 -38.61236372
OS 32.26285902 -38.61791108
OS 32.26470814 -38.624383
OS 32.26933094 -38.63917596
OS 32.27395374 -38.65766716
OS 32.27765198 -38.67800748
OS 32.28042566 -38.70112148
OS 32.28135022 -38.72516004
OS 32.28135022 -38.7260846
OS 32.28135022 -38.72793372
OS 32.28135022 -38.73163196
OS 32.28135022 -38.73717932
OS 32.28042566 -38.74365124
OS 32.28042566 -38.75104772
OS 32.27857654 -38.7676898
OS 32.2748783 -38.78803012
OS 32.2702555 -38.809295
OS 32.26378358 -38.83148444
OS 32.25546254 -38.85367388
OS 32.25546254 -38.85459844
OS 32.25453798 -38.85644756
OS 32.25268886 -38.85922124
OS 32.25083974 -38.86291948
OS 32.24436782 -38.87308964
OS 32.23604678 -38.88603348
OS 32.22587662 -38.89990188
OS 32.21293278 -38.91377028
OS 32.19813982 -38.92763868
OS 32.18057318 -38.94058252
OS 32.17964862 -38.94058252
OS 32.17872406 -38.94150708
OS 32.17595038 -38.9433562
OS 32.17225214 -38.94520532
OS 32.16300654 -38.94982812
OS 32.1500627 -38.95537548
OS 32.13434518 -38.96092284
OS 32.1177031 -38.96554564
OS 32.09828734 -38.96924388
OS 32.07887158 -38.97016844
OS 32.07239966 -38.97016844
OS 32.06500318 -38.96924388
OS 32.05575758 -38.96831932
OS 32.04466286 -38.9664702
OS 32.03264358 -38.96369652
OS 32.0206243 -38.95999828
OS 32.00860502 -38.95445092
OS 32.00768046 -38.95352636
OS 32.00305766 -38.95167724
OS 31.9975103 -38.947979
OS 31.99011382 -38.94243164
OS 31.98271734 -38.93688428
OS 31.97347174 -38.9294878
OS 31.9651507 -38.92116676
OS 31.95775422 -38.91192116
OS 31.95775422 -39.1375138
OS 31.87916662 -39.1375138
OS 31.87916662 -38.49586916
OS 31.95035774 -38.49586916
OS 31.95035774 -38.55689012
OS 31.9512823 -38.555041
OS 31.95498054 -38.55134276
OS 31.95960334 -38.54487084
OS 31.96699982 -38.53747436
OS 31.97532086 -38.52822876
OS 31.98456646 -38.51990772
OS 31.99566118 -38.51158668
OS 32.0067559 -38.5041902
OS 32.00860502 -38.50326564
OS 32.01230326 -38.50141652
OS 32.01969974 -38.49864284
OS 32.02894534 -38.4949446
OS 32.04004006 -38.49124636
OS 32.0529839 -38.48847268
OS 32.06777686 -38.48662356
OS 32.08441894 -38.485699
OS 32.0945891 -38.485699
OS 32.0992119 -38.48662356
OE
OB 32.5614919 -38.48662356 I
OS 32.57166206 -38.48847268
OS 32.58368134 -38.49217092
OS 32.59662518 -38.49679372
OS 32.61141814 -38.50326564
OS 32.62713566 -38.51158668
OS 32.5984743 -38.58370236
OS 32.59754974 -38.5827778
OS 32.5938515 -38.58092868
OS 32.58830414 -38.578155
OS 32.58090766 -38.57538132
OS 32.57258662 -38.57260764
OS 32.56241646 -38.56983396
OS 32.5522463 -38.56798484
OS 32.54207614 -38.56706028
OS 32.53745334 -38.56706028
OS 32.53283054 -38.56798484
OS 32.52635862 -38.5689094
OS 32.5198867 -38.57075852
OS 32.51156566 -38.5735322
OS 32.50324462 -38.57723044
OS 32.49584814 -38.5827778
OS 32.49492358 -38.58370236
OS 32.4921499 -38.58555148
OS 32.48937622 -38.58924972
OS 32.48475342 -38.59387252
OS 32.48013062 -38.60034444
OS 32.47550782 -38.60774092
OS 32.47088502 -38.61606196
OS 32.46718678 -38.62623212
OS 32.46626222 -38.62808124
OS 32.46533766 -38.6336286
OS 32.46348854 -38.64194964
OS 32.46071486 -38.65304436
OS 32.45794118 -38.66691276
OS 32.45609206 -38.68263028
OS 32.4551675 -38.69927236
OS 32.45424294 -38.71776356
OS 32.45424294 -38.95999828
OS 32.37565534 -38.95999828
OS 32.37565534 -38.49586916
OS 32.44684646 -38.49586916
OS 32.44684646 -38.56613572
OS 32.44777102 -38.56521116
OS 32.45146926 -38.55873924
OS 32.45609206 -38.5504182
OS 32.46348854 -38.54024804
OS 32.47088502 -38.53007788
OS 32.47920606 -38.51898316
OS 32.4875271 -38.50973756
OS 32.49584814 -38.50234108
OS 32.4967727 -38.50141652
OS 32.49954638 -38.4995674
OS 32.50509374 -38.49679372
OS 32.5106411 -38.49402004
OS 32.51803758 -38.49124636
OS 32.52728318 -38.48847268
OS 32.53652878 -38.48662356
OS 32.54669894 -38.485699
OS 32.55317086 -38.485699
OS 32.5614919 -38.48662356
OE
OB 32.75195126 -38.4117342 I
OS 32.67336366 -38.4117342
OS 32.67336366 -38.32020276
OS 32.75195126 -38.32020276
OS 32.75195126 -38.4117342
OE
OB 36.56668582 -38.95999828 I
OS 36.47885262 -38.95999828
OS 36.1441619 -38.4579622
OS 36.1441619 -38.95999828
OS 36.06280062 -38.95999828
OS 36.06280062 -38.32020276
OS 36.14970926 -38.32020276
OS 36.48532454 -38.8231634
OS 36.48532454 -38.32020276
OS 36.56668582 -38.32020276
OS 36.56668582 -38.95999828
OE
OB 35.74382742 -38.32112732 I
OS 35.75954494 -38.32205188
OS 35.77618702 -38.32297644
OS 35.79190454 -38.32482556
OS 35.80577294 -38.32667468
OS 35.80762206 -38.32667468
OS 35.81409398 -38.3285238
OS 35.82241502 -38.33037292
OS 35.83350974 -38.3331466
OS 35.84552902 -38.3377694
OS 35.85847286 -38.34331676
OS 35.87234126 -38.34978868
OS 35.88436054 -38.35718516
OS 35.88620966 -38.35810972
OS 35.8899079 -38.3608834
OS 35.89545526 -38.36643076
OS 35.90285174 -38.37290268
OS 35.91117278 -38.38122372
OS 35.91949382 -38.39231844
OS 35.92873942 -38.40433772
OS 35.9361359 -38.41820612
OS 35.93706046 -38.42005524
OS 35.93890958 -38.42467804
OS 35.94260782 -38.43299908
OS 35.94630606 -38.4440938
OS 35.94907974 -38.45703764
OS 35.95277798 -38.4718306
OS 35.9546271 -38.48847268
OS 35.95555166 -38.50603932
OS 35.95555166 -38.50696388
OS 35.95555166 -38.50973756
OS 35.95555166 -38.5134358
OS 35.9546271 -38.51990772
OS 35.95370254 -38.52637964
OS 35.95277798 -38.53470068
OS 35.95092886 -38.54394628
OS 35.94907974 -38.55411644
OS 35.94260782 -38.57538132
OS 35.93890958 -38.58647604
OS 35.93336222 -38.59849532
OS 35.9268903 -38.6105146
OS 35.92041838 -38.62160932
OS 35.91209734 -38.63270404
OS 35.90285174 -38.64379876
OS 35.90192718 -38.64472332
OS 35.90007806 -38.64657244
OS 35.89730438 -38.64934612
OS 35.89268158 -38.6521198
OS 35.88713422 -38.6567426
OS 35.87973774 -38.6613654
OS 35.87049214 -38.66691276
OS 35.86032198 -38.67153556
OS 35.8483027 -38.67708292
OS 35.8344343 -38.68263028
OS 35.81964134 -38.68725308
OS 35.8020747 -38.69095132
OS 35.7835835 -38.69464956
OS 35.76324318 -38.69742324
OS 35.74012918 -38.69927236
OS 35.71609062 -38.70019692
OS 35.5524435 -38.70019692
OS 35.5524435 -38.95999828
OS 35.46738398 -38.95999828
OS 35.46738398 -38.32020276
OS 35.72995902 -38.32020276
OS 35.74382742 -38.32112732
OE
OB 36.76916446 -38.42745172 I
OS 36.74789958 -38.54671996
OS 36.6988979 -38.54671996
OS 36.67948214 -38.42745172
OS 36.67948214 -38.32020276
OS 36.76916446 -38.32020276
OS 36.76916446 -38.42745172
OE
OB 38.2382903 -38.39601668 I
OS 37.86014526 -38.39601668
OS 37.86014526 -38.59109884
OS 38.21425174 -38.59109884
OS 38.21425174 -38.66691276
OS 37.86014526 -38.66691276
OS 37.86014526 -38.88418436
OS 38.25308326 -38.88418436
OS 38.25308326 -38.95999828
OS 37.77508574 -38.95999828
OS 37.77508574 -38.32020276
OS 38.2382903 -38.32020276
OS 38.2382903 -38.39601668
OE
OB 37.4339231 -38.32112732 I
OS 37.44224414 -38.32112732
OS 37.4616599 -38.32205188
OS 37.48200022 -38.32482556
OS 37.50418966 -38.32759924
OS 37.52452998 -38.33222204
OS 37.53470014 -38.33499572
OS 37.54302118 -38.3377694
OS 37.54394574 -38.3377694
OS 37.5448703 -38.33869396
OS 37.55041766 -38.34146764
OS 37.5587387 -38.34516588
OS 37.56890886 -38.3516378
OS 37.58000358 -38.35995884
OS 37.59202286 -38.37105356
OS 37.60311758 -38.3839974
OS 37.6142123 -38.39879036
OS 37.6142123 -38.39971492
OS 37.61513686 -38.40063948
OS 37.6188351 -38.40618684
OS 37.62253334 -38.41543244
OS 37.6280807 -38.42745172
OS 37.6327035 -38.44132012
OS 37.6373263 -38.4579622
OS 37.64009998 -38.47552884
OS 37.64102454 -38.4949446
OS 37.64102454 -38.49586916
OS 37.64102454 -38.49771828
OS 37.64102454 -38.50141652
OS 37.64009998 -38.50603932
OS 37.64009998 -38.51251124
OS 37.63917542 -38.51898316
OS 37.63547718 -38.53470068
OS 37.62992982 -38.55319188
OS 37.62253334 -38.57260764
OS 37.61143862 -38.5920234
OS 37.60404214 -38.601269
OS 37.59664566 -38.6105146
OS 37.5957211 -38.61143916
OS 37.59479654 -38.61236372
OS 37.59202286 -38.6151374
OS 37.58832462 -38.61791108
OS 37.58370182 -38.62160932
OS 37.57815446 -38.62530756
OS 37.57075798 -38.62993036
OS 37.5633615 -38.63547772
OS 37.5541159 -38.64010052
OS 37.54394574 -38.64472332
OS 37.53285102 -38.65027068
OS 37.52083174 -38.65489348
OS 37.50696334 -38.65859172
OS 37.49309494 -38.66321452
OS 37.47737742 -38.6659882
OS 37.46073534 -38.66876188
OS 37.46258446 -38.66968644
OS 37.4662827 -38.67153556
OS 37.47183006 -38.6752338
OS 37.47922654 -38.67893204
OS 37.49586862 -38.6891022
OS 37.50418966 -38.69557412
OS 37.51158614 -38.70112148
OS 37.51343526 -38.7029706
OS 37.51805806 -38.7075934
OS 37.52545454 -38.71498988
OS 37.53470014 -38.72423548
OS 37.5448703 -38.73717932
OS 37.55688958 -38.75104772
OS 37.56890886 -38.7676898
OS 37.5818527 -38.786181
OS 37.69187534 -38.95999828
OS 37.5864755 -38.95999828
OS 37.50234054 -38.82686164
OS 37.50234054 -38.82593708
OS 37.50049142 -38.82408796
OS 37.4986423 -38.82131428
OS 37.49586862 -38.81761604
OS 37.4893967 -38.80744588
OS 37.48107566 -38.79450204
OS 37.4709055 -38.78063364
OS 37.46073534 -38.76584068
OS 37.45056518 -38.75197228
OS 37.44131958 -38.73902844
OS 37.44039502 -38.73810388
OS 37.43762134 -38.73440564
OS 37.43299854 -38.72885828
OS 37.42652662 -38.72238636
OS 37.41265822 -38.70851796
OS 37.40526174 -38.70204604
OS 37.39786526 -38.69649868
OS 37.3969407 -38.69557412
OS 37.39509158 -38.69464956
OS 37.39139334 -38.69280044
OS 37.38584598 -38.69002676
OS 37.38029862 -38.68725308
OS 37.3738267 -38.6844794
OS 37.35903374 -38.6798566
OS 37.35810918 -38.6798566
OS 37.35626006 -38.67893204
OS 37.35256182 -38.67893204
OS 37.34793902 -38.67800748
OS 37.3414671 -38.67708292
OS 37.33407062 -38.67708292
OS 37.32390046 -38.67615836
OS 37.21480238 -38.67615836
OS 37.21480238 -38.95999828
OS 37.12974286 -38.95999828
OS 37.12974286 -38.32020276
OS 37.42652662 -38.32020276
OS 37.4339231 -38.32112732
OE
OB 35.31760526 -38.95999828 I
OS 35.23254574 -38.95999828
OS 35.23254574 -38.32020276
OS 35.31760526 -38.32020276
OS 35.31760526 -38.95999828
OE
OB 42.12051774 -38.66413908 H
OS 41.95224782 -38.66413908
OS 41.95224782 -38.88418436
OS 42.13438614 -38.88418436
OS 42.1538019 -38.8832598
OS 42.16212294 -38.88233524
OS 42.16951942 -38.88141068
OS 42.17044398 -38.88141068
OS 42.17414222 -38.88048612
OS 42.17968958 -38.87956156
OS 42.1861615 -38.87771244
OS 42.20187902 -38.87216508
OS 42.21759654 -38.8647686
OS 42.2185211 -38.86384404
OS 42.22129478 -38.86199492
OS 42.22499302 -38.85922124
OS 42.22961582 -38.855523
OS 42.23423862 -38.84997564
OS 42.24071054 -38.84442828
OS 42.24533334 -38.8370318
OS 42.2508807 -38.82871076
OS 42.25180526 -38.8277862
OS 42.25272982 -38.82501252
OS 42.25457894 -38.81946516
OS 42.25735262 -38.81299324
OS 42.2601263 -38.80559676
OS 42.26197542 -38.79635116
OS 42.26289998 -38.78525644
OS 42.26382454 -38.77416172
OS 42.26382454 -38.7723126
OS 42.26382454 -38.76861436
OS 42.26289998 -38.76121788
OS 42.26105086 -38.75289684
OS 42.25920174 -38.74365124
OS 42.2555035 -38.73348108
OS 42.2508807 -38.72331092
OS 42.24440878 -38.71314076
OS 42.24348422 -38.7122162
OS 42.24071054 -38.70851796
OS 42.2370123 -38.70389516
OS 42.23146494 -38.6983478
OS 42.22406846 -38.69187588
OS 42.21482286 -38.68540396
OS 42.2046527 -38.6798566
OS 42.19263342 -38.6752338
OS 42.1907843 -38.67430924
OS 42.18708606 -38.67338468
OS 42.17876502 -38.67153556
OS 42.16859486 -38.66968644
OS 42.15565102 -38.66783732
OS 42.1399335 -38.6659882
OS 42.12051774 -38.66413908
OE
OB 45.22981302 -38.5504182 H
OS 45.22426566 -38.5504182
OS 45.21964286 -38.55134276
OS 45.2094727 -38.55226732
OS 45.1956043 -38.55596556
OS 45.17988678 -38.56151292
OS 45.1632447 -38.5689094
OS 45.14752718 -38.58000412
OS 45.13920614 -38.5874006
OS 45.13180966 -38.59479708
OS 45.13180966 -38.59572164
OS 45.12996054 -38.5966462
OS 45.12811142 -38.59941988
OS 45.12533774 -38.60311812
OS 45.12256406 -38.60774092
OS 45.11979038 -38.61328828
OS 45.11609214 -38.62068476
OS 45.1123939 -38.62808124
OS 45.10869566 -38.63732684
OS 45.10499742 -38.64657244
OS 45.10222374 -38.65766716
OS 45.09945006 -38.66968644
OS 45.09667638 -38.68263028
OS 45.09482726 -38.69649868
OS 45.0939027 -38.7122162
OS 45.09297814 -38.72793372
OS 45.09297814 -38.72885828
OS 45.09297814 -38.73163196
OS 45.09297814 -38.73625476
OS 45.0939027 -38.74272668
OS 45.0939027 -38.75012316
OS 45.09482726 -38.7584442
OS 45.09760094 -38.77785996
OS 45.10222374 -38.8000494
OS 45.10962022 -38.82223884
OS 45.11886582 -38.84350372
OS 45.12533774 -38.85274932
OS 45.13180966 -38.86199492
OS 45.13273422 -38.86199492
OS 45.13365878 -38.86384404
OS 45.13920614 -38.86846684
OS 45.14752718 -38.87586332
OS 45.1586219 -38.8832598
OS 45.1724903 -38.89158084
OS 45.18913238 -38.89897732
OS 45.20854814 -38.90360012
OS 45.2187183 -38.90452468
OS 45.22981302 -38.90544924
OS 45.23536038 -38.90544924
OS 45.23998318 -38.90452468
OS 45.25015334 -38.90267556
OS 45.26402174 -38.89990188
OS 45.2788147 -38.89435452
OS 45.29545678 -38.88695804
OS 45.3111743 -38.87586332
OS 45.31949534 -38.86846684
OS 45.32689182 -38.86107036
OS 45.32781638 -38.8601458
OS 45.32874094 -38.85922124
OS 45.33059006 -38.85644756
OS 45.33336374 -38.85274932
OS 45.33613742 -38.84812652
OS 45.33983566 -38.84257916
OS 45.3435339 -38.83518268
OS 45.34723214 -38.8277862
OS 45.35093038 -38.8185406
OS 45.35370406 -38.80837044
OS 45.3574023 -38.79727572
OS 45.36017598 -38.78525644
OS 45.36294966 -38.77138804
OS 45.36479878 -38.75751964
OS 45.3666479 -38.74180212
OS 45.3666479 -38.72516004
OS 45.3666479 -38.72423548
OS 45.3666479 -38.7214618
OS 45.3666479 -38.716839
OS 45.36572334 -38.71129164
OS 45.36572334 -38.70389516
OS 45.36479878 -38.69557412
OS 45.3620251 -38.67615836
OS 45.3574023 -38.65581804
OS 45.35000582 -38.6336286
OS 45.33983566 -38.61328828
OS 45.3342883 -38.60311812
OS 45.32689182 -38.59479708
OS 45.32689182 -38.59387252
OS 45.3250427 -38.59294796
OS 45.31949534 -38.5874006
OS 45.3111743 -38.58092868
OS 45.30007958 -38.57260764
OS 45.28621118 -38.5642866
OS 45.2695691 -38.55689012
OS 45.2510779 -38.55226732
OS 45.24090774 -38.55134276
OS 45.22981302 -38.5504182
OE
OB 32.07702246 -38.54764452 H
OS 32.07239966 -38.54764452
OS 32.06870142 -38.54856908
OS 32.05945582 -38.5504182
OS 32.04743654 -38.55319188
OS 32.03356814 -38.55873924
OS 32.01877518 -38.56706028
OS 32.01045414 -38.57260764
OS 32.00305766 -38.57907956
OS 31.99566118 -38.58647604
OS 31.9882647 -38.59479708
OS 31.9882647 -38.59572164
OS 31.98641558 -38.5966462
OS 31.98456646 -38.59941988
OS 31.98271734 -38.60311812
OS 31.97994366 -38.60866548
OS 31.97624542 -38.61421284
OS 31.97254718 -38.62160932
OS 31.9697735 -38.6290058
OS 31.96607526 -38.6382514
OS 31.96237702 -38.64842156
OS 31.95960334 -38.65951628
OS 31.9559051 -38.67153556
OS 31.95405598 -38.68540396
OS 31.95220686 -38.69927236
OS 31.95035774 -38.71406532
OS 31.95035774 -38.7307074
OS 31.95035774 -38.73163196
OS 31.95035774 -38.73440564
OS 31.95035774 -38.73902844
OS 31.9512823 -38.74550036
OS 31.9512823 -38.75289684
OS 31.95220686 -38.76121788
OS 31.95498054 -38.78063364
OS 31.95960334 -38.80282308
OS 31.9651507 -38.82408796
OS 31.9743963 -38.84535284
OS 31.97994366 -38.85459844
OS 31.98641558 -38.86291948
OS 31.9882647 -38.8647686
OS 31.9928875 -38.8693914
OS 32.00028398 -38.87678788
OS 32.01045414 -38.88418436
OS 32.02339798 -38.89158084
OS 32.03819094 -38.89897732
OS 32.05483302 -38.90360012
OS 32.06407862 -38.90452468
OS 32.07332422 -38.90544924
OS 32.07887158 -38.90544924
OS 32.08256982 -38.90452468
OS 32.09181542 -38.90267556
OS 32.10475926 -38.89990188
OS 32.11862766 -38.89435452
OS 32.13342062 -38.88695804
OS 32.14821358 -38.87586332
OS 32.15561006 -38.8693914
OS 32.16300654 -38.86199492
OS 32.16300654 -38.86107036
OS 32.16485566 -38.8601458
OS 32.16670478 -38.85737212
OS 32.1685539 -38.85367388
OS 32.17225214 -38.84905108
OS 32.17502582 -38.84257916
OS 32.17872406 -38.83610724
OS 32.1824223 -38.8277862
OS 32.18519598 -38.81946516
OS 32.18889422 -38.80837044
OS 32.19259246 -38.79727572
OS 32.19536614 -38.78525644
OS 32.19721526 -38.77138804
OS 32.19906438 -38.75659508
OS 32.2009135 -38.74087756
OS 32.2009135 -38.72423548
OS 32.2009135 -38.72331092
OS 32.2009135 -38.72053724
OS 32.2009135 -38.71591444
OS 32.19998894 -38.70944252
OS 32.19998894 -38.70204604
OS 32.19906438 -38.693725
OS 32.1962907 -38.67430924
OS 32.1916679 -38.65304436
OS 32.18519598 -38.63177948
OS 32.17595038 -38.6105146
OS 32.17040302 -38.60034444
OS 32.1639311 -38.5920234
OS 32.1639311 -38.59109884
OS 32.16208198 -38.59017428
OS 32.15745918 -38.58462692
OS 32.1500627 -38.578155
OS 32.13989254 -38.56983396
OS 32.1269487 -38.56151292
OS 32.11215574 -38.55411644
OS 32.09551366 -38.54949364
OS 32.08626806 -38.54856908
OS 32.07702246 -38.54764452
OE
OB 42.10387566 -38.39601668 H
OS 41.95224782 -38.39601668
OS 41.95224782 -38.58832516
OS 42.10942302 -38.58832516
OS 42.1214423 -38.5874006
OS 42.13438614 -38.58647604
OS 42.14732998 -38.58555148
OS 42.16027382 -38.58370236
OS 42.17044398 -38.58185324
OS 42.1722931 -38.58092868
OS 42.17599134 -38.58000412
OS 42.1815387 -38.57723044
OS 42.18893518 -38.5735322
OS 42.19633166 -38.56983396
OS 42.2046527 -38.5642866
OS 42.21297374 -38.55689012
OS 42.21944566 -38.54949364
OS 42.22037022 -38.54856908
OS 42.22221934 -38.5457954
OS 42.22499302 -38.54024804
OS 42.2277667 -38.53377612
OS 42.23054038 -38.52637964
OS 42.23331406 -38.51713404
OS 42.23516318 -38.50603932
OS 42.23608774 -38.49402004
OS 42.23608774 -38.49217092
OS 42.23608774 -38.48847268
OS 42.23516318 -38.48292532
OS 42.23423862 -38.47552884
OS 42.2323895 -38.46628324
OS 42.22961582 -38.45703764
OS 42.22591758 -38.44779204
OS 42.22037022 -38.43854644
OS 42.21944566 -38.43762188
OS 42.21759654 -38.4348482
OS 42.2138983 -38.4302254
OS 42.2092755 -38.4256026
OS 42.20280358 -38.42005524
OS 42.1954071 -38.41450788
OS 42.1861615 -38.40896052
OS 42.17599134 -38.40526228
OS 42.17506678 -38.40526228
OS 42.17044398 -38.40341316
OS 42.16397206 -38.4024886
OS 42.1538019 -38.40063948
OS 42.1399335 -38.39879036
OS 42.12421598 -38.3978658
OS 42.10387566 -38.39601668
OE
OB 37.41635646 -38.39139388 H
OS 37.21480238 -38.39139388
OS 37.21480238 -38.60311812
OS 37.40526174 -38.60311812
OS 37.41635646 -38.60219356
OS 37.4293003 -38.601269
OS 37.44409326 -38.60034444
OS 37.45888622 -38.59849532
OS 37.47367918 -38.59572164
OS 37.48662302 -38.5920234
OS 37.48847214 -38.59109884
OS 37.49217038 -38.58924972
OS 37.49771774 -38.58647604
OS 37.50511422 -38.5827778
OS 37.51343526 -38.57723044
OS 37.5217563 -38.57075852
OS 37.53007734 -38.56243748
OS 37.53654926 -38.55319188
OS 37.53747382 -38.55226732
OS 37.53932294 -38.54856908
OS 37.54209662 -38.54302172
OS 37.54579486 -38.53562524
OS 37.54856854 -38.5273042
OS 37.55134222 -38.5180586
OS 37.55319134 -38.50696388
OS 37.5541159 -38.49586916
OS 37.5541159 -38.4949446
OS 37.5541159 -38.49402004
OS 37.55319134 -38.48847268
OS 37.55226678 -38.48015164
OS 37.55041766 -38.46905692
OS 37.54579486 -38.4579622
OS 37.5402475 -38.44501836
OS 37.53192646 -38.43299908
OS 37.52083174 -38.4209798
OS 37.51898262 -38.42005524
OS 37.51435982 -38.416357
OS 37.50696334 -38.4117342
OS 37.49494406 -38.40618684
OS 37.48107566 -38.40063948
OS 37.46258446 -38.39601668
OS 37.44131958 -38.39231844
OS 37.41635646 -38.39139388
OE
OB 39.82298614 -38.54764452 H
OS 39.81836334 -38.54764452
OS 39.8146651 -38.54856908
OS 39.8054195 -38.5504182
OS 39.79340022 -38.55319188
OS 39.77953182 -38.55873924
OS 39.76473886 -38.56706028
OS 39.75641782 -38.57260764
OS 39.74902134 -38.57907956
OS 39.74162486 -38.58647604
OS 39.73422838 -38.59479708
OS 39.73422838 -38.59572164
OS 39.73237926 -38.5966462
OS 39.73053014 -38.59941988
OS 39.72868102 -38.60311812
OS 39.72590734 -38.60866548
OS 39.7222091 -38.61421284
OS 39.71851086 -38.62160932
OS 39.71573718 -38.6290058
OS 39.71203894 -38.6382514
OS 39.7083407 -38.64842156
OS 39.70556702 -38.65951628
OS 39.70186878 -38.67153556
OS 39.70001966 -38.68540396
OS 39.69817054 -38.69927236
OS 39.69632142 -38.71406532
OS 39.69632142 -38.7307074
OS 39.69632142 -38.73163196
OS 39.69632142 -38.73440564
OS 39.69632142 -38.73902844
OS 39.69724598 -38.74550036
OS 39.69724598 -38.75289684
OS 39.69817054 -38.76121788
OS 39.70094422 -38.78063364
OS 39.70556702 -38.80282308
OS 39.71111438 -38.82408796
OS 39.72035998 -38.84535284
OS 39.72590734 -38.85459844
OS 39.73237926 -38.86291948
OS 39.73422838 -38.8647686
OS 39.73885118 -38.8693914
OS 39.74624766 -38.87678788
OS 39.75641782 -38.88418436
OS 39.76936166 -38.89158084
OS 39.78415462 -38.89897732
OS 39.8007967 -38.90360012
OS 39.8100423 -38.90452468
OS 39.8192879 -38.90544924
OS 39.82483526 -38.90544924
OS 39.8285335 -38.90452468
OS 39.8377791 -38.90267556
OS 39.85072294 -38.89990188
OS 39.86459134 -38.89435452
OS 39.8793843 -38.88695804
OS 39.89417726 -38.87586332
OS 39.90157374 -38.8693914
OS 39.90897022 -38.86199492
OS 39.90897022 -38.86107036
OS 39.91081934 -38.8601458
OS 39.91266846 -38.85737212
OS 39.91451758 -38.85367388
OS 39.91821582 -38.84905108
OS 39.9209895 -38.84257916
OS 39.92468774 -38.83610724
OS 39.92838598 -38.8277862
OS 39.93115966 -38.81946516
OS 39.9348579 -38.80837044
OS 39.93855614 -38.79727572
OS 39.94132982 -38.78525644
OS 39.94317894 -38.77138804
OS 39.94502806 -38.75659508
OS 39.94687718 -38.74087756
OS 39.94687718 -38.72423548
OS 39.94687718 -38.72331092
OS 39.94687718 -38.72053724
OS 39.94687718 -38.71591444
OS 39.94595262 -38.70944252
OS 39.94595262 -38.70204604
OS 39.94502806 -38.693725
OS 39.94225438 -38.67430924
OS 39.93763158 -38.65304436
OS 39.93115966 -38.63177948
OS 39.92191406 -38.6105146
OS 39.9163667 -38.60034444
OS 39.90989478 -38.5920234
OS 39.90989478 -38.59109884
OS 39.90804566 -38.59017428
OS 39.90342286 -38.58462692
OS 39.89602638 -38.578155
OS 39.88585622 -38.56983396
OS 39.87291238 -38.56151292
OS 39.85811942 -38.55411644
OS 39.84147734 -38.54949364
OS 39.83223174 -38.54856908
OS 39.82298614 -38.54764452
OE
OB 35.73550638 -38.39601668 H
OS 35.5524435 -38.39601668
OS 35.5524435 -38.624383
OS 35.72441166 -38.624383
OS 35.73088358 -38.62345844
OS 35.7373555 -38.62345844
OS 35.74475198 -38.62253388
OS 35.76231862 -38.62068476
OS 35.78173438 -38.61698652
OS 35.80115014 -38.61143916
OS 35.81871678 -38.60404268
OS 35.82703782 -38.59941988
OS 35.83350974 -38.59387252
OS 35.83535886 -38.5920234
OS 35.8390571 -38.58832516
OS 35.84460446 -38.58092868
OS 35.85107638 -38.57168308
OS 35.8575483 -38.5596638
OS 35.86309566 -38.54487084
OS 35.8667939 -38.52822876
OS 35.86864302 -38.508813
OS 35.86864302 -38.50788844
OS 35.86864302 -38.50696388
OS 35.86864302 -38.50234108
OS 35.86771846 -38.49402004
OS 35.86586934 -38.48477444
OS 35.86402022 -38.47460428
OS 35.86032198 -38.462585
OS 35.85477462 -38.45149028
OS 35.8483027 -38.44039556
OS 35.84737814 -38.439471
OS 35.84460446 -38.43577276
OS 35.83998166 -38.43114996
OS 35.8344343 -38.42467804
OS 35.82611326 -38.41820612
OS 35.81686766 -38.41265876
OS 35.8066975 -38.4071114
OS 35.79467822 -38.4024886
OS 35.79375366 -38.4024886
OS 35.79005542 -38.40156404
OS 35.78450806 -38.40063948
OS 35.77711158 -38.39879036
OS 35.76601686 -38.3978658
OS 35.75214846 -38.39694124
OS 35.73550638 -38.39601668
OE
OB 43.44263854 -38.5504182 H
OS 43.43709118 -38.5504182
OS 43.43339294 -38.55134276
OS 43.42322278 -38.55226732
OS 43.4112035 -38.555041
OS 43.39641054 -38.5596638
OS 43.38069302 -38.56613572
OS 43.36590006 -38.57538132
OS 43.3511071 -38.5874006
OS 43.34925798 -38.58924972
OS 43.34555974 -38.59387252
OS 43.33908782 -38.60219356
OS 43.3326159 -38.61328828
OS 43.32521942 -38.62623212
OS 43.3187475 -38.6428742
OS 43.31320014 -38.66228996
OS 43.31042646 -38.68355484
OS 43.57022782 -38.68355484
OS 43.57022782 -38.68263028
OS 43.57022782 -38.68078116
OS 43.56930326 -38.67800748
OS 43.56930326 -38.67430924
OS 43.56745414 -38.66321452
OS 43.56468046 -38.65119524
OS 43.56005766 -38.63640228
OS 43.55543486 -38.62253388
OS 43.54803838 -38.60866548
OS 43.53971734 -38.5966462
OS 43.53971734 -38.59572164
OS 43.53786822 -38.59479708
OS 43.53324542 -38.58924972
OS 43.52492438 -38.58185324
OS 43.51382966 -38.5735322
OS 43.49996126 -38.56521116
OS 43.48331918 -38.55781468
OS 43.46390342 -38.55226732
OS 43.45373326 -38.55134276
OS 43.44263854 -38.5504182
OE
OB 34.35791198 -38.39601668 H
OS 34.20628414 -38.39601668
OS 34.20628414 -38.58832516
OS 34.36345934 -38.58832516
OS 34.37547862 -38.5874006
OS 34.38842246 -38.58647604
OS 34.4013663 -38.58555148
OS 34.41431014 -38.58370236
OS 34.4244803 -38.58185324
OS 34.42632942 -38.58092868
OS 34.43002766 -38.58000412
OS 34.43557502 -38.57723044
OS 34.4429715 -38.5735322
OS 34.45036798 -38.56983396
OS 34.45868902 -38.5642866
OS 34.46701006 -38.55689012
OS 34.47348198 -38.54949364
OS 34.47440654 -38.54856908
OS 34.47625566 -38.5457954
OS 34.47902934 -38.54024804
OS 34.48180302 -38.53377612
OS 34.4845767 -38.52637964
OS 34.48735038 -38.51713404
OS 34.4891995 -38.50603932
OS 34.49012406 -38.49402004
OS 34.49012406 -38.49217092
OS 34.49012406 -38.48847268
OS 34.4891995 -38.48292532
OS 34.48827494 -38.47552884
OS 34.48642582 -38.46628324
OS 34.48365214 -38.45703764
OS 34.4799539 -38.44779204
OS 34.47440654 -38.43854644
OS 34.47348198 -38.43762188
OS 34.47163286 -38.4348482
OS 34.46793462 -38.4302254
OS 34.46331182 -38.4256026
OS 34.4568399 -38.42005524
OS 34.44944342 -38.41450788
OS 34.44019782 -38.40896052
OS 34.43002766 -38.40526228
OS 34.4291031 -38.40526228
OS 34.4244803 -38.40341316
OS 34.41800838 -38.4024886
OS 34.40783822 -38.40063948
OS 34.39396982 -38.39879036
OS 34.3782523 -38.3978658
OS 34.35791198 -38.39601668
OE
OB 40.89732486 -38.39601668 H
OS 40.71426198 -38.39601668
OS 40.71426198 -38.624383
OS 40.88623014 -38.624383
OS 40.89270206 -38.62345844
OS 40.89917398 -38.62345844
OS 40.90657046 -38.62253388
OS 40.9241371 -38.62068476
OS 40.94355286 -38.61698652
OS 40.96296862 -38.61143916
OS 40.98053526 -38.60404268
OS 40.9888563 -38.59941988
OS 40.99532822 -38.59387252
OS 40.99717734 -38.5920234
OS 41.00087558 -38.58832516
OS 41.00642294 -38.58092868
OS 41.01289486 -38.57168308
OS 41.01936678 -38.5596638
OS 41.02491414 -38.54487084
OS 41.02861238 -38.52822876
OS 41.0304615 -38.508813
OS 41.0304615 -38.50788844
OS 41.0304615 -38.50696388
OS 41.0304615 -38.50234108
OS 41.02953694 -38.49402004
OS 41.02768782 -38.48477444
OS 41.0258387 -38.47460428
OS 41.02214046 -38.462585
OS 41.0165931 -38.45149028
OS 41.01012118 -38.44039556
OS 41.00919662 -38.439471
OS 41.00642294 -38.43577276
OS 41.00180014 -38.43114996
OS 40.99625278 -38.42467804
OS 40.98793174 -38.41820612
OS 40.97868614 -38.41265876
OS 40.96851598 -38.4071114
OS 40.9564967 -38.4024886
OS 40.95557214 -38.4024886
OS 40.9518739 -38.40156404
OS 40.94632654 -38.40063948
OS 40.93893006 -38.39879036
OS 40.92783534 -38.3978658
OS 40.91396694 -38.39694124
OS 40.89732486 -38.39601668
OE
OB 33.15136118 -38.39601668 H
OS 32.9682983 -38.39601668
OS 32.9682983 -38.624383
OS 33.14026646 -38.624383
OS 33.14673838 -38.62345844
OS 33.1532103 -38.62345844
OS 33.16060678 -38.62253388
OS 33.17817342 -38.62068476
OS 33.19758918 -38.61698652
OS 33.21700494 -38.61143916
OS 33.23457158 -38.60404268
OS 33.24289262 -38.59941988
OS 33.24936454 -38.59387252
OS 33.25121366 -38.5920234
OS 33.2549119 -38.58832516
OS 33.26045926 -38.58092868
OS 33.26693118 -38.57168308
OS 33.2734031 -38.5596638
OS 33.27895046 -38.54487084
OS 33.2826487 -38.52822876
OS 33.28449782 -38.508813
OS 33.28449782 -38.50788844
OS 33.28449782 -38.50696388
OS 33.28449782 -38.50234108
OS 33.28357326 -38.49402004
OS 33.28172414 -38.48477444
OS 33.27987502 -38.47460428
OS 33.27617678 -38.462585
OS 33.27062942 -38.45149028
OS 33.2641575 -38.44039556
OS 33.26323294 -38.439471
OS 33.26045926 -38.43577276
OS 33.25583646 -38.43114996
OS 33.2502891 -38.42467804
OS 33.24196806 -38.41820612
OS 33.23272246 -38.41265876
OS 33.2225523 -38.4071114
OS 33.21053302 -38.4024886
OS 33.20960846 -38.4024886
OS 33.20591022 -38.40156404
OS 33.20036286 -38.40063948
OS 33.19296638 -38.39879036
OS 33.18187166 -38.3978658
OS 33.16800326 -38.39694124
OS 33.15136118 -38.39601668
OE
OB 34.37455406 -38.66413908 H
OS 34.20628414 -38.66413908
OS 34.20628414 -38.88418436
OS 34.38842246 -38.88418436
OS 34.40783822 -38.8832598
OS 34.41615926 -38.88233524
OS 34.42355574 -38.88141068
OS 34.4244803 -38.88141068
OS 34.42817854 -38.88048612
OS 34.4337259 -38.87956156
OS 34.44019782 -38.87771244
OS 34.45591534 -38.87216508
OS 34.47163286 -38.8647686
OS 34.47255742 -38.86384404
OS 34.4753311 -38.86199492
OS 34.47902934 -38.85922124
OS 34.48365214 -38.855523
OS 34.48827494 -38.84997564
OS 34.49474686 -38.84442828
OS 34.49936966 -38.8370318
OS 34.50491702 -38.82871076
OS 34.50584158 -38.8277862
OS 34.50676614 -38.82501252
OS 34.50861526 -38.81946516
OS 34.51138894 -38.81299324
OS 34.51416262 -38.80559676
OS 34.51601174 -38.79635116
OS 34.5169363 -38.78525644
OS 34.51786086 -38.77416172
OS 34.51786086 -38.7723126
OS 34.51786086 -38.76861436
OS 34.5169363 -38.76121788
OS 34.51508718 -38.75289684
OS 34.51323806 -38.74365124
OS 34.50953982 -38.73348108
OS 34.50491702 -38.72331092
OS 34.4984451 -38.71314076
OS 34.49752054 -38.7122162
OS 34.49474686 -38.70851796
OS 34.49104862 -38.70389516
OS 34.48550126 -38.6983478
OS 34.47810478 -38.69187588
OS 34.46885918 -38.68540396
OS 34.45868902 -38.6798566
OS 34.44666974 -38.6752338
OS 34.44482062 -38.67430924
OS 34.44112238 -38.67338468
OS 34.43280134 -38.67153556
OS 34.42263118 -38.66968644
OS 34.40968734 -38.66783732
OS 34.39396982 -38.6659882
OS 34.37455406 -38.66413908
OE
SE
S P 0
OB 48.49040086 -36.61402634 I
OS 48.17420134 -36.61402634
OS 48.17420134 -37.45999874
OS 48.04661206 -37.45999874
OS 48.04661206 -36.61402634
OS 47.73041254 -36.61402634
OS 47.73041254 -36.50030546
OS 48.49040086 -36.50030546
OS 48.49040086 -36.61402634
OE
OB 47.69990206 -37.45999874 I
OS 47.5556707 -37.45999874
OS 47.44333666 -37.16876234
OS 47.04115306 -37.16876234
OS 46.93714006 -37.45999874
OS 46.80261658 -37.45999874
OS 47.16874234 -36.50030546
OS 47.30742634 -36.50030546
OS 47.69990206 -37.45999874
OE
OB 49.31834434 -36.61402634 I
OS 48.75112678 -36.61402634
OS 48.75112678 -36.90664958
OS 49.2822865 -36.90664958
OS 49.2822865 -37.02037046
OS 48.75112678 -37.02037046
OS 48.75112678 -37.34627786
OS 49.34053378 -37.34627786
OS 49.34053378 -37.45999874
OS 48.6235375 -37.45999874
OS 48.6235375 -36.50030546
OS 49.31834434 -36.50030546
OS 49.31834434 -36.61402634
OE
OB 46.33386466 -36.5016923 I
OS 46.36160146 -36.50307914
OS 46.38933826 -36.50585282
OS 46.41707506 -36.51001334
OS 46.44065134 -36.51417386
OS 46.44203818 -36.51417386
OS 46.44481186 -36.5155607
OS 46.44897238 -36.5155607
OS 46.45451974 -36.51833438
OS 46.46977498 -36.5224949
OS 46.48919074 -36.5294291
OS 46.51138018 -36.53913698
OS 46.53495646 -36.55161854
OS 46.55853274 -36.56548694
OS 46.58072218 -36.58351586
OS 46.58210902 -36.5849027
OS 46.58349586 -36.58628954
OS 46.58765638 -36.59045006
OS 46.59320374 -36.59461058
OS 46.60707214 -36.60847898
OS 46.62371422 -36.62789474
OS 46.64174314 -36.65147102
OS 46.6611589 -36.67920782
OS 46.67918782 -36.71110514
OS 46.69444306 -36.74716298
OS 46.69444306 -36.74854982
OS 46.6958299 -36.7513235
OS 46.69860358 -36.75687086
OS 46.69999042 -36.7651919
OS 46.70415094 -36.77489978
OS 46.70692462 -36.7859945
OS 46.7096983 -36.79847606
OS 46.71385882 -36.8137313
OS 46.71801934 -36.82898654
OS 46.72079302 -36.84701546
OS 46.72772722 -36.88584698
OS 46.73188774 -36.92883902
OS 46.73327458 -36.97599158
OS 46.73327458 -36.97737842
OS 46.73327458 -36.9801521
OS 46.73327458 -36.9870863
OS 46.73327458 -36.9940205
OS 46.73188774 -37.00372838
OS 46.73188774 -37.0148231
OS 46.7305009 -37.04117306
OS 46.72634038 -37.07168354
OS 46.72217986 -37.10358086
OS 46.71524566 -37.13686502
OS 46.70692462 -37.17014918
OS 46.70692462 -37.17153602
OS 46.70553778 -37.1743097
OS 46.70415094 -37.17847022
OS 46.7027641 -37.18401758
OS 46.69721674 -37.19927282
OS 46.6888957 -37.21868858
OS 46.68057466 -37.24087802
OS 46.66947994 -37.26306746
OS 46.65561154 -37.28664374
OS 46.64174314 -37.30883318
OS 46.6403563 -37.31160686
OS 46.63480894 -37.31854106
OS 46.6264879 -37.32824894
OS 46.61539318 -37.3407305
OS 46.60291162 -37.3545989
OS 46.58765638 -37.3684673
OS 46.57240114 -37.38372254
OS 46.55437222 -37.3962041
OS 46.55159854 -37.39759094
OS 46.54605118 -37.40175146
OS 46.5363433 -37.40729882
OS 46.5224749 -37.41423302
OS 46.50583282 -37.42255406
OS 46.48641706 -37.42948826
OS 46.46422762 -37.4378093
OS 46.4392645 -37.4447435
OS 46.43649082 -37.4447435
OS 46.4323303 -37.44613034
OS 46.42816978 -37.44751718
OS 46.41430138 -37.44890402
OS 46.39488562 -37.4516777
OS 46.37269618 -37.45445138
OS 46.34634622 -37.45722506
OS 46.31722258 -37.4586119
OS 46.28532526 -37.45999874
OS 45.9400021 -37.45999874
OS 45.9400021 -36.50030546
OS 46.30890154 -36.50030546
OS 46.33386466 -36.5016923
OE
OB 46.28948578 -36.61402634 H
OS 46.06759138 -36.61402634
OS 46.06759138 -37.34627786
OS 46.29503314 -37.34627786
OS 46.30474102 -37.34489102
OS 46.32554362 -37.34350418
OS 46.3491199 -37.34211734
OS 46.37408302 -37.33934366
OS 46.39904614 -37.33518314
OS 46.41984874 -37.32963578
OS 46.42262242 -37.32824894
OS 46.42955662 -37.3268621
OS 46.4392645 -37.32270158
OS 46.45174606 -37.31715422
OS 46.46561446 -37.30883318
OS 46.47948286 -37.30051214
OS 46.49335126 -37.29080426
OS 46.50721966 -37.27970954
OS 46.5086065 -37.27693586
OS 46.51415386 -37.2713885
OS 46.5224749 -37.26168062
OS 46.53218278 -37.24781222
OS 46.5432775 -37.2297833
OS 46.55575906 -37.2089807
OS 46.56685378 -37.18540442
OS 46.57656166 -37.15905446
OS 46.57656166 -37.15766762
OS 46.5779485 -37.15489394
OS 46.57933534 -37.15073342
OS 46.58072218 -37.14518606
OS 46.58210902 -37.13825186
OS 46.5848827 -37.12854398
OS 46.58765638 -37.1188361
OS 46.59043006 -37.10774138
OS 46.59459058 -37.08000458
OS 46.5987511 -37.04810726
OS 46.60152478 -37.01204942
OS 46.60291162 -36.9732179
OS 46.60291162 -36.97183106
OS 46.60291162 -36.9662837
OS 46.60291162 -36.9593495
OS 46.60152478 -36.94825478
OS 46.60152478 -36.93577322
OS 46.60013794 -36.92190482
OS 46.5987511 -36.90526274
OS 46.59736426 -36.88862066
OS 46.59043006 -36.85117598
OS 46.58210902 -36.81234446
OS 46.56962746 -36.77628662
OS 46.56130642 -36.7582577
OS 46.55298538 -36.74300246
OS 46.55298538 -36.74161562
OS 46.5502117 -36.73884194
OS 46.54743802 -36.73468142
OS 46.54466434 -36.72913406
OS 46.53356962 -36.71526566
OS 46.51970122 -36.69862358
OS 46.5016723 -36.68059466
OS 46.4808697 -36.66256574
OS 46.45729342 -36.6473105
OS 46.4323303 -36.63482894
OS 46.42955662 -36.6334421
OS 46.42262242 -36.63205526
OS 46.41014086 -36.62789474
OS 46.39211194 -36.62373422
OS 46.3699225 -36.62096054
OS 46.3421857 -36.61680002
OS 46.32554362 -36.61541318
OS 46.3075147 -36.61541318
OS 46.28948578 -36.61402634
OE
OB 47.23531066 -36.60015794 H
OS 47.23531066 -36.60154478
OS 47.23392382 -36.60431846
OS 47.23392382 -36.60986582
OS 47.23115014 -36.61541318
OS 47.2297633 -36.62512106
OS 47.22698962 -36.63482894
OS 47.22144226 -36.65840522
OS 47.21450806 -36.68614202
OS 47.20480018 -36.7166525
OS 47.1950923 -36.74993666
OS 47.18261074 -36.78460766
OS 47.07859774 -37.06474934
OS 47.4031183 -37.06474934
OS 47.30326582 -36.80124974
OS 47.30326582 -36.7998629
OS 47.30187898 -36.79570238
OS 47.2991053 -36.78876818
OS 47.29633162 -36.78044714
OS 47.2921711 -36.77073926
OS 47.28801058 -36.7582577
OS 47.28385006 -36.7443893
OS 47.2783027 -36.7305209
OS 47.26720798 -36.69862358
OS 47.25611326 -36.66533942
OS 47.24501854 -36.63205526
OS 47.23531066 -36.60015794
OE
SE
S P 0
OB 53.57408132 -38.30725892 I
OS 53.5861006 -38.30910804
OS 53.60089356 -38.31188172
OS 53.61753564 -38.31650452
OS 53.63417772 -38.32205188
OS 53.6508198 -38.32944836
OS 53.65174436 -38.32944836
OS 53.65266892 -38.33037292
OS 53.65821628 -38.3331466
OS 53.66653732 -38.33869396
OS 53.67578292 -38.34516588
OS 53.68687764 -38.35441148
OS 53.69797236 -38.36458164
OS 53.70906708 -38.37660092
OS 53.71831268 -38.39046932
OS 53.71923724 -38.39231844
OS 53.72201092 -38.39694124
OS 53.72570916 -38.40526228
OS 53.73033196 -38.41543244
OS 53.73495476 -38.42745172
OS 53.738653 -38.44132012
OS 53.74142668 -38.45703764
OS 53.74235124 -38.47275516
OS 53.74235124 -38.47460428
OS 53.74235124 -38.48015164
OS 53.74142668 -38.48754812
OS 53.73957756 -38.49771828
OS 53.73680388 -38.50973756
OS 53.73218108 -38.5226814
OS 53.72663372 -38.53562524
OS 53.71923724 -38.54856908
OS 53.71831268 -38.5504182
OS 53.715539 -38.55411644
OS 53.70999164 -38.56058836
OS 53.70259516 -38.56798484
OS 53.69334956 -38.57630588
OS 53.68225484 -38.58555148
OS 53.669311 -38.59387252
OS 53.65359348 -38.60219356
OS 53.65451804 -38.60219356
OS 53.65636716 -38.60311812
OS 53.65914084 -38.60404268
OS 53.66283908 -38.60496724
OS 53.67300924 -38.60866548
OS 53.68595308 -38.61421284
OS 53.70074604 -38.62160932
OS 53.715539 -38.63085492
OS 53.7294074 -38.6428742
OS 53.74235124 -38.6567426
OS 53.7432758 -38.65859172
OS 53.74697404 -38.66413908
OS 53.7525214 -38.67338468
OS 53.75806876 -38.68540396
OS 53.76361612 -38.70019692
OS 53.76916348 -38.71776356
OS 53.77286172 -38.73810388
OS 53.77378628 -38.76029332
OS 53.77378628 -38.76121788
OS 53.77378628 -38.76399156
OS 53.77378628 -38.76861436
OS 53.77286172 -38.77416172
OS 53.77193716 -38.7815582
OS 53.77008804 -38.78987924
OS 53.76823892 -38.79912484
OS 53.7663898 -38.809295
OS 53.75899332 -38.83148444
OS 53.75344596 -38.84350372
OS 53.7478986 -38.85459844
OS 53.74050212 -38.86661772
OS 53.73218108 -38.878637
OS 53.72293548 -38.89065628
OS 53.71184076 -38.901751
OS 53.7109162 -38.90267556
OS 53.70906708 -38.90452468
OS 53.70536884 -38.90729836
OS 53.70074604 -38.9109966
OS 53.69519868 -38.9156194
OS 53.6878022 -38.9202422
OS 53.67948116 -38.92578956
OS 53.669311 -38.93041236
OS 53.65914084 -38.93595972
OS 53.64712156 -38.94150708
OS 53.63510228 -38.94612988
OS 53.62123388 -38.95075268
OS 53.60644092 -38.95445092
OS 53.5907234 -38.9572246
OS 53.57500588 -38.95907372
OS 53.55743924 -38.95999828
OS 53.5491182 -38.95999828
OS 53.54357084 -38.95907372
OS 53.53617436 -38.95814916
OS 53.52785332 -38.9572246
OS 53.51860772 -38.95537548
OS 53.50843756 -38.95352636
OS 53.48624812 -38.947979
OS 53.46313412 -38.9387334
OS 53.45111484 -38.93318604
OS 53.44002012 -38.92671412
OS 53.4289254 -38.91839308
OS 53.41783068 -38.91007204
OS 53.41690612 -38.90914748
OS 53.415057 -38.90729836
OS 53.41228332 -38.90452468
OS 53.40950964 -38.90082644
OS 53.40488684 -38.89620364
OS 53.40026404 -38.88973172
OS 53.39471668 -38.8832598
OS 53.38916932 -38.87493876
OS 53.38362196 -38.86569316
OS 53.3780746 -38.85644756
OS 53.36790444 -38.83425812
OS 53.3595834 -38.80837044
OS 53.35680972 -38.79450204
OS 53.3549606 -38.77970908
OS 53.4335482 -38.76953892
OS 53.4335482 -38.77046348
OS 53.43447276 -38.7723126
OS 53.43539732 -38.77601084
OS 53.43632188 -38.78063364
OS 53.43724644 -38.786181
OS 53.43909556 -38.79265292
OS 53.44371836 -38.80652132
OS 53.45019028 -38.8231634
OS 53.45851132 -38.83888092
OS 53.46775692 -38.85367388
OS 53.47885164 -38.86661772
OS 53.48070076 -38.86754228
OS 53.484399 -38.87124052
OS 53.49179548 -38.87586332
OS 53.50104108 -38.88048612
OS 53.5121358 -38.88603348
OS 53.5260042 -38.89065628
OS 53.54172172 -38.89435452
OS 53.5583638 -38.89527908
OS 53.56391116 -38.89527908
OS 53.5676094 -38.89435452
OS 53.57777956 -38.89342996
OS 53.5907234 -38.89065628
OS 53.60551636 -38.88603348
OS 53.62123388 -38.87956156
OS 53.6369514 -38.87031596
OS 53.65174436 -38.85737212
OS 53.65359348 -38.855523
OS 53.65821628 -38.84997564
OS 53.66376364 -38.8416546
OS 53.67116012 -38.83055988
OS 53.6785566 -38.81669148
OS 53.68410396 -38.80097396
OS 53.68872676 -38.78248276
OS 53.69057588 -38.76214244
OS 53.69057588 -38.76121788
OS 53.69057588 -38.75936876
OS 53.69057588 -38.75659508
OS 53.68965132 -38.75289684
OS 53.68872676 -38.74272668
OS 53.68595308 -38.7307074
OS 53.68225484 -38.71591444
OS 53.67578292 -38.70112148
OS 53.66653732 -38.68632852
OS 53.65451804 -38.67246012
OS 53.65266892 -38.670611
OS 53.64804612 -38.66691276
OS 53.64064964 -38.6613654
OS 53.63047948 -38.65489348
OS 53.61753564 -38.64842156
OS 53.60181812 -38.6428742
OS 53.58425148 -38.63917596
OS 53.56483572 -38.63732684
OS 53.55651468 -38.63732684
OS 53.55004276 -38.6382514
OS 53.54172172 -38.63917596
OS 53.53247612 -38.64102508
OS 53.5213814 -38.6428742
OS 53.50936212 -38.64564788
OS 53.51860772 -38.57630588
OS 53.52323052 -38.57630588
OS 53.52692876 -38.57723044
OS 53.53894804 -38.57723044
OS 53.5491182 -38.57538132
OS 53.56113748 -38.5735322
OS 53.57500588 -38.57075852
OS 53.5907234 -38.56613572
OS 53.60551636 -38.5596638
OS 53.62123388 -38.55134276
OS 53.62215844 -38.55134276
OS 53.623083 -38.5504182
OS 53.6277058 -38.54671996
OS 53.63417772 -38.54024804
OS 53.6415742 -38.531927
OS 53.64897068 -38.51990772
OS 53.6554426 -38.50603932
OS 53.6600654 -38.4903218
OS 53.66191452 -38.4810762
OS 53.66191452 -38.47090604
OS 53.66191452 -38.46998148
OS 53.66191452 -38.46905692
OS 53.66191452 -38.46350956
OS 53.6600654 -38.45611308
OS 53.65821628 -38.44594292
OS 53.65451804 -38.4348482
OS 53.64989524 -38.42282892
OS 53.64249876 -38.41080964
OS 53.6323286 -38.39971492
OS 53.63140404 -38.39879036
OS 53.62678124 -38.39509212
OS 53.62030932 -38.39046932
OS 53.61198828 -38.38492196
OS 53.60089356 -38.38029916
OS 53.58794972 -38.37567636
OS 53.57315676 -38.37197812
OS 53.55651468 -38.37105356
OS 53.5491182 -38.37105356
OS 53.54079716 -38.37290268
OS 53.52970244 -38.3747518
OS 53.51768316 -38.37845004
OS 53.50566388 -38.38307284
OS 53.49272004 -38.39046932
OS 53.48070076 -38.39971492
OS 53.4797762 -38.40063948
OS 53.47607796 -38.40526228
OS 53.4705306 -38.4117342
OS 53.46405868 -38.4209798
OS 53.45758676 -38.43299908
OS 53.45111484 -38.44779204
OS 53.44556748 -38.46535868
OS 53.44186924 -38.485699
OS 53.36328164 -38.4718306
OS 53.36328164 -38.47090604
OS 53.3642062 -38.46813236
OS 53.36513076 -38.46443412
OS 53.36605532 -38.45888676
OS 53.36790444 -38.45241484
OS 53.37067812 -38.44501836
OS 53.37622548 -38.42745172
OS 53.38547108 -38.4071114
OS 53.3965658 -38.38677108
OS 53.4104342 -38.36735532
OS 53.42800084 -38.34978868
OS 53.4289254 -38.34886412
OS 53.43077452 -38.34793956
OS 53.4335482 -38.34609044
OS 53.43724644 -38.34331676
OS 53.44186924 -38.33961852
OS 53.44834116 -38.33592028
OS 53.45481308 -38.33222204
OS 53.46313412 -38.32759924
OS 53.48162532 -38.32020276
OS 53.5028902 -38.31280628
OS 53.52785332 -38.30818348
OS 53.54079716 -38.30633436
OS 53.56391116 -38.30633436
OS 53.57408132 -38.30725892
OE
OB 54.07889108 -38.30725892 I
OS 54.09091036 -38.30910804
OS 54.10477876 -38.31188172
OS 54.11957172 -38.31557996
OS 54.13528924 -38.32020276
OS 54.1500822 -38.32759924
OS 54.15100676 -38.32759924
OS 54.15193132 -38.3285238
OS 54.15655412 -38.33129748
OS 54.1639506 -38.33592028
OS 54.1731962 -38.3423922
OS 54.18336636 -38.3516378
OS 54.19446108 -38.36180796
OS 54.20463124 -38.37382724
OS 54.2148014 -38.38769564
OS 54.21572596 -38.38954476
OS 54.2194242 -38.39416756
OS 54.22312244 -38.4024886
OS 54.22959436 -38.41450788
OS 54.23514172 -38.42837628
OS 54.2425382 -38.4440938
OS 54.24901012 -38.462585
OS 54.25455748 -38.48292532
OS 54.25455748 -38.48384988
OS 54.25548204 -38.485699
OS 54.2564066 -38.48847268
OS 54.25733116 -38.49309548
OS 54.25825572 -38.49864284
OS 54.25918028 -38.50511476
OS 54.2610294 -38.5134358
OS 54.26195396 -38.5226814
OS 54.26380308 -38.53285156
OS 54.26472764 -38.54394628
OS 54.2656522 -38.55689012
OS 54.26750132 -38.56983396
OS 54.26842588 -38.58462692
OS 54.26842588 -38.59941988
OS 54.26935044 -38.61606196
OS 54.26935044 -38.6336286
OS 54.26935044 -38.63455316
OS 54.26935044 -38.6382514
OS 54.26935044 -38.64472332
OS 54.26935044 -38.6521198
OS 54.26842588 -38.66228996
OS 54.26842588 -38.67338468
OS 54.26750132 -38.68540396
OS 54.26657676 -38.6983478
OS 54.26380308 -38.72793372
OS 54.25918028 -38.7584442
OS 54.25363292 -38.78803012
OS 54.24993468 -38.80189852
OS 54.24531188 -38.81576692
OS 54.24531188 -38.81669148
OS 54.24438732 -38.8185406
OS 54.2425382 -38.82223884
OS 54.24068908 -38.82686164
OS 54.23883996 -38.83333356
OS 54.23514172 -38.83980548
OS 54.22774524 -38.855523
OS 54.21849964 -38.87216508
OS 54.20648036 -38.89065628
OS 54.19261196 -38.90729836
OS 54.17596988 -38.92301588
OS 54.17504532 -38.92301588
OS 54.17412076 -38.924865
OS 54.17134708 -38.92671412
OS 54.16764884 -38.92856324
OS 54.16302604 -38.93133692
OS 54.15840324 -38.93503516
OS 54.14453484 -38.94150708
OS 54.12789276 -38.947979
OS 54.108477 -38.95445092
OS 54.085363 -38.95814916
OS 54.06039988 -38.95999828
OS 54.05115428 -38.95999828
OS 54.04468236 -38.95907372
OS 54.03728588 -38.95814916
OS 54.02804028 -38.95630004
OS 54.01787012 -38.95445092
OS 54.0067754 -38.95167724
OS 53.99568068 -38.947979
OS 53.9836614 -38.94428076
OS 53.97164212 -38.9387334
OS 53.95962284 -38.93226148
OS 53.94760356 -38.924865
OS 53.93558428 -38.9156194
OS 53.92448956 -38.90544924
OS 53.9143194 -38.89435452
OS 53.91339484 -38.89342996
OS 53.91154572 -38.89065628
OS 53.90877204 -38.88603348
OS 53.90414924 -38.878637
OS 53.89952644 -38.87031596
OS 53.89490364 -38.85922124
OS 53.88843172 -38.8462774
OS 53.88288436 -38.83148444
OS 53.877337 -38.81484236
OS 53.87178964 -38.7954266
OS 53.86624228 -38.77416172
OS 53.86161948 -38.75012316
OS 53.85699668 -38.72423548
OS 53.854223 -38.69649868
OS 53.85237388 -38.6659882
OS 53.85144932 -38.6336286
OS 53.85144932 -38.63270404
OS 53.85144932 -38.6290058
OS 53.85144932 -38.62253388
OS 53.85144932 -38.6151374
OS 53.85237388 -38.60496724
OS 53.85237388 -38.59387252
OS 53.85329844 -38.58185324
OS 53.854223 -38.56798484
OS 53.85699668 -38.53932348
OS 53.86161948 -38.508813
OS 53.86716684 -38.47830252
OS 53.87086508 -38.46443412
OS 53.87456332 -38.45056572
OS 53.87456332 -38.44964116
OS 53.87548788 -38.44779204
OS 53.877337 -38.4440938
OS 53.87918612 -38.439471
OS 53.88103524 -38.43299908
OS 53.88473348 -38.42652716
OS 53.89212996 -38.41080964
OS 53.90137556 -38.39416756
OS 53.91339484 -38.37660092
OS 53.92726324 -38.35903428
OS 53.94390532 -38.34424132
OS 53.94482988 -38.34424132
OS 53.94575444 -38.3423922
OS 53.94852812 -38.34054308
OS 53.95222636 -38.33869396
OS 53.95684916 -38.33499572
OS 53.96239652 -38.33222204
OS 53.97626492 -38.32482556
OS 53.992907 -38.31835364
OS 54.01232276 -38.31188172
OS 54.03543676 -38.30818348
OS 54.06039988 -38.30633436
OS 54.06872092 -38.30633436
OS 54.07889108 -38.30725892
OE
OB 53.23846604 -38.94890356 I
OS 53.14878372 -38.94890356
OS 53.14878372 -38.85922124
OS 53.23846604 -38.85922124
OS 53.23846604 -38.94890356
OE
OB 53.00177868 -38.39231844 I
OS 52.74567556 -38.39231844
OS 52.71146684 -38.56521116
OS 52.7123914 -38.5642866
OS 52.71424052 -38.56336204
OS 52.7170142 -38.56151292
OS 52.721637 -38.55873924
OS 52.72718436 -38.55596556
OS 52.73365628 -38.55226732
OS 52.74844924 -38.54487084
OS 52.76694044 -38.53747436
OS 52.78728076 -38.53100244
OS 52.8094702 -38.52637964
OS 52.82056492 -38.52453052
OS 52.84090524 -38.52453052
OS 52.8464526 -38.52545508
OS 52.85384908 -38.52637964
OS 52.86217012 -38.5273042
OS 52.87141572 -38.52915332
OS 52.88158588 -38.531927
OS 52.90377532 -38.53839892
OS 52.9157946 -38.54302172
OS 52.92781388 -38.54949364
OS 52.93983316 -38.55596556
OS 52.95185244 -38.56336204
OS 52.96294716 -38.57260764
OS 52.97404188 -38.5827778
OS 52.97496644 -38.58370236
OS 52.97681556 -38.58555148
OS 52.97958924 -38.58832516
OS 52.98328748 -38.59294796
OS 52.98791028 -38.59941988
OS 52.99253308 -38.6058918
OS 52.99808044 -38.61421284
OS 53.0036278 -38.62345844
OS 53.0082506 -38.6336286
OS 53.01379796 -38.64472332
OS 53.01842076 -38.65766716
OS 53.02304356 -38.670611
OS 53.0267418 -38.6844794
OS 53.02951548 -38.70019692
OS 53.0313646 -38.71591444
OS 53.03228916 -38.73255652
OS 53.03228916 -38.73348108
OS 53.03228916 -38.73625476
OS 53.03228916 -38.74087756
OS 53.0313646 -38.74734948
OS 53.03044004 -38.75474596
OS 53.02951548 -38.763067
OS 53.02766636 -38.77323716
OS 53.02581724 -38.78340732
OS 53.02026988 -38.80744588
OS 53.01102428 -38.832409
OS 53.00547692 -38.84535284
OS 52.99808044 -38.85737212
OS 52.99068396 -38.87031596
OS 52.98143836 -38.88233524
OS 52.9805138 -38.8832598
OS 52.97866468 -38.88603348
OS 52.97496644 -38.88973172
OS 52.97034364 -38.89435452
OS 52.96387172 -38.89990188
OS 52.95647524 -38.90729836
OS 52.94722964 -38.91377028
OS 52.93705948 -38.92116676
OS 52.92596476 -38.92856324
OS 52.91302092 -38.93503516
OS 52.89915252 -38.94150708
OS 52.88435956 -38.947979
OS 52.86864204 -38.9526018
OS 52.8510754 -38.95630004
OS 52.8325842 -38.95907372
OS 52.81316844 -38.95999828
OS 52.8048474 -38.95999828
OS 52.79837548 -38.95907372
OS 52.790979 -38.95814916
OS 52.78265796 -38.9572246
OS 52.7724878 -38.95630004
OS 52.76231764 -38.95352636
OS 52.73920364 -38.947979
OS 52.71608964 -38.93965796
OS 52.70407036 -38.9341106
OS 52.69205108 -38.92763868
OS 52.68095636 -38.9202422
OS 52.66986164 -38.91192116
OS 52.66893708 -38.9109966
OS 52.66708796 -38.91007204
OS 52.66523884 -38.9063738
OS 52.6615406 -38.90267556
OS 52.6569178 -38.89805276
OS 52.652295 -38.8925054
OS 52.64674764 -38.88510892
OS 52.64212484 -38.87678788
OS 52.63657748 -38.86846684
OS 52.63103012 -38.85829668
OS 52.62085996 -38.83610724
OS 52.61253892 -38.81021956
OS 52.60976524 -38.79635116
OS 52.60791612 -38.7815582
OS 52.69020196 -38.77508628
OS 52.69020196 -38.77601084
OS 52.69020196 -38.77785996
OS 52.69112652 -38.78063364
OS 52.69205108 -38.78525644
OS 52.69482476 -38.7954266
OS 52.698523 -38.809295
OS 52.70407036 -38.8231634
OS 52.71146684 -38.83888092
OS 52.72071244 -38.85274932
OS 52.73180716 -38.86569316
OS 52.73365628 -38.86661772
OS 52.73735452 -38.87031596
OS 52.744751 -38.87493876
OS 52.75492116 -38.88048612
OS 52.76601588 -38.88603348
OS 52.77988428 -38.89065628
OS 52.7956018 -38.89435452
OS 52.81316844 -38.89527908
OS 52.8187158 -38.89527908
OS 52.82241404 -38.89435452
OS 52.83350876 -38.89342996
OS 52.8464526 -38.88973172
OS 52.86217012 -38.88510892
OS 52.87788764 -38.87771244
OS 52.89452972 -38.86661772
OS 52.9019262 -38.8601458
OS 52.90932268 -38.85274932
OS 52.91024724 -38.85182476
OS 52.9111718 -38.8509002
OS 52.91302092 -38.84812652
OS 52.9157946 -38.84535284
OS 52.92226652 -38.83518268
OS 52.929663 -38.82223884
OS 52.93613492 -38.80652132
OS 52.94260684 -38.78710556
OS 52.94722964 -38.76399156
OS 52.94907876 -38.75197228
OS 52.94907876 -38.73902844
OS 52.94907876 -38.73810388
OS 52.94907876 -38.73625476
OS 52.94907876 -38.73255652
OS 52.9481542 -38.72793372
OS 52.9481542 -38.72238636
OS 52.94722964 -38.71591444
OS 52.94445596 -38.70112148
OS 52.93983316 -38.68355484
OS 52.93336124 -38.6659882
OS 52.92411564 -38.64934612
OS 52.9111718 -38.6336286
OS 52.9111718 -38.63270404
OS 52.90932268 -38.63177948
OS 52.90469988 -38.62715668
OS 52.89637884 -38.62068476
OS 52.88528412 -38.61328828
OS 52.87049116 -38.60681636
OS 52.85384908 -38.60034444
OS 52.83443332 -38.59572164
OS 52.8233386 -38.59387252
OS 52.80577196 -38.59387252
OS 52.79837548 -38.59479708
OS 52.78912988 -38.59572164
OS 52.77803516 -38.59849532
OS 52.76694044 -38.601269
OS 52.75492116 -38.6058918
OS 52.74290188 -38.61143916
OS 52.74197732 -38.61236372
OS 52.73827908 -38.61421284
OS 52.73273172 -38.61883564
OS 52.72533524 -38.62345844
OS 52.71793876 -38.62993036
OS 52.71054228 -38.6382514
OS 52.70222124 -38.64657244
OS 52.69574932 -38.6567426
OS 52.62178452 -38.64657244
OS 52.68373004 -38.31742908
OS 53.00177868 -38.31742908
OS 53.00177868 -38.39231844
OE
OB 53.23846604 -38.57445676 I
OS 53.14878372 -38.57445676
OS 53.14878372 -38.48477444
OS 53.23846604 -38.48477444
OS 53.23846604 -38.57445676
OE
OB 54.48199924 -38.57445676 I
OS 54.39231692 -38.57445676
OS 54.39231692 -38.48477444
OS 54.48199924 -38.48477444
OS 54.48199924 -38.57445676
OE
OB 56.14990548 -38.3100326 I
OS 56.165623 -38.31095716
OS 56.18226508 -38.31188172
OS 56.1979826 -38.31373084
OS 56.211851 -38.31557996
OS 56.21370012 -38.31557996
OS 56.22017204 -38.31742908
OS 56.22849308 -38.3192782
OS 56.2395878 -38.32205188
OS 56.25160708 -38.32667468
OS 56.26455092 -38.33222204
OS 56.27841932 -38.33869396
OS 56.2904386 -38.34609044
OS 56.29228772 -38.347015
OS 56.29598596 -38.34978868
OS 56.30153332 -38.35533604
OS 56.3089298 -38.36180796
OS 56.31725084 -38.370129
OS 56.32557188 -38.38122372
OS 56.33481748 -38.393243
OS 56.34221396 -38.4071114
OS 56.34313852 -38.40896052
OS 56.34498764 -38.41358332
OS 56.34868588 -38.42190436
OS 56.35238412 -38.43299908
OS 56.3551578 -38.44594292
OS 56.35885604 -38.46073588
OS 56.36070516 -38.47737796
OS 56.36162972 -38.4949446
OS 56.36162972 -38.49586916
OS 56.36162972 -38.49864284
OS 56.36162972 -38.50234108
OS 56.36070516 -38.508813
OS 56.3597806 -38.51528492
OS 56.35885604 -38.52360596
OS 56.35700692 -38.53285156
OS 56.3551578 -38.54302172
OS 56.34868588 -38.5642866
OS 56.34498764 -38.57538132
OS 56.33944028 -38.5874006
OS 56.33296836 -38.59941988
OS 56.32649644 -38.6105146
OS 56.3181754 -38.62160932
OS 56.3089298 -38.63270404
OS 56.30800524 -38.6336286
OS 56.30615612 -38.63547772
OS 56.30338244 -38.6382514
OS 56.29875964 -38.64102508
OS 56.29321228 -38.64564788
OS 56.2858158 -38.65027068
OS 56.2765702 -38.65581804
OS 56.26640004 -38.66044084
OS 56.25438076 -38.6659882
OS 56.24051236 -38.67153556
OS 56.2257194 -38.67615836
OS 56.20815276 -38.6798566
OS 56.18966156 -38.68355484
OS 56.16932124 -38.68632852
OS 56.14620724 -38.68817764
OS 56.12216868 -38.6891022
OS 55.95852156 -38.6891022
OS 55.95852156 -38.94890356
OS 55.87346204 -38.94890356
OS 55.87346204 -38.30910804
OS 56.13603708 -38.30910804
OS 56.14990548 -38.3100326
OE
OB 57.07723916 -38.94890356 I
OS 56.99587788 -38.94890356
OS 56.99587788 -38.41358332
OS 56.80911676 -38.94890356
OS 56.73330284 -38.94890356
OS 56.54839084 -38.40433772
OS 56.54839084 -38.94890356
OS 56.46702956 -38.94890356
OS 56.46702956 -38.30910804
OS 56.59369428 -38.30910804
OS 56.74532212 -38.763067
OS 56.74532212 -38.76399156
OS 56.74624668 -38.76584068
OS 56.74717124 -38.76861436
OS 56.74902036 -38.77323716
OS 56.7527186 -38.78433188
OS 56.7573414 -38.79820028
OS 56.7619642 -38.8139178
OS 56.76751156 -38.82963532
OS 56.77213436 -38.84442828
OS 56.7758326 -38.85737212
OS 56.77675716 -38.855523
OS 56.77768172 -38.8509002
OS 56.7804554 -38.84257916
OS 56.78415364 -38.83148444
OS 56.78877644 -38.81669148
OS 56.79524836 -38.79912484
OS 56.80172028 -38.77878452
OS 56.81004132 -38.75474596
OS 56.96351828 -38.30910804
OS 57.07723916 -38.30910804
OS 57.07723916 -38.94890356
OE
OB 55.3150278 -38.30725892 I
OS 55.32704708 -38.30910804
OS 55.34184004 -38.31188172
OS 55.35848212 -38.31650452
OS 55.3751242 -38.32205188
OS 55.39176628 -38.32944836
OS 55.39269084 -38.32944836
OS 55.3936154 -38.33037292
OS 55.39916276 -38.3331466
OS 55.4074838 -38.33869396
OS 55.4167294 -38.34516588
OS 55.42782412 -38.35441148
OS 55.43891884 -38.36458164
OS 55.45001356 -38.37660092
OS 55.45925916 -38.39046932
OS 55.46018372 -38.39231844
OS 55.4629574 -38.39694124
OS 55.46665564 -38.40526228
OS 55.47127844 -38.41543244
OS 55.47590124 -38.42745172
OS 55.47959948 -38.44132012
OS 55.48237316 -38.45703764
OS 55.48329772 -38.47275516
OS 55.48329772 -38.47460428
OS 55.48329772 -38.48015164
OS 55.48237316 -38.48754812
OS 55.48052404 -38.49771828
OS 55.47775036 -38.50973756
OS 55.47312756 -38.5226814
OS 55.4675802 -38.53562524
OS 55.46018372 -38.54856908
OS 55.45925916 -38.5504182
OS 55.45648548 -38.55411644
OS 55.45093812 -38.56058836
OS 55.44354164 -38.56798484
OS 55.43429604 -38.57630588
OS 55.42320132 -38.58555148
OS 55.41025748 -38.59387252
OS 55.39453996 -38.60219356
OS 55.39546452 -38.60219356
OS 55.39731364 -38.60311812
OS 55.40008732 -38.60404268
OS 55.40378556 -38.60496724
OS 55.41395572 -38.60866548
OS 55.42689956 -38.61421284
OS 55.44169252 -38.62160932
OS 55.45648548 -38.63085492
OS 55.47035388 -38.6428742
OS 55.48329772 -38.6567426
OS 55.48422228 -38.65859172
OS 55.48792052 -38.66413908
OS 55.49346788 -38.67338468
OS 55.49901524 -38.68540396
OS 55.5045626 -38.70019692
OS 55.51010996 -38.71776356
OS 55.5138082 -38.73810388
OS 55.51473276 -38.76029332
OS 55.51473276 -38.76121788
OS 55.51473276 -38.76399156
OS 55.51473276 -38.76861436
OS 55.5138082 -38.77416172
OS 55.51288364 -38.7815582
OS 55.51103452 -38.78987924
OS 55.5091854 -38.79912484
OS 55.50733628 -38.809295
OS 55.4999398 -38.83148444
OS 55.49439244 -38.84350372
OS 55.48884508 -38.85459844
OS 55.4814486 -38.86661772
OS 55.47312756 -38.878637
OS 55.46388196 -38.89065628
OS 55.45278724 -38.901751
OS 55.45186268 -38.90267556
OS 55.45001356 -38.90452468
OS 55.44631532 -38.90729836
OS 55.44169252 -38.9109966
OS 55.43614516 -38.9156194
OS 55.42874868 -38.9202422
OS 55.42042764 -38.92578956
OS 55.41025748 -38.93041236
OS 55.40008732 -38.93595972
OS 55.38806804 -38.94150708
OS 55.37604876 -38.94612988
OS 55.36218036 -38.95075268
OS 55.3473874 -38.95445092
OS 55.33166988 -38.9572246
OS 55.31595236 -38.95907372
OS 55.29838572 -38.95999828
OS 55.29006468 -38.95999828
OS 55.28451732 -38.95907372
OS 55.27712084 -38.95814916
OS 55.2687998 -38.9572246
OS 55.2595542 -38.95537548
OS 55.24938404 -38.95352636
OS 55.2271946 -38.947979
OS 55.2040806 -38.9387334
OS 55.19206132 -38.93318604
OS 55.1809666 -38.92671412
OS 55.16987188 -38.91839308
OS 55.15877716 -38.91007204
OS 55.1578526 -38.90914748
OS 55.15600348 -38.90729836
OS 55.1532298 -38.90452468
OS 55.15045612 -38.90082644
OS 55.14583332 -38.89620364
OS 55.14121052 -38.88973172
OS 55.13566316 -38.8832598
OS 55.1301158 -38.87493876
OS 55.12456844 -38.86569316
OS 55.11902108 -38.85644756
OS 55.10885092 -38.83425812
OS 55.10052988 -38.80837044
OS 55.0977562 -38.79450204
OS 55.09590708 -38.77970908
OS 55.17449468 -38.76953892
OS 55.17449468 -38.77046348
OS 55.17541924 -38.7723126
OS 55.1763438 -38.77601084
OS 55.17726836 -38.78063364
OS 55.17819292 -38.786181
OS 55.18004204 -38.79265292
OS 55.18466484 -38.80652132
OS 55.19113676 -38.8231634
OS 55.1994578 -38.83888092
OS 55.2087034 -38.85367388
OS 55.21979812 -38.86661772
OS 55.22164724 -38.86754228
OS 55.22534548 -38.87124052
OS 55.23274196 -38.87586332
OS 55.24198756 -38.88048612
OS 55.25308228 -38.88603348
OS 55.26695068 -38.89065628
OS 55.2826682 -38.89435452
OS 55.29931028 -38.89527908
OS 55.30485764 -38.89527908
OS 55.30855588 -38.89435452
OS 55.31872604 -38.89342996
OS 55.33166988 -38.89065628
OS 55.34646284 -38.88603348
OS 55.36218036 -38.87956156
OS 55.37789788 -38.87031596
OS 55.39269084 -38.85737212
OS 55.39453996 -38.855523
OS 55.39916276 -38.84997564
OS 55.40471012 -38.8416546
OS 55.4121066 -38.83055988
OS 55.41950308 -38.81669148
OS 55.42505044 -38.80097396
OS 55.42967324 -38.78248276
OS 55.43152236 -38.76214244
OS 55.43152236 -38.76121788
OS 55.43152236 -38.75936876
OS 55.43152236 -38.75659508
OS 55.4305978 -38.75289684
OS 55.42967324 -38.74272668
OS 55.42689956 -38.7307074
OS 55.42320132 -38.71591444
OS 55.4167294 -38.70112148
OS 55.4074838 -38.68632852
OS 55.39546452 -38.67246012
OS 55.3936154 -38.670611
OS 55.3889926 -38.66691276
OS 55.38159612 -38.6613654
OS 55.37142596 -38.65489348
OS 55.35848212 -38.64842156
OS 55.3427646 -38.6428742
OS 55.32519796 -38.63917596
OS 55.3057822 -38.63732684
OS 55.29746116 -38.63732684
OS 55.29098924 -38.6382514
OS 55.2826682 -38.63917596
OS 55.2734226 -38.64102508
OS 55.26232788 -38.6428742
OS 55.2503086 -38.64564788
OS 55.2595542 -38.57630588
OS 55.264177 -38.57630588
OS 55.26787524 -38.57723044
OS 55.27989452 -38.57723044
OS 55.29006468 -38.57538132
OS 55.30208396 -38.5735322
OS 55.31595236 -38.57075852
OS 55.33166988 -38.56613572
OS 55.34646284 -38.5596638
OS 55.36218036 -38.55134276
OS 55.36310492 -38.55134276
OS 55.36402948 -38.5504182
OS 55.36865228 -38.54671996
OS 55.3751242 -38.54024804
OS 55.38252068 -38.531927
OS 55.38991716 -38.51990772
OS 55.39638908 -38.50603932
OS 55.40101188 -38.4903218
OS 55.402861 -38.4810762
OS 55.402861 -38.47090604
OS 55.402861 -38.46998148
OS 55.402861 -38.46905692
OS 55.402861 -38.46350956
OS 55.40101188 -38.45611308
OS 55.39916276 -38.44594292
OS 55.39546452 -38.4348482
OS 55.39084172 -38.42282892
OS 55.38344524 -38.41080964
OS 55.37327508 -38.39971492
OS 55.37235052 -38.39879036
OS 55.36772772 -38.39509212
OS 55.3612558 -38.39046932
OS 55.35293476 -38.38492196
OS 55.34184004 -38.38029916
OS 55.3288962 -38.37567636
OS 55.31410324 -38.37197812
OS 55.29746116 -38.37105356
OS 55.29006468 -38.37105356
OS 55.28174364 -38.37290268
OS 55.27064892 -38.3747518
OS 55.25862964 -38.37845004
OS 55.24661036 -38.38307284
OS 55.23366652 -38.39046932
OS 55.22164724 -38.39971492
OS 55.22072268 -38.40063948
OS 55.21702444 -38.40526228
OS 55.21147708 -38.4117342
OS 55.20500516 -38.4209798
OS 55.19853324 -38.43299908
OS 55.19206132 -38.44779204
OS 55.18651396 -38.46535868
OS 55.18281572 -38.485699
OS 55.10422812 -38.4718306
OS 55.10422812 -38.47090604
OS 55.10515268 -38.46813236
OS 55.10607724 -38.46443412
OS 55.1070018 -38.45888676
OS 55.10885092 -38.45241484
OS 55.1116246 -38.44501836
OS 55.11717196 -38.42745172
OS 55.12641756 -38.4071114
OS 55.13751228 -38.38677108
OS 55.15138068 -38.36735532
OS 55.16894732 -38.34978868
OS 55.16987188 -38.34886412
OS 55.171721 -38.34793956
OS 55.17449468 -38.34609044
OS 55.17819292 -38.34331676
OS 55.18281572 -38.33961852
OS 55.18928764 -38.33592028
OS 55.19575956 -38.33222204
OS 55.2040806 -38.32759924
OS 55.2225718 -38.32020276
OS 55.24383668 -38.31280628
OS 55.2687998 -38.30818348
OS 55.28174364 -38.30633436
OS 55.30485764 -38.30633436
OS 55.3150278 -38.30725892
OE
OB 54.48199924 -38.94890356 I
OS 54.39231692 -38.94890356
OS 54.39231692 -38.85922124
OS 54.48199924 -38.85922124
OS 54.48199924 -38.94890356
OE
OB 54.9914318 -38.39231844 I
OS 54.73532868 -38.39231844
OS 54.70111996 -38.56521116
OS 54.70204452 -38.5642866
OS 54.70389364 -38.56336204
OS 54.70666732 -38.56151292
OS 54.71129012 -38.55873924
OS 54.71683748 -38.55596556
OS 54.7233094 -38.55226732
OS 54.73810236 -38.54487084
OS 54.75659356 -38.53747436
OS 54.77693388 -38.53100244
OS 54.79912332 -38.52637964
OS 54.81021804 -38.52453052
OS 54.83055836 -38.52453052
OS 54.83610572 -38.52545508
OS 54.8435022 -38.52637964
OS 54.85182324 -38.5273042
OS 54.86106884 -38.52915332
OS 54.871239 -38.531927
OS 54.89342844 -38.53839892
OS 54.90544772 -38.54302172
OS 54.917467 -38.54949364
OS 54.92948628 -38.55596556
OS 54.94150556 -38.56336204
OS 54.95260028 -38.57260764
OS 54.963695 -38.5827778
OS 54.96461956 -38.58370236
OS 54.96646868 -38.58555148
OS 54.96924236 -38.58832516
OS 54.9729406 -38.59294796
OS 54.9775634 -38.59941988
OS 54.9821862 -38.6058918
OS 54.98773356 -38.61421284
OS 54.99328092 -38.62345844
OS 54.99790372 -38.6336286
OS 55.00345108 -38.64472332
OS 55.00807388 -38.65766716
OS 55.01269668 -38.670611
OS 55.01639492 -38.6844794
OS 55.0191686 -38.70019692
OS 55.02101772 -38.71591444
OS 55.02194228 -38.73255652
OS 55.02194228 -38.73348108
OS 55.02194228 -38.73625476
OS 55.02194228 -38.74087756
OS 55.02101772 -38.74734948
OS 55.02009316 -38.75474596
OS 55.0191686 -38.763067
OS 55.01731948 -38.77323716
OS 55.01547036 -38.78340732
OS 55.009923 -38.80744588
OS 55.0006774 -38.832409
OS 54.99513004 -38.84535284
OS 54.98773356 -38.85737212
OS 54.98033708 -38.87031596
OS 54.97109148 -38.88233524
OS 54.97016692 -38.8832598
OS 54.9683178 -38.88603348
OS 54.96461956 -38.88973172
OS 54.95999676 -38.89435452
OS 54.95352484 -38.89990188
OS 54.94612836 -38.90729836
OS 54.93688276 -38.91377028
OS 54.9267126 -38.92116676
OS 54.91561788 -38.92856324
OS 54.90267404 -38.93503516
OS 54.88880564 -38.94150708
OS 54.87401268 -38.947979
OS 54.85829516 -38.9526018
OS 54.84072852 -38.95630004
OS 54.82223732 -38.95907372
OS 54.80282156 -38.95999828
OS 54.79450052 -38.95999828
OS 54.7880286 -38.95907372
OS 54.78063212 -38.95814916
OS 54.77231108 -38.9572246
OS 54.76214092 -38.95630004
OS 54.75197076 -38.95352636
OS 54.72885676 -38.947979
OS 54.70574276 -38.93965796
OS 54.69372348 -38.9341106
OS 54.6817042 -38.92763868
OS 54.67060948 -38.9202422
OS 54.65951476 -38.91192116
OS 54.6585902 -38.9109966
OS 54.65674108 -38.91007204
OS 54.65489196 -38.9063738
OS 54.65119372 -38.90267556
OS 54.64657092 -38.89805276
OS 54.64194812 -38.8925054
OS 54.63640076 -38.88510892
OS 54.63177796 -38.87678788
OS 54.6262306 -38.86846684
OS 54.62068324 -38.85829668
OS 54.61051308 -38.83610724
OS 54.60219204 -38.81021956
OS 54.59941836 -38.79635116
OS 54.59756924 -38.7815582
OS 54.67985508 -38.77508628
OS 54.67985508 -38.77601084
OS 54.67985508 -38.77785996
OS 54.68077964 -38.78063364
OS 54.6817042 -38.78525644
OS 54.68447788 -38.7954266
OS 54.68817612 -38.809295
OS 54.69372348 -38.8231634
OS 54.70111996 -38.83888092
OS 54.71036556 -38.85274932
OS 54.72146028 -38.86569316
OS 54.7233094 -38.86661772
OS 54.72700764 -38.87031596
OS 54.73440412 -38.87493876
OS 54.74457428 -38.88048612
OS 54.755669 -38.88603348
OS 54.7695374 -38.89065628
OS 54.78525492 -38.89435452
OS 54.80282156 -38.89527908
OS 54.80836892 -38.89527908
OS 54.81206716 -38.89435452
OS 54.82316188 -38.89342996
OS 54.83610572 -38.88973172
OS 54.85182324 -38.88510892
OS 54.86754076 -38.87771244
OS 54.88418284 -38.86661772
OS 54.89157932 -38.8601458
OS 54.8989758 -38.85274932
OS 54.89990036 -38.85182476
OS 54.90082492 -38.8509002
OS 54.90267404 -38.84812652
OS 54.90544772 -38.84535284
OS 54.91191964 -38.83518268
OS 54.91931612 -38.82223884
OS 54.92578804 -38.80652132
OS 54.93225996 -38.78710556
OS 54.93688276 -38.76399156
OS 54.93873188 -38.75197228
OS 54.93873188 -38.73902844
OS 54.93873188 -38.73810388
OS 54.93873188 -38.73625476
OS 54.93873188 -38.73255652
OS 54.93780732 -38.72793372
OS 54.93780732 -38.72238636
OS 54.93688276 -38.71591444
OS 54.93410908 -38.70112148
OS 54.92948628 -38.68355484
OS 54.92301436 -38.6659882
OS 54.91376876 -38.64934612
OS 54.90082492 -38.6336286
OS 54.90082492 -38.63270404
OS 54.8989758 -38.63177948
OS 54.894353 -38.62715668
OS 54.88603196 -38.62068476
OS 54.87493724 -38.61328828
OS 54.86014428 -38.60681636
OS 54.8435022 -38.60034444
OS 54.82408644 -38.59572164
OS 54.81299172 -38.59387252
OS 54.79542508 -38.59387252
OS 54.7880286 -38.59479708
OS 54.778783 -38.59572164
OS 54.76768828 -38.59849532
OS 54.75659356 -38.601269
OS 54.74457428 -38.6058918
OS 54.732555 -38.61143916
OS 54.73163044 -38.61236372
OS 54.7279322 -38.61421284
OS 54.72238484 -38.61883564
OS 54.71498836 -38.62345844
OS 54.70759188 -38.62993036
OS 54.7001954 -38.6382514
OS 54.69187436 -38.64657244
OS 54.68540244 -38.6567426
OS 54.61143764 -38.64657244
OS 54.67338316 -38.31742908
OS 54.9914318 -38.31742908
OS 54.9914318 -38.39231844
OE
OB 49.95350436 -38.72331092 I
OS 50.040413 -38.72331092
OS 50.040413 -38.7954266
OS 49.95350436 -38.7954266
OS 49.95350436 -38.94890356
OS 49.87491676 -38.94890356
OS 49.87491676 -38.7954266
OS 49.5966242 -38.7954266
OS 49.5966242 -38.72331092
OS 49.88970972 -38.30910804
OS 49.95350436 -38.30910804
OS 49.95350436 -38.72331092
OE
OB 50.1467374 -38.95999828 I
OS 50.08386732 -38.95999828
OS 50.26970388 -38.29801332
OS 50.33257396 -38.29801332
OS 50.1467374 -38.95999828
OE
OB 49.35346492 -38.30725892 I
OS 49.3608614 -38.30818348
OS 49.370107 -38.30910804
OS 49.38027716 -38.31095716
OS 49.39044732 -38.31280628
OS 49.41448588 -38.3192782
OS 49.43852444 -38.3285238
OS 49.45054372 -38.33407116
OS 49.462563 -38.34054308
OS 49.47365772 -38.34886412
OS 49.48382788 -38.35810972
OS 49.48475244 -38.35903428
OS 49.48660156 -38.35995884
OS 49.48845068 -38.36365708
OS 49.49214892 -38.36735532
OS 49.49677172 -38.37197812
OS 49.50139452 -38.37845004
OS 49.50601732 -38.38492196
OS 49.51156468 -38.393243
OS 49.52081028 -38.41080964
OS 49.53005588 -38.43299908
OS 49.53375412 -38.4440938
OS 49.53560324 -38.45703764
OS 49.53745236 -38.46998148
OS 49.53837692 -38.48384988
OS 49.53837692 -38.485699
OS 49.53837692 -38.4903218
OS 49.53745236 -38.49771828
OS 49.5365278 -38.50788844
OS 49.53467868 -38.51898316
OS 49.53098044 -38.531927
OS 49.5272822 -38.5457954
OS 49.52173484 -38.5596638
OS 49.52081028 -38.56151292
OS 49.51896116 -38.56613572
OS 49.51526292 -38.5735322
OS 49.50971556 -38.58370236
OS 49.50231908 -38.59479708
OS 49.49307348 -38.60866548
OS 49.48197876 -38.62253388
OS 49.46903492 -38.6382514
OS 49.4671858 -38.64010052
OS 49.462563 -38.64564788
OS 49.4579402 -38.65027068
OS 49.4533174 -38.65489348
OS 49.44777004 -38.66044084
OS 49.44037356 -38.66783732
OS 49.43297708 -38.6752338
OS 49.42373148 -38.68355484
OS 49.41448588 -38.69280044
OS 49.40339116 -38.7029706
OS 49.39137188 -38.71314076
OS 49.37842804 -38.72516004
OS 49.36363508 -38.73717932
OS 49.34884212 -38.75012316
OS 49.34791756 -38.75104772
OS 49.34606844 -38.75289684
OS 49.3423702 -38.75567052
OS 49.3377474 -38.75936876
OS 49.33220004 -38.76491612
OS 49.32572812 -38.77046348
OS 49.31093516 -38.78248276
OS 49.29521764 -38.79635116
OS 49.28042468 -38.81021956
OS 49.26748084 -38.82223884
OS 49.26193348 -38.82686164
OS 49.25731068 -38.83148444
OS 49.25638612 -38.832409
OS 49.25361244 -38.83518268
OS 49.2499142 -38.83888092
OS 49.2452914 -38.84442828
OS 49.2406686 -38.8509002
OS 49.23512124 -38.85737212
OS 49.22402652 -38.87308964
OS 49.53930148 -38.87308964
OS 49.53930148 -38.94890356
OS 49.11492844 -38.94890356
OS 49.11492844 -38.947979
OS 49.11492844 -38.94428076
OS 49.11492844 -38.9387334
OS 49.115853 -38.93133692
OS 49.11677756 -38.92301588
OS 49.11862668 -38.91377028
OS 49.1204758 -38.90452468
OS 49.12417404 -38.89435452
OS 49.12417404 -38.89342996
OS 49.1250986 -38.8925054
OS 49.12694772 -38.88695804
OS 49.13064596 -38.878637
OS 49.13619332 -38.86754228
OS 49.1435898 -38.85459844
OS 49.1528354 -38.83980548
OS 49.16300556 -38.82501252
OS 49.1759494 -38.809295
OS 49.1759494 -38.80837044
OS 49.17779852 -38.80744588
OS 49.18242132 -38.80189852
OS 49.19074236 -38.79357748
OS 49.20276164 -38.7815582
OS 49.21663004 -38.7676898
OS 49.23419668 -38.75104772
OS 49.25546156 -38.73255652
OS 49.27857556 -38.71314076
OS 49.27950012 -38.7122162
OS 49.28319836 -38.70944252
OS 49.28874572 -38.70481972
OS 49.29521764 -38.69927236
OS 49.30353868 -38.69187588
OS 49.31370884 -38.68355484
OS 49.323879 -38.67430924
OS 49.33589828 -38.66413908
OS 49.35901228 -38.64194964
OS 49.38212628 -38.6197602
OS 49.393221 -38.60866548
OS 49.40339116 -38.59757076
OS 49.41263676 -38.5874006
OS 49.42003324 -38.57723044
OS 49.42003324 -38.57630588
OS 49.42188236 -38.57538132
OS 49.42373148 -38.57260764
OS 49.4255806 -38.5689094
OS 49.43205252 -38.55873924
OS 49.439449 -38.54671996
OS 49.44592092 -38.531927
OS 49.45239284 -38.51620948
OS 49.45609108 -38.49864284
OS 49.4579402 -38.48200076
OS 49.4579402 -38.4810762
OS 49.4579402 -38.48015164
OS 49.45701564 -38.47460428
OS 49.45609108 -38.46535868
OS 49.4533174 -38.45518852
OS 49.44961916 -38.44224468
OS 49.44314724 -38.42930084
OS 49.4348262 -38.416357
OS 49.42373148 -38.40341316
OS 49.42188236 -38.40156404
OS 49.41725956 -38.3978658
OS 49.41078764 -38.393243
OS 49.40061748 -38.38677108
OS 49.38767364 -38.38122372
OS 49.37288068 -38.37567636
OS 49.35531404 -38.37197812
OS 49.33589828 -38.37105356
OS 49.33035092 -38.37105356
OS 49.32665268 -38.37197812
OS 49.31555796 -38.37290268
OS 49.30261412 -38.37567636
OS 49.28874572 -38.3793746
OS 49.2730282 -38.38584652
OS 49.25823524 -38.39416756
OS 49.24436684 -38.40526228
OS 49.24251772 -38.4071114
OS 49.23881948 -38.4117342
OS 49.23327212 -38.41913068
OS 49.22772476 -38.4302254
OS 49.22125284 -38.44316924
OS 49.21570548 -38.45981132
OS 49.21200724 -38.47830252
OS 49.21015812 -38.4995674
OS 49.1297214 -38.49124636
OS 49.1297214 -38.4903218
OS 49.13064596 -38.48754812
OS 49.13064596 -38.48292532
OS 49.13157052 -38.4764534
OS 49.13341964 -38.46905692
OS 49.13526876 -38.46073588
OS 49.13804244 -38.45056572
OS 49.14081612 -38.44039556
OS 49.1482126 -38.41820612
OS 49.15930732 -38.39601668
OS 49.16577924 -38.38492196
OS 49.17410028 -38.37382724
OS 49.18242132 -38.36365708
OS 49.19166692 -38.35441148
OS 49.19259148 -38.35348692
OS 49.1944406 -38.35256236
OS 49.19721428 -38.34978868
OS 49.20183708 -38.347015
OS 49.20738444 -38.34331676
OS 49.21385636 -38.33961852
OS 49.22125284 -38.33499572
OS 49.23049844 -38.33037292
OS 49.2406686 -38.32575012
OS 49.25176332 -38.32112732
OS 49.2637826 -38.31742908
OS 49.27672644 -38.31373084
OS 49.29059484 -38.31095716
OS 49.3053878 -38.30818348
OS 49.32110532 -38.30725892
OS 49.3377474 -38.30633436
OS 49.346993 -38.30633436
OS 49.35346492 -38.30725892
OE
OB 48.67576244 -38.94890356 I
OS 48.59717484 -38.94890356
OS 48.59717484 -38.4487166
OS 48.59625028 -38.44964116
OS 48.59162748 -38.4533394
OS 48.58608012 -38.45888676
OS 48.57683452 -38.46535868
OS 48.56666436 -38.47367972
OS 48.55372052 -38.48292532
OS 48.53892756 -38.49309548
OS 48.52228548 -38.50326564
OS 48.52136092 -38.50326564
OS 48.52043636 -38.5041902
OS 48.514889 -38.50788844
OS 48.5056434 -38.51251124
OS 48.49454868 -38.5180586
OS 48.48160484 -38.52453052
OS 48.46773644 -38.53100244
OS 48.45386804 -38.53747436
OS 48.43999964 -38.54302172
OS 48.43999964 -38.4672078
OS 48.4409242 -38.4672078
OS 48.44277332 -38.46535868
OS 48.44647156 -38.46443412
OS 48.45109436 -38.46166044
OS 48.45664172 -38.45888676
OS 48.46311364 -38.45518852
OS 48.47883116 -38.44594292
OS 48.49732236 -38.43577276
OS 48.51581356 -38.42282892
OS 48.53522932 -38.40803596
OS 48.55464508 -38.39231844
OS 48.55556964 -38.39139388
OS 48.5564942 -38.39046932
OS 48.55926788 -38.38769564
OS 48.56296612 -38.38492196
OS 48.57128716 -38.37567636
OS 48.58238188 -38.36458164
OS 48.5934766 -38.3516378
OS 48.60549588 -38.33684484
OS 48.61566604 -38.32205188
OS 48.62491164 -38.30633436
OS 48.67576244 -38.30633436
OS 48.67576244 -38.94890356
OE
OB 48.9032042 -38.95999828 I
OS 48.84033412 -38.95999828
OS 49.02617068 -38.29801332
OS 49.08904076 -38.29801332
OS 48.9032042 -38.95999828
OE
OB 50.59699812 -38.30725892 I
OS 50.6043946 -38.30818348
OS 50.6136402 -38.30910804
OS 50.62381036 -38.31095716
OS 50.63398052 -38.31280628
OS 50.65801908 -38.3192782
OS 50.68205764 -38.3285238
OS 50.69407692 -38.33407116
OS 50.7060962 -38.34054308
OS 50.71719092 -38.34886412
OS 50.72736108 -38.35810972
OS 50.72828564 -38.35903428
OS 50.73013476 -38.35995884
OS 50.73198388 -38.36365708
OS 50.73568212 -38.36735532
OS 50.74030492 -38.37197812
OS 50.74492772 -38.37845004
OS 50.74955052 -38.38492196
OS 50.75509788 -38.393243
OS 50.76434348 -38.41080964
OS 50.77358908 -38.43299908
OS 50.77728732 -38.4440938
OS 50.77913644 -38.45703764
OS 50.78098556 -38.46998148
OS 50.78191012 -38.48384988
OS 50.78191012 -38.485699
OS 50.78191012 -38.4903218
OS 50.78098556 -38.49771828
OS 50.780061 -38.50788844
OS 50.77821188 -38.51898316
OS 50.77451364 -38.531927
OS 50.7708154 -38.5457954
OS 50.76526804 -38.5596638
OS 50.76434348 -38.56151292
OS 50.76249436 -38.56613572
OS 50.75879612 -38.5735322
OS 50.75324876 -38.58370236
OS 50.74585228 -38.59479708
OS 50.73660668 -38.60866548
OS 50.72551196 -38.62253388
OS 50.71256812 -38.6382514
OS 50.710719 -38.64010052
OS 50.7060962 -38.64564788
OS 50.7014734 -38.65027068
OS 50.6968506 -38.65489348
OS 50.69130324 -38.66044084
OS 50.68390676 -38.66783732
OS 50.67651028 -38.6752338
OS 50.66726468 -38.68355484
OS 50.65801908 -38.69280044
OS 50.64692436 -38.7029706
OS 50.63490508 -38.71314076
OS 50.62196124 -38.72516004
OS 50.60716828 -38.73717932
OS 50.59237532 -38.75012316
OS 50.59145076 -38.75104772
OS 50.58960164 -38.75289684
OS 50.5859034 -38.75567052
OS 50.5812806 -38.75936876
OS 50.57573324 -38.76491612
OS 50.56926132 -38.77046348
OS 50.55446836 -38.78248276
OS 50.53875084 -38.79635116
OS 50.52395788 -38.81021956
OS 50.51101404 -38.82223884
OS 50.50546668 -38.82686164
OS 50.50084388 -38.83148444
OS 50.49991932 -38.832409
OS 50.49714564 -38.83518268
OS 50.4934474 -38.83888092
OS 50.4888246 -38.84442828
OS 50.4842018 -38.8509002
OS 50.47865444 -38.85737212
OS 50.46755972 -38.87308964
OS 50.78283468 -38.87308964
OS 50.78283468 -38.94890356
OS 50.35846164 -38.94890356
OS 50.35846164 -38.947979
OS 50.35846164 -38.94428076
OS 50.35846164 -38.9387334
OS 50.3593862 -38.93133692
OS 50.36031076 -38.92301588
OS 50.36215988 -38.91377028
OS 50.364009 -38.90452468
OS 50.36770724 -38.89435452
OS 50.36770724 -38.89342996
OS 50.3686318 -38.8925054
OS 50.37048092 -38.88695804
OS 50.37417916 -38.878637
OS 50.37972652 -38.86754228
OS 50.387123 -38.85459844
OS 50.3963686 -38.83980548
OS 50.40653876 -38.82501252
OS 50.4194826 -38.809295
OS 50.4194826 -38.80837044
OS 50.42133172 -38.80744588
OS 50.42595452 -38.80189852
OS 50.43427556 -38.79357748
OS 50.44629484 -38.7815582
OS 50.46016324 -38.7676898
OS 50.47772988 -38.75104772
OS 50.49899476 -38.73255652
OS 50.52210876 -38.71314076
OS 50.52303332 -38.7122162
OS 50.52673156 -38.70944252
OS 50.53227892 -38.70481972
OS 50.53875084 -38.69927236
OS 50.54707188 -38.69187588
OS 50.55724204 -38.68355484
OS 50.5674122 -38.67430924
OS 50.57943148 -38.66413908
OS 50.60254548 -38.64194964
OS 50.62565948 -38.6197602
OS 50.6367542 -38.60866548
OS 50.64692436 -38.59757076
OS 50.65616996 -38.5874006
OS 50.66356644 -38.57723044
OS 50.66356644 -38.57630588
OS 50.66541556 -38.57538132
OS 50.66726468 -38.57260764
OS 50.6691138 -38.5689094
OS 50.67558572 -38.55873924
OS 50.6829822 -38.54671996
OS 50.68945412 -38.531927
OS 50.69592604 -38.51620948
OS 50.69962428 -38.49864284
OS 50.7014734 -38.48200076
OS 50.7014734 -38.4810762
OS 50.7014734 -38.48015164
OS 50.70054884 -38.47460428
OS 50.69962428 -38.46535868
OS 50.6968506 -38.45518852
OS 50.69315236 -38.44224468
OS 50.68668044 -38.42930084
OS 50.6783594 -38.416357
OS 50.66726468 -38.40341316
OS 50.66541556 -38.40156404
OS 50.66079276 -38.3978658
OS 50.65432084 -38.393243
OS 50.64415068 -38.38677108
OS 50.63120684 -38.38122372
OS 50.61641388 -38.37567636
OS 50.59884724 -38.37197812
OS 50.57943148 -38.37105356
OS 50.57388412 -38.37105356
OS 50.57018588 -38.37197812
OS 50.55909116 -38.37290268
OS 50.54614732 -38.37567636
OS 50.53227892 -38.3793746
OS 50.5165614 -38.38584652
OS 50.50176844 -38.39416756
OS 50.48790004 -38.40526228
OS 50.48605092 -38.4071114
OS 50.48235268 -38.4117342
OS 50.47680532 -38.41913068
OS 50.47125796 -38.4302254
OS 50.46478604 -38.44316924
OS 50.45923868 -38.45981132
OS 50.45554044 -38.47830252
OS 50.45369132 -38.4995674
OS 50.3732546 -38.49124636
OS 50.3732546 -38.4903218
OS 50.37417916 -38.48754812
OS 50.37417916 -38.48292532
OS 50.37510372 -38.4764534
OS 50.37695284 -38.46905692
OS 50.37880196 -38.46073588
OS 50.38157564 -38.45056572
OS 50.38434932 -38.44039556
OS 50.3917458 -38.41820612
OS 50.40284052 -38.39601668
OS 50.40931244 -38.38492196
OS 50.41763348 -38.37382724
OS 50.42595452 -38.36365708
OS 50.43520012 -38.35441148
OS 50.43612468 -38.35348692
OS 50.4379738 -38.35256236
OS 50.44074748 -38.34978868
OS 50.44537028 -38.347015
OS 50.45091764 -38.34331676
OS 50.45738956 -38.33961852
OS 50.46478604 -38.33499572
OS 50.47403164 -38.33037292
OS 50.4842018 -38.32575012
OS 50.49529652 -38.32112732
OS 50.5073158 -38.31742908
OS 50.52025964 -38.31373084
OS 50.53412804 -38.31095716
OS 50.548921 -38.30818348
OS 50.56463852 -38.30725892
OS 50.5812806 -38.30633436
OS 50.5905262 -38.30633436
OS 50.59699812 -38.30725892
OE
OB 51.0944114 -38.30725892 I
OS 51.10643068 -38.30910804
OS 51.12029908 -38.31188172
OS 51.13509204 -38.31557996
OS 51.15080956 -38.32020276
OS 51.16560252 -38.32759924
OS 51.16652708 -38.32759924
OS 51.16745164 -38.3285238
OS 51.17207444 -38.33129748
OS 51.17947092 -38.33592028
OS 51.18871652 -38.3423922
OS 51.19888668 -38.3516378
OS 51.2099814 -38.36180796
OS 51.22015156 -38.37382724
OS 51.23032172 -38.38769564
OS 51.23124628 -38.38954476
OS 51.23494452 -38.39416756
OS 51.23864276 -38.4024886
OS 51.24511468 -38.41450788
OS 51.25066204 -38.42837628
OS 51.25805852 -38.4440938
OS 51.26453044 -38.462585
OS 51.2700778 -38.48292532
OS 51.2700778 -38.48384988
OS 51.27100236 -38.485699
OS 51.27192692 -38.48847268
OS 51.27285148 -38.49309548
OS 51.27377604 -38.49864284
OS 51.2747006 -38.50511476
OS 51.27654972 -38.5134358
OS 51.27747428 -38.5226814
OS 51.2793234 -38.53285156
OS 51.28024796 -38.54394628
OS 51.28117252 -38.55689012
OS 51.28302164 -38.56983396
OS 51.2839462 -38.58462692
OS 51.2839462 -38.59941988
OS 51.28487076 -38.61606196
OS 51.28487076 -38.6336286
OS 51.28487076 -38.63455316
OS 51.28487076 -38.6382514
OS 51.28487076 -38.64472332
OS 51.28487076 -38.6521198
OS 51.2839462 -38.66228996
OS 51.2839462 -38.67338468
OS 51.28302164 -38.68540396
OS 51.28209708 -38.6983478
OS 51.2793234 -38.72793372
OS 51.2747006 -38.7584442
OS 51.26915324 -38.78803012
OS 51.265455 -38.80189852
OS 51.2608322 -38.81576692
OS 51.2608322 -38.81669148
OS 51.25990764 -38.8185406
OS 51.25805852 -38.82223884
OS 51.2562094 -38.82686164
OS 51.25436028 -38.83333356
OS 51.25066204 -38.83980548
OS 51.24326556 -38.855523
OS 51.23401996 -38.87216508
OS 51.22200068 -38.89065628
OS 51.20813228 -38.90729836
OS 51.1914902 -38.92301588
OS 51.19056564 -38.92301588
OS 51.18964108 -38.924865
OS 51.1868674 -38.92671412
OS 51.18316916 -38.92856324
OS 51.17854636 -38.93133692
OS 51.17392356 -38.93503516
OS 51.16005516 -38.94150708
OS 51.14341308 -38.947979
OS 51.12399732 -38.95445092
OS 51.10088332 -38.95814916
OS 51.0759202 -38.95999828
OS 51.0666746 -38.95999828
OS 51.06020268 -38.95907372
OS 51.0528062 -38.95814916
OS 51.0435606 -38.95630004
OS 51.03339044 -38.95445092
OS 51.02229572 -38.95167724
OS 51.011201 -38.947979
OS 50.99918172 -38.94428076
OS 50.98716244 -38.9387334
OS 50.97514316 -38.93226148
OS 50.96312388 -38.924865
OS 50.9511046 -38.9156194
OS 50.94000988 -38.90544924
OS 50.92983972 -38.89435452
OS 50.92891516 -38.89342996
OS 50.92706604 -38.89065628
OS 50.92429236 -38.88603348
OS 50.91966956 -38.878637
OS 50.91504676 -38.87031596
OS 50.91042396 -38.85922124
OS 50.90395204 -38.8462774
OS 50.89840468 -38.83148444
OS 50.89285732 -38.81484236
OS 50.88730996 -38.7954266
OS 50.8817626 -38.77416172
OS 50.8771398 -38.75012316
OS 50.872517 -38.72423548
OS 50.86974332 -38.69649868
OS 50.8678942 -38.6659882
OS 50.86696964 -38.6336286
OS 50.86696964 -38.63270404
OS 50.86696964 -38.6290058
OS 50.86696964 -38.62253388
OS 50.86696964 -38.6151374
OS 50.8678942 -38.60496724
OS 50.8678942 -38.59387252
OS 50.86881876 -38.58185324
OS 50.86974332 -38.56798484
OS 50.872517 -38.53932348
OS 50.8771398 -38.508813
OS 50.88268716 -38.47830252
OS 50.8863854 -38.46443412
OS 50.89008364 -38.45056572
OS 50.89008364 -38.44964116
OS 50.8910082 -38.44779204
OS 50.89285732 -38.4440938
OS 50.89470644 -38.439471
OS 50.89655556 -38.43299908
OS 50.9002538 -38.42652716
OS 50.90765028 -38.41080964
OS 50.91689588 -38.39416756
OS 50.92891516 -38.37660092
OS 50.94278356 -38.35903428
OS 50.95942564 -38.34424132
OS 50.9603502 -38.34424132
OS 50.96127476 -38.3423922
OS 50.96404844 -38.34054308
OS 50.96774668 -38.33869396
OS 50.97236948 -38.33499572
OS 50.97791684 -38.33222204
OS 50.99178524 -38.32482556
OS 51.00842732 -38.31835364
OS 51.02784308 -38.31188172
OS 51.05095708 -38.30818348
OS 51.0759202 -38.30633436
OS 51.08424124 -38.30633436
OS 51.0944114 -38.30725892
OE
OB 51.59182468 -38.30725892 I
OS 51.59922116 -38.30818348
OS 51.60846676 -38.30910804
OS 51.61863692 -38.31095716
OS 51.62880708 -38.31280628
OS 51.65284564 -38.3192782
OS 51.6768842 -38.3285238
OS 51.68890348 -38.33407116
OS 51.70092276 -38.34054308
OS 51.71201748 -38.34886412
OS 51.72218764 -38.35810972
OS 51.7231122 -38.35903428
OS 51.72496132 -38.35995884
OS 51.72681044 -38.36365708
OS 51.73050868 -38.36735532
OS 51.73513148 -38.37197812
OS 51.73975428 -38.37845004
OS 51.74437708 -38.38492196
OS 51.74992444 -38.393243
OS 51.75917004 -38.41080964
OS 51.76841564 -38.43299908
OS 51.77211388 -38.4440938
OS 51.773963 -38.45703764
OS 51.77581212 -38.46998148
OS 51.77673668 -38.48384988
OS 51.77673668 -38.485699
OS 51.77673668 -38.4903218
OS 51.77581212 -38.49771828
OS 51.77488756 -38.50788844
OS 51.77303844 -38.51898316
OS 51.7693402 -38.531927
OS 51.76564196 -38.5457954
OS 51.7600946 -38.5596638
OS 51.75917004 -38.56151292
OS 51.75732092 -38.56613572
OS 51.75362268 -38.5735322
OS 51.74807532 -38.58370236
OS 51.74067884 -38.59479708
OS 51.73143324 -38.60866548
OS 51.72033852 -38.62253388
OS 51.70739468 -38.6382514
OS 51.70554556 -38.64010052
OS 51.70092276 -38.64564788
OS 51.69629996 -38.65027068
OS 51.69167716 -38.65489348
OS 51.6861298 -38.66044084
OS 51.67873332 -38.66783732
OS 51.67133684 -38.6752338
OS 51.66209124 -38.68355484
OS 51.65284564 -38.69280044
OS 51.64175092 -38.7029706
OS 51.62973164 -38.71314076
OS 51.6167878 -38.72516004
OS 51.60199484 -38.73717932
OS 51.58720188 -38.75012316
OS 51.58627732 -38.75104772
OS 51.5844282 -38.75289684
OS 51.58072996 -38.75567052
OS 51.57610716 -38.75936876
OS 51.5705598 -38.76491612
OS 51.56408788 -38.77046348
OS 51.54929492 -38.78248276
OS 51.5335774 -38.79635116
OS 51.51878444 -38.81021956
OS 51.5058406 -38.82223884
OS 51.50029324 -38.82686164
OS 51.49567044 -38.83148444
OS 51.49474588 -38.832409
OS 51.4919722 -38.83518268
OS 51.48827396 -38.83888092
OS 51.48365116 -38.84442828
OS 51.47902836 -38.8509002
OS 51.473481 -38.85737212
OS 51.46238628 -38.87308964
OS 51.77766124 -38.87308964
OS 51.77766124 -38.94890356
OS 51.3532882 -38.94890356
OS 51.3532882 -38.947979
OS 51.3532882 -38.94428076
OS 51.3532882 -38.9387334
OS 51.35421276 -38.93133692
OS 51.35513732 -38.92301588
OS 51.35698644 -38.91377028
OS 51.35883556 -38.90452468
OS 51.3625338 -38.89435452
OS 51.3625338 -38.89342996
OS 51.36345836 -38.8925054
OS 51.36530748 -38.88695804
OS 51.36900572 -38.878637
OS 51.37455308 -38.86754228
OS 51.38194956 -38.85459844
OS 51.39119516 -38.83980548
OS 51.40136532 -38.82501252
OS 51.41430916 -38.809295
OS 51.41430916 -38.80837044
OS 51.41615828 -38.80744588
OS 51.42078108 -38.80189852
OS 51.42910212 -38.79357748
OS 51.4411214 -38.7815582
OS 51.4549898 -38.7676898
OS 51.47255644 -38.75104772
OS 51.49382132 -38.73255652
OS 51.51693532 -38.71314076
OS 51.51785988 -38.7122162
OS 51.52155812 -38.70944252
OS 51.52710548 -38.70481972
OS 51.5335774 -38.69927236
OS 51.54189844 -38.69187588
OS 51.5520686 -38.68355484
OS 51.56223876 -38.67430924
OS 51.57425804 -38.66413908
OS 51.59737204 -38.64194964
OS 51.62048604 -38.6197602
OS 51.63158076 -38.60866548
OS 51.64175092 -38.59757076
OS 51.65099652 -38.5874006
OS 51.658393 -38.57723044
OS 51.658393 -38.57630588
OS 51.66024212 -38.57538132
OS 51.66209124 -38.57260764
OS 51.66394036 -38.5689094
OS 51.67041228 -38.55873924
OS 51.67780876 -38.54671996
OS 51.68428068 -38.531927
OS 51.6907526 -38.51620948
OS 51.69445084 -38.49864284
OS 51.69629996 -38.48200076
OS 51.69629996 -38.4810762
OS 51.69629996 -38.48015164
OS 51.6953754 -38.47460428
OS 51.69445084 -38.46535868
OS 51.69167716 -38.45518852
OS 51.68797892 -38.44224468
OS 51.681507 -38.42930084
OS 51.67318596 -38.416357
OS 51.66209124 -38.40341316
OS 51.66024212 -38.40156404
OS 51.65561932 -38.3978658
OS 51.6491474 -38.393243
OS 51.63897724 -38.38677108
OS 51.6260334 -38.38122372
OS 51.61124044 -38.37567636
OS 51.5936738 -38.37197812
OS 51.57425804 -38.37105356
OS 51.56871068 -38.37105356
OS 51.56501244 -38.37197812
OS 51.55391772 -38.37290268
OS 51.54097388 -38.37567636
OS 51.52710548 -38.3793746
OS 51.51138796 -38.38584652
OS 51.496595 -38.39416756
OS 51.4827266 -38.40526228
OS 51.48087748 -38.4071114
OS 51.47717924 -38.4117342
OS 51.47163188 -38.41913068
OS 51.46608452 -38.4302254
OS 51.4596126 -38.44316924
OS 51.45406524 -38.45981132
OS 51.450367 -38.47830252
OS 51.44851788 -38.4995674
OS 51.36808116 -38.49124636
OS 51.36808116 -38.4903218
OS 51.36900572 -38.48754812
OS 51.36900572 -38.48292532
OS 51.36993028 -38.4764534
OS 51.3717794 -38.46905692
OS 51.37362852 -38.46073588
OS 51.3764022 -38.45056572
OS 51.37917588 -38.44039556
OS 51.38657236 -38.41820612
OS 51.39766708 -38.39601668
OS 51.404139 -38.38492196
OS 51.41246004 -38.37382724
OS 51.42078108 -38.36365708
OS 51.43002668 -38.35441148
OS 51.43095124 -38.35348692
OS 51.43280036 -38.35256236
OS 51.43557404 -38.34978868
OS 51.44019684 -38.347015
OS 51.4457442 -38.34331676
OS 51.45221612 -38.33961852
OS 51.4596126 -38.33499572
OS 51.4688582 -38.33037292
OS 51.47902836 -38.32575012
OS 51.49012308 -38.32112732
OS 51.50214236 -38.31742908
OS 51.5150862 -38.31373084
OS 51.5289546 -38.31095716
OS 51.54374756 -38.30818348
OS 51.55946508 -38.30725892
OS 51.57610716 -38.30633436
OS 51.58535276 -38.30633436
OS 51.59182468 -38.30725892
OE
OB 52.08184148 -38.30725892 I
OS 52.09386076 -38.30910804
OS 52.10865372 -38.31188172
OS 52.1252958 -38.31650452
OS 52.14193788 -38.32205188
OS 52.15857996 -38.32944836
OS 52.15950452 -38.32944836
OS 52.16042908 -38.33037292
OS 52.16597644 -38.3331466
OS 52.17429748 -38.33869396
OS 52.18354308 -38.34516588
OS 52.1946378 -38.35441148
OS 52.20573252 -38.36458164
OS 52.21682724 -38.37660092
OS 52.22607284 -38.39046932
OS 52.2269974 -38.39231844
OS 52.22977108 -38.39694124
OS 52.23346932 -38.40526228
OS 52.23809212 -38.41543244
OS 52.24271492 -38.42745172
OS 52.24641316 -38.44132012
OS 52.24918684 -38.45703764
OS 52.2501114 -38.47275516
OS 52.2501114 -38.47460428
OS 52.2501114 -38.48015164
OS 52.24918684 -38.48754812
OS 52.24733772 -38.49771828
OS 52.24456404 -38.50973756
OS 52.23994124 -38.5226814
OS 52.23439388 -38.53562524
OS 52.2269974 -38.54856908
OS 52.22607284 -38.5504182
OS 52.22329916 -38.55411644
OS 52.2177518 -38.56058836
OS 52.21035532 -38.56798484
OS 52.20110972 -38.57630588
OS 52.190015 -38.58555148
OS 52.17707116 -38.59387252
OS 52.16135364 -38.60219356
OS 52.1622782 -38.60219356
OS 52.16412732 -38.60311812
OS 52.166901 -38.60404268
OS 52.17059924 -38.60496724
OS 52.1807694 -38.60866548
OS 52.19371324 -38.61421284
OS 52.2085062 -38.62160932
OS 52.22329916 -38.63085492
OS 52.23716756 -38.6428742
OS 52.2501114 -38.6567426
OS 52.25103596 -38.65859172
OS 52.2547342 -38.66413908
OS 52.26028156 -38.67338468
OS 52.26582892 -38.68540396
OS 52.27137628 -38.70019692
OS 52.27692364 -38.71776356
OS 52.28062188 -38.73810388
OS 52.28154644 -38.76029332
OS 52.28154644 -38.76121788
OS 52.28154644 -38.76399156
OS 52.28154644 -38.76861436
OS 52.28062188 -38.77416172
OS 52.27969732 -38.7815582
OS 52.2778482 -38.78987924
OS 52.27599908 -38.79912484
OS 52.27414996 -38.809295
OS 52.26675348 -38.83148444
OS 52.26120612 -38.84350372
OS 52.25565876 -38.85459844
OS 52.24826228 -38.86661772
OS 52.23994124 -38.878637
OS 52.23069564 -38.89065628
OS 52.21960092 -38.901751
OS 52.21867636 -38.90267556
OS 52.21682724 -38.90452468
OS 52.213129 -38.90729836
OS 52.2085062 -38.9109966
OS 52.20295884 -38.9156194
OS 52.19556236 -38.9202422
OS 52.18724132 -38.92578956
OS 52.17707116 -38.93041236
OS 52.166901 -38.93595972
OS 52.15488172 -38.94150708
OS 52.14286244 -38.94612988
OS 52.12899404 -38.95075268
OS 52.11420108 -38.95445092
OS 52.09848356 -38.9572246
OS 52.08276604 -38.95907372
OS 52.0651994 -38.95999828
OS 52.05687836 -38.95999828
OS 52.051331 -38.95907372
OS 52.04393452 -38.95814916
OS 52.03561348 -38.9572246
OS 52.02636788 -38.95537548
OS 52.01619772 -38.95352636
OS 51.99400828 -38.947979
OS 51.97089428 -38.9387334
OS 51.958875 -38.93318604
OS 51.94778028 -38.92671412
OS 51.93668556 -38.91839308
OS 51.92559084 -38.91007204
OS 51.92466628 -38.90914748
OS 51.92281716 -38.90729836
OS 51.92004348 -38.90452468
OS 51.9172698 -38.90082644
OS 51.912647 -38.89620364
OS 51.9080242 -38.88973172
OS 51.90247684 -38.8832598
OS 51.89692948 -38.87493876
OS 51.89138212 -38.86569316
OS 51.88583476 -38.85644756
OS 51.8756646 -38.83425812
OS 51.86734356 -38.80837044
OS 51.86456988 -38.79450204
OS 51.86272076 -38.77970908
OS 51.94130836 -38.76953892
OS 51.94130836 -38.77046348
OS 51.94223292 -38.7723126
OS 51.94315748 -38.77601084
OS 51.94408204 -38.78063364
OS 51.9450066 -38.786181
OS 51.94685572 -38.79265292
OS 51.95147852 -38.80652132
OS 51.95795044 -38.8231634
OS 51.96627148 -38.83888092
OS 51.97551708 -38.85367388
OS 51.9866118 -38.86661772
OS 51.98846092 -38.86754228
OS 51.99215916 -38.87124052
OS 51.99955564 -38.87586332
OS 52.00880124 -38.88048612
OS 52.01989596 -38.88603348
OS 52.03376436 -38.89065628
OS 52.04948188 -38.89435452
OS 52.06612396 -38.89527908
OS 52.07167132 -38.89527908
OS 52.07536956 -38.89435452
OS 52.08553972 -38.89342996
OS 52.09848356 -38.89065628
OS 52.11327652 -38.88603348
OS 52.12899404 -38.87956156
OS 52.14471156 -38.87031596
OS 52.15950452 -38.85737212
OS 52.16135364 -38.855523
OS 52.16597644 -38.84997564
OS 52.1715238 -38.8416546
OS 52.17892028 -38.83055988
OS 52.18631676 -38.81669148
OS 52.19186412 -38.80097396
OS 52.19648692 -38.78248276
OS 52.19833604 -38.76214244
OS 52.19833604 -38.76121788
OS 52.19833604 -38.75936876
OS 52.19833604 -38.75659508
OS 52.19741148 -38.75289684
OS 52.19648692 -38.74272668
OS 52.19371324 -38.7307074
OS 52.190015 -38.71591444
OS 52.18354308 -38.70112148
OS 52.17429748 -38.68632852
OS 52.1622782 -38.67246012
OS 52.16042908 -38.670611
OS 52.15580628 -38.66691276
OS 52.1484098 -38.6613654
OS 52.13823964 -38.65489348
OS 52.1252958 -38.64842156
OS 52.10957828 -38.6428742
OS 52.09201164 -38.63917596
OS 52.07259588 -38.63732684
OS 52.06427484 -38.63732684
OS 52.05780292 -38.6382514
OS 52.04948188 -38.63917596
OS 52.04023628 -38.64102508
OS 52.02914156 -38.6428742
OS 52.01712228 -38.64564788
OS 52.02636788 -38.57630588
OS 52.03099068 -38.57630588
OS 52.03468892 -38.57723044
OS 52.0467082 -38.57723044
OS 52.05687836 -38.57538132
OS 52.06889764 -38.5735322
OS 52.08276604 -38.57075852
OS 52.09848356 -38.56613572
OS 52.11327652 -38.5596638
OS 52.12899404 -38.55134276
OS 52.1299186 -38.55134276
OS 52.13084316 -38.5504182
OS 52.13546596 -38.54671996
OS 52.14193788 -38.54024804
OS 52.14933436 -38.531927
OS 52.15673084 -38.51990772
OS 52.16320276 -38.50603932
OS 52.16782556 -38.4903218
OS 52.16967468 -38.4810762
OS 52.16967468 -38.47090604
OS 52.16967468 -38.46998148
OS 52.16967468 -38.46905692
OS 52.16967468 -38.46350956
OS 52.16782556 -38.45611308
OS 52.16597644 -38.44594292
OS 52.1622782 -38.4348482
OS 52.1576554 -38.42282892
OS 52.15025892 -38.41080964
OS 52.14008876 -38.39971492
OS 52.1391642 -38.39879036
OS 52.1345414 -38.39509212
OS 52.12806948 -38.39046932
OS 52.11974844 -38.38492196
OS 52.10865372 -38.38029916
OS 52.09570988 -38.37567636
OS 52.08091692 -38.37197812
OS 52.06427484 -38.37105356
OS 52.05687836 -38.37105356
OS 52.04855732 -38.37290268
OS 52.0374626 -38.3747518
OS 52.02544332 -38.37845004
OS 52.01342404 -38.38307284
OS 52.0004802 -38.39046932
OS 51.98846092 -38.39971492
OS 51.98753636 -38.40063948
OS 51.98383812 -38.40526228
OS 51.97829076 -38.4117342
OS 51.97181884 -38.4209798
OS 51.96534692 -38.43299908
OS 51.958875 -38.44779204
OS 51.95332764 -38.46535868
OS 51.9496294 -38.485699
OS 51.8710418 -38.4718306
OS 51.8710418 -38.47090604
OS 51.87196636 -38.46813236
OS 51.87289092 -38.46443412
OS 51.87381548 -38.45888676
OS 51.8756646 -38.45241484
OS 51.87843828 -38.44501836
OS 51.88398564 -38.42745172
OS 51.89323124 -38.4071114
OS 51.90432596 -38.38677108
OS 51.91819436 -38.36735532
OS 51.935761 -38.34978868
OS 51.93668556 -38.34886412
OS 51.93853468 -38.34793956
OS 51.94130836 -38.34609044
OS 51.9450066 -38.34331676
OS 51.9496294 -38.33961852
OS 51.95610132 -38.33592028
OS 51.96257324 -38.33222204
OS 51.97089428 -38.32759924
OS 51.98938548 -38.32020276
OS 52.01065036 -38.31280628
OS 52.03561348 -38.30818348
OS 52.04855732 -38.30633436
OS 52.07167132 -38.30633436
OS 52.08184148 -38.30725892
OE
OB 51.07499564 -38.37105356 H
OS 51.06944828 -38.37105356
OS 51.06575004 -38.37197812
OS 51.05557988 -38.37382724
OS 51.0435606 -38.37660092
OS 51.0296922 -38.38214828
OS 51.01489924 -38.39046932
OS 51.00750276 -38.39601668
OS 51.00010628 -38.40156404
OS 50.99363436 -38.40896052
OS 50.98716244 -38.41728156
OS 50.98716244 -38.41820612
OS 50.98531332 -38.42005524
OS 50.9834642 -38.42375348
OS 50.98069052 -38.42837628
OS 50.97791684 -38.43577276
OS 50.9742186 -38.4440938
OS 50.97144492 -38.45426396
OS 50.96774668 -38.46628324
OS 50.96404844 -38.48015164
OS 50.9603502 -38.49586916
OS 50.95665196 -38.5134358
OS 50.95387828 -38.53285156
OS 50.9511046 -38.555041
OS 50.94925548 -38.57907956
OS 50.94833092 -38.60496724
OS 50.94740636 -38.6336286
OS 50.94740636 -38.63547772
OS 50.94740636 -38.64010052
OS 50.94740636 -38.64842156
OS 50.94833092 -38.65951628
OS 50.94833092 -38.67153556
OS 50.94925548 -38.68632852
OS 50.95018004 -38.70204604
OS 50.95202916 -38.71868812
OS 50.95665196 -38.75474596
OS 50.95942564 -38.7723126
OS 50.96312388 -38.78895468
OS 50.96682212 -38.8046722
OS 50.97236948 -38.81946516
OS 50.97791684 -38.832409
OS 50.98438876 -38.84350372
OS 50.98438876 -38.84442828
OS 50.98623788 -38.84535284
OS 50.99086068 -38.85182476
OS 50.99918172 -38.8601458
OS 51.00935188 -38.8693914
OS 51.02322028 -38.878637
OS 51.0389378 -38.88695804
OS 51.05650444 -38.89342996
OS 51.06575004 -38.89435452
OS 51.0759202 -38.89527908
OS 51.08146756 -38.89527908
OS 51.0851658 -38.89435452
OS 51.0944114 -38.8925054
OS 51.10735524 -38.88880716
OS 51.12122364 -38.88233524
OS 51.13694116 -38.87308964
OS 51.14433764 -38.86754228
OS 51.15173412 -38.8601458
OS 51.1591306 -38.85274932
OS 51.16652708 -38.84350372
OS 51.16652708 -38.84257916
OS 51.1683762 -38.84073004
OS 51.17022532 -38.83795636
OS 51.17207444 -38.83333356
OS 51.17577268 -38.82686164
OS 51.17854636 -38.8185406
OS 51.1822446 -38.809295
OS 51.18594284 -38.79820028
OS 51.18871652 -38.78433188
OS 51.19241476 -38.76953892
OS 51.196113 -38.75197228
OS 51.19888668 -38.73348108
OS 51.2007358 -38.71129164
OS 51.20258492 -38.68817764
OS 51.20443404 -38.66228996
OS 51.20443404 -38.6336286
OS 51.20443404 -38.63270404
OS 51.20443404 -38.63177948
OS 51.20443404 -38.62715668
OS 51.20443404 -38.61883564
OS 51.20350948 -38.60774092
OS 51.20350948 -38.59572164
OS 51.20258492 -38.58092868
OS 51.20166036 -38.56521116
OS 51.19981124 -38.54764452
OS 51.19518844 -38.51251124
OS 51.19241476 -38.4949446
OS 51.18871652 -38.47830252
OS 51.18501828 -38.462585
OS 51.17947092 -38.44779204
OS 51.17392356 -38.4348482
OS 51.16745164 -38.42375348
OS 51.16745164 -38.42282892
OS 51.16560252 -38.42190436
OS 51.1637534 -38.41913068
OS 51.16097972 -38.41543244
OS 51.15265868 -38.4071114
OS 51.14248852 -38.39694124
OS 51.12862012 -38.38769564
OS 51.1129026 -38.3793746
OS 51.10458156 -38.37567636
OS 51.09533596 -38.37290268
OS 51.0851658 -38.37197812
OS 51.07499564 -38.37105356
OE
OB 54.05947532 -38.37105356 H
OS 54.05392796 -38.37105356
OS 54.05022972 -38.37197812
OS 54.04005956 -38.37382724
OS 54.02804028 -38.37660092
OS 54.01417188 -38.38214828
OS 53.99937892 -38.39046932
OS 53.99198244 -38.39601668
OS 53.98458596 -38.40156404
OS 53.97811404 -38.40896052
OS 53.97164212 -38.41728156
OS 53.97164212 -38.41820612
OS 53.969793 -38.42005524
OS 53.96794388 -38.42375348
OS 53.9651702 -38.42837628
OS 53.96239652 -38.43577276
OS 53.95869828 -38.4440938
OS 53.9559246 -38.45426396
OS 53.95222636 -38.46628324
OS 53.94852812 -38.48015164
OS 53.94482988 -38.49586916
OS 53.94113164 -38.5134358
OS 53.93835796 -38.53285156
OS 53.93558428 -38.555041
OS 53.93373516 -38.57907956
OS 53.9328106 -38.60496724
OS 53.93188604 -38.6336286
OS 53.93188604 -38.63547772
OS 53.93188604 -38.64010052
OS 53.93188604 -38.64842156
OS 53.9328106 -38.65951628
OS 53.9328106 -38.67153556
OS 53.93373516 -38.68632852
OS 53.93465972 -38.70204604
OS 53.93650884 -38.71868812
OS 53.94113164 -38.75474596
OS 53.94390532 -38.7723126
OS 53.94760356 -38.78895468
OS 53.9513018 -38.8046722
OS 53.95684916 -38.81946516
OS 53.96239652 -38.832409
OS 53.96886844 -38.84350372
OS 53.96886844 -38.84442828
OS 53.97071756 -38.84535284
OS 53.97534036 -38.85182476
OS 53.9836614 -38.8601458
OS 53.99383156 -38.8693914
OS 54.00769996 -38.878637
OS 54.02341748 -38.88695804
OS 54.04098412 -38.89342996
OS 54.05022972 -38.89435452
OS 54.06039988 -38.89527908
OS 54.06594724 -38.89527908
OS 54.06964548 -38.89435452
OS 54.07889108 -38.8925054
OS 54.09183492 -38.88880716
OS 54.10570332 -38.88233524
OS 54.12142084 -38.87308964
OS 54.12881732 -38.86754228
OS 54.1362138 -38.8601458
OS 54.14361028 -38.85274932
OS 54.15100676 -38.84350372
OS 54.15100676 -38.84257916
OS 54.15285588 -38.84073004
OS 54.154705 -38.83795636
OS 54.15655412 -38.83333356
OS 54.16025236 -38.82686164
OS 54.16302604 -38.8185406
OS 54.16672428 -38.809295
OS 54.17042252 -38.79820028
OS 54.1731962 -38.78433188
OS 54.17689444 -38.76953892
OS 54.18059268 -38.75197228
OS 54.18336636 -38.73348108
OS 54.18521548 -38.71129164
OS 54.1870646 -38.68817764
OS 54.18891372 -38.66228996
OS 54.18891372 -38.6336286
OS 54.18891372 -38.63270404
OS 54.18891372 -38.63177948
OS 54.18891372 -38.62715668
OS 54.18891372 -38.61883564
OS 54.18798916 -38.60774092
OS 54.18798916 -38.59572164
OS 54.1870646 -38.58092868
OS 54.18614004 -38.56521116
OS 54.18429092 -38.54764452
OS 54.17966812 -38.51251124
OS 54.17689444 -38.4949446
OS 54.1731962 -38.47830252
OS 54.16949796 -38.462585
OS 54.1639506 -38.44779204
OS 54.15840324 -38.4348482
OS 54.15193132 -38.42375348
OS 54.15193132 -38.42282892
OS 54.1500822 -38.42190436
OS 54.14823308 -38.41913068
OS 54.1454594 -38.41543244
OS 54.13713836 -38.4071114
OS 54.1269682 -38.39694124
OS 54.1130998 -38.38769564
OS 54.09738228 -38.3793746
OS 54.08906124 -38.37567636
OS 54.07981564 -38.37290268
OS 54.06964548 -38.37197812
OS 54.05947532 -38.37105356
OE
OB 49.87491676 -38.43669732 H
OS 49.67336268 -38.72331092
OS 49.87491676 -38.72331092
OS 49.87491676 -38.43669732
OE
OB 56.14158444 -38.38492196 H
OS 55.95852156 -38.38492196
OS 55.95852156 -38.61328828
OS 56.13048972 -38.61328828
OS 56.13696164 -38.61236372
OS 56.14343356 -38.61236372
OS 56.15083004 -38.61143916
OS 56.16839668 -38.60959004
OS 56.18781244 -38.6058918
OS 56.2072282 -38.60034444
OS 56.22479484 -38.59294796
OS 56.23311588 -38.58832516
OS 56.2395878 -38.5827778
OS 56.24143692 -38.58092868
OS 56.24513516 -38.57723044
OS 56.25068252 -38.56983396
OS 56.25715444 -38.56058836
OS 56.26362636 -38.54856908
OS 56.26917372 -38.53377612
OS 56.27287196 -38.51713404
OS 56.27472108 -38.49771828
OS 56.27472108 -38.49679372
OS 56.27472108 -38.49586916
OS 56.27472108 -38.49124636
OS 56.27379652 -38.48292532
OS 56.2719474 -38.47367972
OS 56.27009828 -38.46350956
OS 56.26640004 -38.45149028
OS 56.26085268 -38.44039556
OS 56.25438076 -38.42930084
OS 56.2534562 -38.42837628
OS 56.25068252 -38.42467804
OS 56.24605972 -38.42005524
OS 56.24051236 -38.41358332
OS 56.23219132 -38.4071114
OS 56.22294572 -38.40156404
OS 56.21277556 -38.39601668
OS 56.20075628 -38.39139388
OS 56.19983172 -38.39139388
OS 56.19613348 -38.39046932
OS 56.19058612 -38.38954476
OS 56.18318964 -38.38769564
OS 56.17209492 -38.38677108
OS 56.15822652 -38.38584652
OS 56.14158444 -38.38492196
OE
SE

### steps/pcb/layers/comp_+_bot/components
UNITS=MM
#
#Component attribute names
#
@0 .comp_mount_type
@1 .comp_height

# CMP 0
CMP 8 4.39999882 38.599999 0 N J6 Keystone_4871 ;0=1,1=1.5700
PRP ComponentLink1Description 'Datasheet'
PRP ComponentLink1URL ''
PRP Manufacturer 'Keystone Electronics'
PRP Manufacturer_Part_Number '4871'
PRP Supplier_1 ''
PRP Supplier_Part_Number_1 ''
PRP System 'connector'
TOP 0 4.39999882 38.599999 180 N 0 25 Hole
TOP 1 4.39999882 38.599999 180 N 0 18 MT
#
# CMP 1
CMP 8 36.20000126 40.10000108 0 N J5 Keystone_4871 ;0=1,1=1.5700
PRP ComponentLink1Description 'Datasheet'
PRP ComponentLink1URL ''
PRP Manufacturer 'Keystone Electronics'
PRP Manufacturer_Part_Number '4871'
PRP Supplier_1 ''
PRP Supplier_Part_Number_1 ''
PRP System 'connector'
TOP 0 36.20000126 40.10000108 180 N 0 19 Hole
TOP 1 36.20000126 40.10000108 180 N 0 11 MT
#
# CMP 2
CMP 8 35.50000012 -1.00000054 0 N J4 Keystone_4871 ;0=1,1=1.5700
PRP ComponentLink1Description 'Datasheet'
PRP ComponentLink1URL ''
PRP Manufacturer 'Keystone Electronics'
PRP Manufacturer_Part_Number '4871'
PRP Supplier_1 ''
PRP Supplier_Part_Number_1 ''
PRP System 'connector'
TOP 0 35.50000012 -1.00000054 180 N 0 20 Hole
TOP 1 35.50000012 -1.00000054 180 N 0 12 MT
#
# CMP 3
CMP 8 4.39999882 2.00000108 0 N J3 Keystone_4871 ;0=1,1=1.5700
PRP ComponentLink1Description 'Datasheet'
PRP ComponentLink1URL ''
PRP Manufacturer 'Keystone Electronics'
PRP Manufacturer_Part_Number '4871'
PRP Supplier_1 ''
PRP Supplier_Part_Number_1 ''
PRP System 'connector'
TOP 0 4.39999882 2.00000108 180 N 0 21 Hole
TOP 1 4.39999882 2.00000108 180 N 0 13 MT
#
# CMP 4
CMP 15 14.2699994 43.34999966 0 N P10 Mill-Max_8600-0-05-80-00-00-03-0 ;0=2,1=10.1600
PRP Actual_Diameter ''
PRP Applications ''
PRP Board_Thickness ''
PRP Cable_End_Type ''
PRP Category 'Terminals - PC Pin, Single Post Connectors'
PRP Color ''
PRP Connector_Style ''
PRP Connector_Type ''
PRP Contact_Finish 'Tin'
PRP Contact_Material 'Brass Alloy'
PRP Contact_Shape ''
PRP Contact_Type ''
PRP Current_Rating ''
PRP Datasheet_URL 'https://www.digikey.com/en/products/detail/mill-max-manufacturing-corp/8600-0-05-80-00-00-03-0/7775333?s=N4IgTCBcDaIBwDYAMSC0akFZVw39AzOiALoC%2BQA'
PRP Fastening_Type ''
PRP Features ''
PRP FFC__FCB_Thickness ''
PRP Flange_Diameter '0.072_ (1.83mm)'
PRP Flat_Flex_Type ''
PRP Frequency_-_Max ''
PRP Height ''
PRP Impedance ''
PRP Includes ''
PRP Industry_Recognized_Mating_Diameter ''
PRP Insulation 'Non-Insulated'
PRP Internal_Switch(s) ''
PRP Length_-_Above_Flange '0.364_ (9.25mm)'
PRP Length_-_Below_Flange '0.060_ (1.52mm)'
PRP Length_-_Overall '0.460_ (11.68mm)'
PRP Locking_Feature ''
PRP Manufacturer 'Mill-Max Manufacturing Corp.'
PRP Manufacturer_Part_Number '8600-0-05-80-00-00-03-0'
PRP Mated_Stacking_Heights ''
PRP Mating_Length/Depth ''
PRP Mating_Orientation ''
PRP Max_Operating_Temperature '125°C'
PRP Min_Operating_Temperature '-55°C'
PRP Mounting__Pins ''
PRP Mounting_Feature ''
PRP Mounting_Hole_Diameter '0.043_ (1.09mm)'
PRP Mounting_Type 'Through Hole, Vertical'
PRP Number_of_Levels ''
PRP Number_of_Ports ''
PRP Number_of_Positions/Contacts ''
PRP Part_Status ''
PRP Pin_Size_-_Above_Flange '0.040_ (1.02mm) Dia'
PRP Pin_Size_-_Below_Flange '0.035_ (0.89mm) Square'
PRP Pitch ''
PRP Positions_Per_Level ''
PRP RoHS 'Yes'
PRP Rows '1'
PRP Screw_Thread ''
PRP Series '8600'
PRP Shielding ''
PRP Shrouded ''
PRP Signal_Lines ''
PRP Signal_Pins '1'
PRP Size_/_Dimension ''
PRP Special_Notes ''
PRP Specifications ''
PRP Style ''
PRP Supplier_1 'Digikey'
PRP Supplier_Part_Number_1 '8600-0-05-80-00-00-03-0-ND'
PRP System 'connector'
PRP Terminal_Style 'Single End'
PRP Terminal_Type 'PC Pin'
PRP Termination 'Press-Fit, Square'
PRP Torque_-_Screw ''
PRP Type ''
PRP Voltage_Rating ''
PRP Wire_Gauge ''
PRP Wire_Termination ''
TOP 0 14.2699994 43.3299997 180 N 12 2 1
#
# CMP 5
CMP 15 11.2219994 43.34999966 0 N P9 Mill-Max_8600-0-05-80-00-00-03-0 ;0=2,1=10.1600
PRP Actual_Diameter ''
PRP Applications ''
PRP Board_Thickness ''
PRP Cable_End_Type ''
PRP Category 'Terminals - PC Pin, Single Post Connectors'
PRP Color ''
PRP Connector_Style ''
PRP Connector_Type ''
PRP Contact_Finish 'Tin'
PRP Contact_Material 'Brass Alloy'
PRP Contact_Shape ''
PRP Contact_Type ''
PRP Current_Rating ''
PRP Datasheet_URL 'https://www.digikey.com/en/products/detail/mill-max-manufacturing-corp/8600-0-05-80-00-00-03-0/7775333?s=N4IgTCBcDaIBwDYAMSC0akFZVw39AzOiALoC%2BQA'
PRP Fastening_Type ''
PRP Features ''
PRP FFC__FCB_Thickness ''
PRP Flange_Diameter '0.072_ (1.83mm)'
PRP Flat_Flex_Type ''
PRP Frequency_-_Max ''
PRP Height ''
PRP Impedance ''
PRP Includes ''
PRP Industry_Recognized_Mating_Diameter ''
PRP Insulation 'Non-Insulated'
PRP Internal_Switch(s) ''
PRP Length_-_Above_Flange '0.364_ (9.25mm)'
PRP Length_-_Below_Flange '0.060_ (1.52mm)'
PRP Length_-_Overall '0.460_ (11.68mm)'
PRP Locking_Feature ''
PRP Manufacturer 'Mill-Max Manufacturing Corp.'
PRP Manufacturer_Part_Number '8600-0-05-80-00-00-03-0'
PRP Mated_Stacking_Heights ''
PRP Mating_Length/Depth ''
PRP Mating_Orientation ''
PRP Max_Operating_Temperature '125°C'
PRP Min_Operating_Temperature '-55°C'
PRP Mounting__Pins ''
PRP Mounting_Feature ''
PRP Mounting_Hole_Diameter '0.043_ (1.09mm)'
PRP Mounting_Type 'Through Hole, Vertical'
PRP Number_of_Levels ''
PRP Number_of_Ports ''
PRP Number_of_Positions/Contacts ''
PRP Part_Status ''
PRP Pin_Size_-_Above_Flange '0.040_ (1.02mm) Dia'
PRP Pin_Size_-_Below_Flange '0.035_ (0.89mm) Square'
PRP Pitch ''
PRP Positions_Per_Level ''
PRP RoHS 'Yes'
PRP Rows '1'
PRP Screw_Thread ''
PRP Series '8600'
PRP Shielding ''
PRP Shrouded ''
PRP Signal_Lines ''
PRP Signal_Pins '1'
PRP Size_/_Dimension ''
PRP Special_Notes ''
PRP Specifications ''
PRP Style ''
PRP Supplier_1 'Digikey'
PRP Supplier_Part_Number_1 '8600-0-05-80-00-00-03-0-ND'
PRP System 'connector'
PRP Terminal_Style 'Single End'
PRP Terminal_Type 'PC Pin'
PRP Termination 'Press-Fit, Square'
PRP Torque_-_Screw ''
PRP Type ''
PRP Voltage_Rating ''
PRP Wire_Gauge ''
PRP Wire_Termination ''
TOP 0 11.2219994 43.3299997 180 N 13 1 1
#
# CMP 6
CMP 15 8.1739994 43.34999966 0 N P8 Mill-Max_8600-0-05-80-00-00-03-0 ;0=2,1=10.1600
PRP Actual_Diameter ''
PRP Applications ''
PRP Board_Thickness ''
PRP Cable_End_Type ''
PRP Category 'Terminals - PC Pin, Single Post Connectors'
PRP Color ''
PRP Connector_Style ''
PRP Connector_Type ''
PRP Contact_Finish 'Tin'
PRP Contact_Material 'Brass Alloy'
PRP Contact_Shape ''
PRP Contact_Type ''
PRP Current_Rating ''
PRP Datasheet_URL 'https://www.digikey.com/en/products/detail/mill-max-manufacturing-corp/8600-0-05-80-00-00-03-0/7775333?s=N4IgTCBcDaIBwDYAMSC0akFZVw39AzOiALoC%2BQA'
PRP Fastening_Type ''
PRP Features ''
PRP FFC__FCB_Thickness ''
PRP Flange_Diameter '0.072_ (1.83mm)'
PRP Flat_Flex_Type ''
PRP Frequency_-_Max ''
PRP Height ''
PRP Impedance ''
PRP Includes ''
PRP Industry_Recognized_Mating_Diameter ''
PRP Insulation 'Non-Insulated'
PRP Internal_Switch(s) ''
PRP Length_-_Above_Flange '0.364_ (9.25mm)'
PRP Length_-_Below_Flange '0.060_ (1.52mm)'
PRP Length_-_Overall '0.460_ (11.68mm)'
PRP Locking_Feature ''
PRP Manufacturer 'Mill-Max Manufacturing Corp.'
PRP Manufacturer_Part_Number '8600-0-05-80-00-00-03-0'
PRP Mated_Stacking_Heights ''
PRP Mating_Length/Depth ''
PRP Mating_Orientation ''
PRP Max_Operating_Temperature '125°C'
PRP Min_Operating_Temperature '-55°C'
PRP Mounting__Pins ''
PRP Mounting_Feature ''
PRP Mounting_Hole_Diameter '0.043_ (1.09mm)'
PRP Mounting_Type 'Through Hole, Vertical'
PRP Number_of_Levels ''
PRP Number_of_Ports ''
PRP Number_of_Positions/Contacts ''
PRP Part_Status ''
PRP Pin_Size_-_Above_Flange '0.040_ (1.02mm) Dia'
PRP Pin_Size_-_Below_Flange '0.035_ (0.89mm) Square'
PRP Pitch ''
PRP Positions_Per_Level ''
PRP RoHS 'Yes'
PRP Rows '1'
PRP Screw_Thread ''
PRP Series '8600'
PRP Shielding ''
PRP Shrouded ''
PRP Signal_Lines ''
PRP Signal_Pins '1'
PRP Size_/_Dimension ''
PRP Special_Notes ''
PRP Specifications ''
PRP Style ''
PRP Supplier_1 'Digikey'
PRP Supplier_Part_Number_1 '8600-0-05-80-00-00-03-0-ND'
PRP System 'connector'
PRP Terminal_Style 'Single End'
PRP Terminal_Type 'PC Pin'
PRP Termination 'Press-Fit, Square'
PRP Torque_-_Screw ''
PRP Type ''
PRP Voltage_Rating ''
PRP Wire_Gauge ''
PRP Wire_Termination ''
TOP 0 8.1739994 43.3299997 180 N 8 0 1
#
# CMP 7
CMP 15 5.1259994 43.34999966 0 N P7 Mill-Max_8600-0-05-80-00-00-03-0 ;0=2,1=10.1600
PRP Actual_Diameter ''
PRP Applications ''
PRP Board_Thickness ''
PRP Cable_End_Type ''
PRP Category 'Terminals - PC Pin, Single Post Connectors'
PRP Color ''
PRP Connector_Style ''
PRP Connector_Type ''
PRP Contact_Finish 'Tin'
PRP Contact_Material 'Brass Alloy'
PRP Contact_Shape ''
PRP Contact_Type ''
PRP Current_Rating ''
PRP Datasheet_URL 'https://www.digikey.com/en/products/detail/mill-max-manufacturing-corp/8600-0-05-80-00-00-03-0/7775333?s=N4IgTCBcDaIBwDYAMSC0akFZVw39AzOiALoC%2BQA'
PRP Fastening_Type ''
PRP Features ''
PRP FFC__FCB_Thickness ''
PRP Flange_Diameter '0.072_ (1.83mm)'
PRP Flat_Flex_Type ''
PRP Frequency_-_Max ''
PRP Height ''
PRP Impedance ''
PRP Includes ''
PRP Industry_Recognized_Mating_Diameter ''
PRP Insulation 'Non-Insulated'
PRP Internal_Switch(s) ''
PRP Length_-_Above_Flange '0.364_ (9.25mm)'
PRP Length_-_Below_Flange '0.060_ (1.52mm)'
PRP Length_-_Overall '0.460_ (11.68mm)'
PRP Locking_Feature ''
PRP Manufacturer 'Mill-Max Manufacturing Corp.'
PRP Manufacturer_Part_Number '8600-0-05-80-00-00-03-0'
PRP Mated_Stacking_Heights ''
PRP Mating_Length/Depth ''
PRP Mating_Orientation ''
PRP Max_Operating_Temperature '125°C'
PRP Min_Operating_Temperature '-55°C'
PRP Mounting__Pins ''
PRP Mounting_Feature ''
PRP Mounting_Hole_Diameter '0.043_ (1.09mm)'
PRP Mounting_Type 'Through Hole, Vertical'
PRP Number_of_Levels ''
PRP Number_of_Ports ''
PRP Number_of_Positions/Contacts ''
PRP Part_Status ''
PRP Pin_Size_-_Above_Flange '0.040_ (1.02mm) Dia'
PRP Pin_Size_-_Below_Flange '0.035_ (0.89mm) Square'
PRP Pitch ''
PRP Positions_Per_Level ''
PRP RoHS 'Yes'
PRP Rows '1'
PRP Screw_Thread ''
PRP Series '8600'
PRP Shielding ''
PRP Shrouded ''
PRP Signal_Lines ''
PRP Signal_Pins '1'
PRP Size_/_Dimension ''
PRP Special_Notes ''
PRP Specifications ''
PRP Style ''
PRP Supplier_1 'Digikey'
PRP Supplier_Part_Number_1 '8600-0-05-80-00-00-03-0-ND'
PRP System 'connector'
PRP Terminal_Style 'Single End'
PRP Terminal_Type 'PC Pin'
PRP Termination 'Press-Fit, Square'
PRP Torque_-_Screw ''
PRP Type ''
PRP Voltage_Rating ''
PRP Wire_Gauge ''
PRP Wire_Termination ''
TOP 0 5.1259994 43.3299997 180 N 7 0 1
#
# CMP 8
CMP 15 2.0779994 43.34999966 0 N P6 Mill-Max_8600-0-05-80-00-00-03-0 ;0=2,1=10.1600
PRP Actual_Diameter ''
PRP Applications ''
PRP Board_Thickness ''
PRP Cable_End_Type ''
PRP Category 'Terminals - PC Pin, Single Post Connectors'
PRP Color ''
PRP Connector_Style ''
PRP Connector_Type ''
PRP Contact_Finish 'Tin'
PRP Contact_Material 'Brass Alloy'
PRP Contact_Shape ''
PRP Contact_Type ''
PRP Current_Rating ''
PRP Datasheet_URL 'https://www.digikey.com/en/products/detail/mill-max-manufacturing-corp/8600-0-05-80-00-00-03-0/7775333?s=N4IgTCBcDaIBwDYAMSC0akFZVw39AzOiALoC%2BQA'
PRP Fastening_Type ''
PRP Features ''
PRP FFC__FCB_Thickness ''
PRP Flange_Diameter '0.072_ (1.83mm)'
PRP Flat_Flex_Type ''
PRP Frequency_-_Max ''
PRP Height ''
PRP Impedance ''
PRP Includes ''
PRP Industry_Recognized_Mating_Diameter ''
PRP Insulation 'Non-Insulated'
PRP Internal_Switch(s) ''
PRP Length_-_Above_Flange '0.364_ (9.25mm)'
PRP Length_-_Below_Flange '0.060_ (1.52mm)'
PRP Length_-_Overall '0.460_ (11.68mm)'
PRP Locking_Feature ''
PRP Manufacturer 'Mill-Max Manufacturing Corp.'
PRP Manufacturer_Part_Number '8600-0-05-80-00-00-03-0'
PRP Mated_Stacking_Heights ''
PRP Mating_Length/Depth ''
PRP Mating_Orientation ''
PRP Max_Operating_Temperature '125°C'
PRP Min_Operating_Temperature '-55°C'
PRP Mounting__Pins ''
PRP Mounting_Feature ''
PRP Mounting_Hole_Diameter '0.043_ (1.09mm)'
PRP Mounting_Type 'Through Hole, Vertical'
PRP Number_of_Levels ''
PRP Number_of_Ports ''
PRP Number_of_Positions/Contacts ''
PRP Part_Status ''
PRP Pin_Size_-_Above_Flange '0.040_ (1.02mm) Dia'
PRP Pin_Size_-_Below_Flange '0.035_ (0.89mm) Square'
PRP Pitch ''
PRP Positions_Per_Level ''
PRP RoHS 'Yes'
PRP Rows '1'
PRP Screw_Thread ''
PRP Series '8600'
PRP Shielding ''
PRP Shrouded ''
PRP Signal_Lines ''
PRP Signal_Pins '1'
PRP Size_/_Dimension ''
PRP Special_Notes ''
PRP Specifications ''
PRP Style ''
PRP Supplier_1 'Digikey'
PRP Supplier_Part_Number_1 '8600-0-05-80-00-00-03-0-ND'
PRP System 'connector'
PRP Terminal_Style 'Single End'
PRP Terminal_Type 'PC Pin'
PRP Termination 'Press-Fit, Square'
PRP Torque_-_Screw ''
PRP Type ''
PRP Voltage_Rating ''
PRP Wire_Gauge ''
PRP Wire_Termination ''
TOP 0 2.0779994 43.3299997 180 N 11 0 1
#
# CMP 9
CMP 16 0 0 0 N P5 Mill-Max_8600-0-05-80-00-00-03-0 ;0=2,1=10.1600
PRP Actual_Diameter ''
PRP Applications ''
PRP Board_Thickness ''
PRP Cable_End_Type ''
PRP Category 'Terminals - PC Pin, Single Post Connectors'
PRP Color ''
PRP Connector_Style ''
PRP Connector_Type ''
PRP Contact_Finish 'Tin'
PRP Contact_Material 'Brass Alloy'
PRP Contact_Shape ''
PRP Contact_Type ''
PRP Current_Rating ''
PRP Datasheet_URL 'https://www.digikey.com/en/products/detail/mill-max-manufacturing-corp/8600-0-05-80-00-00-03-0/7775333?s=N4IgTCBcDaIBwDYAMSC0akFZVw39AzOiALoC%2BQA'
PRP Fastening_Type ''
PRP Features ''
PRP FFC__FCB_Thickness ''
PRP Flange_Diameter '0.072_ (1.83mm)'
PRP Flat_Flex_Type ''
PRP Frequency_-_Max ''
PRP Height ''
PRP Impedance ''
PRP Includes ''
PRP Industry_Recognized_Mating_Diameter ''
PRP Insulation 'Non-Insulated'
PRP Internal_Switch(s) ''
PRP Length_-_Above_Flange '0.364_ (9.25mm)'
PRP Length_-_Below_Flange '0.060_ (1.52mm)'
PRP Length_-_Overall '0.460_ (11.68mm)'
PRP Locking_Feature ''
PRP Manufacturer 'Mill-Max Manufacturing Corp.'
PRP Manufacturer_Part_Number '8600-0-05-80-00-00-03-0'
PRP Mated_Stacking_Heights ''
PRP Mating_Length/Depth ''
PRP Mating_Orientation ''
PRP Max_Operating_Temperature '125°C'
PRP Min_Operating_Temperature '-55°C'
PRP Mounting__Pins ''
PRP Mounting_Feature ''
PRP Mounting_Hole_Diameter '0.043_ (1.09mm)'
PRP Mounting_Type 'Through Hole, Vertical'
PRP Number_of_Levels ''
PRP Number_of_Ports ''
PRP Number_of_Positions/Contacts ''
PRP Part_Status ''
PRP Pin_Size_-_Above_Flange '0.040_ (1.02mm) Dia'
PRP Pin_Size_-_Below_Flange '0.035_ (0.89mm) Square'
PRP Pitch ''
PRP Positions_Per_Level ''
PRP RoHS 'Yes'
PRP Rows '1'
PRP Screw_Thread ''
PRP Series '8600'
PRP Shielding ''
PRP Shrouded ''
PRP Signal_Lines ''
PRP Signal_Pins '1'
PRP Size_/_Dimension ''
PRP Special_Notes ''
PRP Specifications ''
PRP Style ''
PRP Supplier_1 'Digikey'
PRP Supplier_Part_Number_1 '8600-0-05-80-00-00-03-0-ND'
PRP System 'connector'
PRP Terminal_Style 'Single End'
PRP Terminal_Type 'PC Pin'
PRP Termination 'Press-Fit, Square'
PRP Torque_-_Screw ''
PRP Type ''
PRP Voltage_Rating ''
PRP Wire_Gauge ''
PRP Wire_Termination ''
TOP 0 0 0 180 N 15 7 1
#
# CMP 10
CMP 17 0 40.67999992 0 N P4 Mill-Max_8600-0-05-80-00-00-03-0 ;0=2,1=10.1600
PRP Actual_Diameter ''
PRP Applications ''
PRP Board_Thickness ''
PRP Cable_End_Type ''
PRP Category 'Terminals - PC Pin, Single Post Connectors'
PRP Color ''
PRP Connector_Style ''
PRP Connector_Type ''
PRP Contact_Finish 'Tin'
PRP Contact_Material 'Brass Alloy'
PRP Contact_Shape ''
PRP Contact_Type ''
PRP Current_Rating ''
PRP Datasheet_URL 'https://www.digikey.com/en/products/detail/mill-max-manufacturing-corp/8600-0-05-80-00-00-03-0/7775333?s=N4IgTCBcDaIBwDYAMSC0akFZVw39AzOiALoC%2BQA'
PRP Fastening_Type ''
PRP Features ''
PRP FFC__FCB_Thickness ''
PRP Flange_Diameter '0.072_ (1.83mm)'
PRP Flat_Flex_Type ''
PRP Frequency_-_Max ''
PRP Height ''
PRP Impedance ''
PRP Includes ''
PRP Industry_Recognized_Mating_Diameter ''
PRP Insulation 'Non-Insulated'
PRP Internal_Switch(s) ''
PRP Length_-_Above_Flange '0.364_ (9.25mm)'
PRP Length_-_Below_Flange '0.060_ (1.52mm)'
PRP Length_-_Overall '0.460_ (11.68mm)'
PRP Locking_Feature ''
PRP Manufacturer 'Mill-Max Manufacturing Corp.'
PRP Manufacturer_Part_Number '8600-0-05-80-00-00-03-0'
PRP Mated_Stacking_Heights ''
PRP Mating_Length/Depth ''
PRP Mating_Orientation ''
PRP Max_Operating_Temperature '125°C'
PRP Min_Operating_Temperature '-55°C'
PRP Mounting__Pins ''
PRP Mounting_Feature ''
PRP Mounting_Hole_Diameter '0.043_ (1.09mm)'
PRP Mounting_Type 'Through Hole, Vertical'
PRP Number_of_Levels ''
PRP Number_of_Ports ''
PRP Number_of_Positions/Contacts ''
PRP Part_Status ''
PRP Pin_Size_-_Above_Flange '0.040_ (1.02mm) Dia'
PRP Pin_Size_-_Below_Flange '0.035_ (0.89mm) Square'
PRP Pitch ''
PRP Positions_Per_Level ''
PRP RoHS 'Yes'
PRP Rows '1'
PRP Screw_Thread ''
PRP Series '8600'
PRP Shielding ''
PRP Shrouded ''
PRP Signal_Lines ''
PRP Signal_Pins '1'
PRP Size_/_Dimension ''
PRP Special_Notes ''
PRP Specifications ''
PRP Style ''
PRP Supplier_1 'Digikey'
PRP Supplier_Part_Number_1 '8600-0-05-80-00-00-03-0-ND'
PRP System 'connector'
PRP Terminal_Style 'Single End'
PRP Terminal_Type 'PC Pin'
PRP Termination 'Press-Fit, Square'
PRP Torque_-_Screw ''
PRP Type ''
PRP Voltage_Rating ''
PRP Wire_Gauge ''
PRP Wire_Termination ''
TOP 0 0 40.64 180 N 14 23 1
#
# CMP 11
CMP 18 40.67999992 40.67999992 0 N P3 Mill-Max_8600-0-05-80-00-00-03-0 ;0=2,1=10.1600
PRP Actual_Diameter ''
PRP Applications ''
PRP Board_Thickness ''
PRP Cable_End_Type ''
PRP Category 'Terminals - PC Pin, Single Post Connectors'
PRP Color ''
PRP Connector_Style ''
PRP Connector_Type ''
PRP Contact_Finish 'Tin'
PRP Contact_Material 'Brass Alloy'
PRP Contact_Shape ''
PRP Contact_Type ''
PRP Current_Rating ''
PRP Datasheet_URL 'https://www.digikey.com/en/products/detail/mill-max-manufacturing-corp/8600-0-05-80-00-00-03-0/7775333?s=N4IgTCBcDaIBwDYAMSC0akFZVw39AzOiALoC%2BQA'
PRP Fastening_Type ''
PRP Features ''
PRP FFC__FCB_Thickness ''
PRP Flange_Diameter '0.072_ (1.83mm)'
PRP Flat_Flex_Type ''
PRP Frequency_-_Max ''
PRP Height ''
PRP Impedance ''
PRP Includes ''
PRP Industry_Recognized_Mating_Diameter ''
PRP Insulation 'Non-Insulated'
PRP Internal_Switch(s) ''
PRP Length_-_Above_Flange '0.364_ (9.25mm)'
PRP Length_-_Below_Flange '0.060_ (1.52mm)'
PRP Length_-_Overall '0.460_ (11.68mm)'
PRP Locking_Feature ''
PRP Manufacturer 'Mill-Max Manufacturing Corp.'
PRP Manufacturer_Part_Number '8600-0-05-80-00-00-03-0'
PRP Mated_Stacking_Heights ''
PRP Mating_Length/Depth ''
PRP Mating_Orientation ''
PRP Max_Operating_Temperature '125°C'
PRP Min_Operating_Temperature '-55°C'
PRP Mounting__Pins ''
PRP Mounting_Feature ''
PRP Mounting_Hole_Diameter '0.043_ (1.09mm)'
PRP Mounting_Type 'Through Hole, Vertical'
PRP Number_of_Levels ''
PRP Number_of_Ports ''
PRP Number_of_Positions/Contacts ''
PRP Part_Status ''
PRP Pin_Size_-_Above_Flange '0.040_ (1.02mm) Dia'
PRP Pin_Size_-_Below_Flange '0.035_ (0.89mm) Square'
PRP Pitch ''
PRP Positions_Per_Level ''
PRP RoHS 'Yes'
PRP Rows '1'
PRP Screw_Thread ''
PRP Series '8600'
PRP Shielding ''
PRP Shrouded ''
PRP Signal_Lines ''
PRP Signal_Pins '1'
PRP Size_/_Dimension ''
PRP Special_Notes ''
PRP Specifications ''
PRP Style ''
PRP Supplier_1 'Digikey'
PRP Supplier_Part_Number_1 '8600-0-05-80-00-00-03-0-ND'
PRP System 'connector'
PRP Terminal_Style 'Single End'
PRP Terminal_Type 'PC Pin'
PRP Termination 'Press-Fit, Square'
PRP Torque_-_Screw ''
PRP Type ''
PRP Voltage_Rating ''
PRP Wire_Gauge ''
PRP Wire_Termination ''
TOP 0 40.64 40.64 180 N 9 2 1
#
# CMP 12
CMP 16 40.67999992 20.33999996 0 N P2 Mill-Max_8600-0-05-80-00-00-03-0 ;0=2,1=10.1600
PRP Actual_Diameter ''
PRP Applications ''
PRP Board_Thickness ''
PRP Cable_End_Type ''
PRP Category 'Terminals - PC Pin, Single Post Connectors'
PRP Color ''
PRP Connector_Style ''
PRP Connector_Type ''
PRP Contact_Finish 'Tin'
PRP Contact_Material 'Brass Alloy'
PRP Contact_Shape ''
PRP Contact_Type ''
PRP Current_Rating ''
PRP Datasheet_URL 'https://www.digikey.com/en/products/detail/mill-max-manufacturing-corp/8600-0-05-80-00-00-03-0/7775333?s=N4IgTCBcDaIBwDYAMSC0akFZVw39AzOiALoC%2BQA'
PRP Fastening_Type ''
PRP Features ''
PRP FFC__FCB_Thickness ''
PRP Flange_Diameter '0.072_ (1.83mm)'
PRP Flat_Flex_Type ''
PRP Frequency_-_Max ''
PRP Height ''
PRP Impedance ''
PRP Includes ''
PRP Industry_Recognized_Mating_Diameter ''
PRP Insulation 'Non-Insulated'
PRP Internal_Switch(s) ''
PRP Length_-_Above_Flange '0.364_ (9.25mm)'
PRP Length_-_Below_Flange '0.060_ (1.52mm)'
PRP Length_-_Overall '0.460_ (11.68mm)'
PRP Locking_Feature ''
PRP Manufacturer 'Mill-Max Manufacturing Corp.'
PRP Manufacturer_Part_Number '8600-0-05-80-00-00-03-0'
PRP Mated_Stacking_Heights ''
PRP Mating_Length/Depth ''
PRP Mating_Orientation ''
PRP Max_Operating_Temperature '125°C'
PRP Min_Operating_Temperature '-55°C'
PRP Mounting__Pins ''
PRP Mounting_Feature ''
PRP Mounting_Hole_Diameter '0.043_ (1.09mm)'
PRP Mounting_Type 'Through Hole, Vertical'
PRP Number_of_Levels ''
PRP Number_of_Ports ''
PRP Number_of_Positions/Contacts ''
PRP Part_Status ''
PRP Pin_Size_-_Above_Flange '0.040_ (1.02mm) Dia'
PRP Pin_Size_-_Below_Flange '0.035_ (0.89mm) Square'
PRP Pitch ''
PRP Positions_Per_Level ''
PRP RoHS 'Yes'
PRP Rows '1'
PRP Screw_Thread ''
PRP Series '8600'
PRP Shielding ''
PRP Shrouded ''
PRP Signal_Lines ''
PRP Signal_Pins '1'
PRP Size_/_Dimension ''
PRP Special_Notes ''
PRP Specifications ''
PRP Style ''
PRP Supplier_1 'Digikey'
PRP Supplier_Part_Number_1 '8600-0-05-80-00-00-03-0-ND'
PRP System 'connector'
PRP Terminal_Style 'Single End'
PRP Terminal_Type 'PC Pin'
PRP Termination 'Press-Fit, Square'
PRP Torque_-_Screw ''
PRP Type ''
PRP Voltage_Rating ''
PRP Wire_Gauge ''
PRP Wire_Termination ''
TOP 0 40.67999992 20.33999996 180 N 14 20 1
#
# CMP 13
CMP 19 40.67999992 0 0 N P1 Mill-Max_8600-0-05-80-00-00-03-0 ;0=2,1=10.1600
PRP Actual_Diameter ''
PRP Applications ''
PRP Board_Thickness ''
PRP Cable_End_Type ''
PRP Category 'Terminals - PC Pin, Single Post Connectors'
PRP Color ''
PRP Connector_Style ''
PRP Connector_Type ''
PRP Contact_Finish 'Tin'
PRP Contact_Material 'Brass Alloy'
PRP Contact_Shape ''
PRP Contact_Type ''
PRP Current_Rating ''
PRP Datasheet_URL 'https://www.digikey.com/en/products/detail/mill-max-manufacturing-corp/8600-0-05-80-00-00-03-0/7775333?s=N4IgTCBcDaIBwDYAMSC0akFZVw39AzOiALoC%2BQA'
PRP Fastening_Type ''
PRP Features ''
PRP FFC__FCB_Thickness ''
PRP Flange_Diameter '0.072_ (1.83mm)'
PRP Flat_Flex_Type ''
PRP Frequency_-_Max ''
PRP Height ''
PRP Impedance ''
PRP Includes ''
PRP Industry_Recognized_Mating_Diameter ''
PRP Insulation 'Non-Insulated'
PRP Internal_Switch(s) ''
PRP Length_-_Above_Flange '0.364_ (9.25mm)'
PRP Length_-_Below_Flange '0.060_ (1.52mm)'
PRP Length_-_Overall '0.460_ (11.68mm)'
PRP Locking_Feature ''
PRP Manufacturer 'Mill-Max Manufacturing Corp.'
PRP Manufacturer_Part_Number '8600-0-05-80-00-00-03-0'
PRP Mated_Stacking_Heights ''
PRP Mating_Length/Depth ''
PRP Mating_Orientation ''
PRP Max_Operating_Temperature '125°C'
PRP Min_Operating_Temperature '-55°C'
PRP Mounting__Pins ''
PRP Mounting_Feature ''
PRP Mounting_Hole_Diameter '0.043_ (1.09mm)'
PRP Mounting_Type 'Through Hole, Vertical'
PRP Number_of_Levels ''
PRP Number_of_Ports ''
PRP Number_of_Positions/Contacts ''
PRP Part_Status ''
PRP Pin_Size_-_Above_Flange '0.040_ (1.02mm) Dia'
PRP Pin_Size_-_Below_Flange '0.035_ (0.89mm) Square'
PRP Pitch ''
PRP Positions_Per_Level ''
PRP RoHS 'Yes'
PRP Rows '1'
PRP Screw_Thread ''
PRP Series '8600'
PRP Shielding ''
PRP Shrouded ''
PRP Signal_Lines ''
PRP Signal_Pins '1'
PRP Size_/_Dimension ''
PRP Special_Notes ''
PRP Specifications ''
PRP Style ''
PRP Supplier_1 'Digikey'
PRP Supplier_Part_Number_1 '8600-0-05-80-00-00-03-0-ND'
PRP System 'connector'
PRP Terminal_Style 'Single End'
PRP Terminal_Type 'PC Pin'
PRP Termination 'Press-Fit, Square'
PRP Torque_-_Screw ''
PRP Type ''
PRP Voltage_Rating ''
PRP Wire_Gauge ''
PRP Wire_Termination ''
TOP 0 40.64 0 180 N 10 0 1
#
# CMP 14
CMP 11 14.38500044 19.16500104 180 N R2 Yageo_RC0402FR-0791KL ;0=1,1=0.4000
PRP Case/Package '0402 (1005 Metric)'
PRP Category 'Chip Resistor - Surface Mount'
PRP Composition 'Thick Film'
PRP Datasheet_URL 'https://www.yageo.com/upload/media/product/productsearch/datasheet/rchip/PYu-RC_Group_51_RoHS_L_12.pdf'
PRP Features ''
PRP Height '0.016_ (0.40mm)'
PRP Manufacturer 'Yageo'
PRP Manufacturer_Part_Number 'RC0402FR-0791KL'
PRP Max_Operating_Temperature '155°C'
PRP Min_Operating_Temperature '-55°C'
PRP Mounting_Type ''
PRP Part_Status ''
PRP Power_(Watts) '62.5mW'
PRP Ratings ''
PRP Resistance '91k'
PRP RoHS ''
PRP Series 'RC_L'
PRP Size_/_Dimension '0.039_ L x 0.020_ W (1.00mm x 0.50mm)'
PRP Supplier_1 'Digi-Key'
PRP Supplier_Part_Number_1 '311-91.0KLRCT-ND'
PRP Temperature_Coefficient '±100ppm/°C'
PRP Termination_Style ''
PRP Tolerance '±1%'
TOP 0 13.9050014 19.16500104 0 N 16 6 1
TOP 1 14.86499948 19.16500104 0 N 3 3 2
#
# CMP 15
CMP 10 15.86500002 20.5550008 270 N R6 Yageo_RC0201JR-070RL ;0=1,1=0.2600
PRP Case/Package '0201 (0603 Metric)'
PRP Category 'Chip Resistor - Surface Mount'
PRP Composition 'Thick Film'
PRP Datasheet_URL 'https://www.yageo.com/upload/media/product/productsearch/datasheet/rchip/PYu-RC_Group_51_RoHS_L_11.pdf'
PRP Features ''
PRP Height '0.010_ (0.26mm)'
PRP Manufacturer 'Yageo'
PRP Manufacturer_Part_Number 'RC0201JR-070RL'
PRP Max_Operating_Temperature ''
PRP Min_Operating_Temperature ''
PRP Mounting_Type ''
PRP Part_Status ''
PRP Power_(Watts) '50mW'
PRP Ratings ''
PRP Resistance '0'
PRP RoHS ''
PRP Series 'RC'
PRP Size_/_Dimension '0.024_ L x 0.012_ W (0.60mm x 0.30mm)'
PRP Supplier_1 'Digi-Key'
PRP Supplier_Part_Number_1 '311-0.0NCT-ND'
PRP Temperature_Coefficient ''
PRP Termination_Style ''
PRP Tolerance 'Jumper'
TOP 0 15.86500002 20.21500148 270 N 1 2 1
TOP 1 15.86500002 20.89500012 270 N 14 18 2
#
# CMP 16
CMP 11 16.95499784 20.69500052 270 N R5 Panasonic_ERJ-2RKF2702X ;0=1,1=0.4000
PRP Case/Package '0402 (1005 Metric)'
PRP Category 'Chip Resistor - Surface Mount'
PRP Composition 'Thick Film'
PRP Datasheet_URL 'https://www.digikey.com/en/products/detail/panasonic-electronic-components/ERJ-2RKF2702X/1746175?s=N4IgTCBcDaIKICUBSBaMCDSAxMB2ADGABogC6AvkA'
PRP Features 'Automotive AEC-Q200'
PRP Height '0.016_ (0.40mm)'
PRP Manufacturer 'Panasonic'
PRP Manufacturer_Part_Number 'ERJ-2RKF2702X'
PRP Max_Operating_Temperature '155°C'
PRP Min_Operating_Temperature '-55°C'
PRP Mounting_Type ''
PRP Part_Status ''
PRP Power_(Watts) '100mW'
PRP Ratings 'AEC-Q200'
PRP Resistance '27k'
PRP RoHS 'Yes'
PRP Series 'ERJ-2RK'
PRP Size_/_Dimension '0.039_ L x 0.020_ W (1.00mm x 0.50mm)'
PRP Supplier_1 'Digikey'
PRP Supplier_Part_Number_1 'P27.0KLCT-ND'
PRP Temperature_Coefficient '±100ppm/°C'
PRP Termination_Style ''
PRP Tolerance '±1%'
TOP 0 16.95499784 20.21500148 270 N 1 0 1
TOP 1 16.95499784 21.17499956 270 N 2 0 2
#
# CMP 17
CMP 0 16.6249985 22.29000114 0 N C9 Murata_GRM033R61A332KA01D ;0=1,1=0.3300
PRP Applications 'General Purpose'
PRP Capacitance '3.3nF'
PRP Case/Package '0201 (0603 Metric)'
PRP Category ''
PRP Composition 'Ceramic'
PRP Datasheet_URL 'https://www.digikey.com/en/products/detail/murata-electronics/GRM033R61A332KA01D/702429?s=N4IgTCBcDaIOICUCyAGAzGhA2AjAQQzAGk8UcAREAXQF8g'
PRP Dielectric_Material ''
PRP ESR_(Equivalent_Series_Resistance) ''
PRP Failure_Rate ''
PRP Features ''
PRP Height '0.013_ (0.33mm)'
PRP Impedance ''
PRP Lead_Spacing ''
PRP Lead_Style ''
PRP Manufacturer 'Murata'
PRP Manufacturer_Part_Number 'GRM033R61A332KA01D'
PRP Max_Operating_Temperature '85°C'
PRP Min_Operating_Temperature '-55°C'
PRP Mounting_Type ''
PRP Part_Status ''
PRP Polarization 'Non-polar'
PRP Ratings ''
PRP RoHS 'Yes'
PRP Series 'GRM'
PRP Size_/_Dimension '0.024_ L x 0.012_ W (0.60mm x 0.30mm)'
PRP Supplier_1 'Digikey'
PRP Supplier_Part_Number_1 '490-3163-1-ND'
PRP Temperature_Coefficient 'X5R'
PRP Thickness_(Max) ''
PRP Tolerance '±10%'
PRP Type ''
PRP Voltage_-_Rated ''
PRP Voltage_Rating '10V'
PRP Voltage_Rating_-_AC ''
PRP Voltage_Rating_-_DC ''
TOP 0 16.95499784 22.29000114 180 N 2 1 1
TOP 1 16.29499916 22.29000114 180 N 14 12 2
#
# CMP 18
CMP 6 23.41500016 16.85250122 180 N L1 4.7uH ;0=1,1=3.0000
PRP Manufacturer 'Eaton'
PRP Manufacturer_Part_Number 'HCM0703-4R7-R'
TOP 0 20.76500038 16.85250122 0 N 4 4 1
TOP 1 26.06499994 16.85250122 0 N 16 5 2
#
# CMP 19
CMP 11 14.38500044 18.0150008 0 N R4 Yageo_RC0402FR-0730KL ;0=1,1=0.4000
PRP Case/Package '0402 (1005 Metric)'
PRP Category 'Chip Resistor - Surface Mount'
PRP Composition 'Thick Film'
PRP Datasheet_URL 'https://www.yageo.com/upload/media/product/productsearch/datasheet/rchip/PYu-RC_Group_51_RoHS_L_11.pdf'
PRP Features ''
PRP Height '0.016_ (0.40mm)'
PRP Manufacturer 'Yageo'
PRP Manufacturer_Part_Number 'RC0402FR-0730KL'
PRP Max_Operating_Temperature '155°C'
PRP Min_Operating_Temperature '-55°C'
PRP Mounting_Type ''
PRP Part_Status ''
PRP Power_(Watts) '62.5mW'
PRP Ratings ''
PRP Resistance '30k'
PRP RoHS ''
PRP Series 'RC_L'
PRP Size_/_Dimension '0.039_ L x 0.020_ W (1.00mm x 0.50mm)'
PRP Supplier_1 'Digi-Key'
PRP Supplier_Part_Number_1 '311-30.0KLRCT-ND'
PRP Temperature_Coefficient '±100ppm/°C'
PRP Termination_Style ''
PRP Tolerance '±1%'
TOP 0 14.86499948 18.0150008 180 N 3 0 1
TOP 1 13.9050014 18.0150008 180 N 14 6 2
#
# CMP 20
CMP 1 23.4150027 12.29000082 0 N C12 Murata_GRM155R61H104KE14D ;0=1,1=0.5500
PRP Applications 'General Purpose'
PRP Capacitance '0.1µF'
PRP Case/Package '0402 (1005 Metric)'
PRP Category 'Ceramic Capacitors'
PRP Composition 'Ceramic'
PRP Datasheet_URL 'https://www.digikey.com/en/products/detail/murata-electronics/GRM155R61H104KE14D/4905152?s=N4IgTCBcDaIOICUCyBGArGhA2FAJFADACwDSAoikQCIgC6AvkA'
PRP Dielectric_Material ''
PRP ESR_(Equivalent_Series_Resistance) ''
PRP Failure_Rate ''
PRP Features ''
PRP Height '0.022_ (0.55mm)'
PRP Impedance ''
PRP Lead_Spacing ''
PRP Lead_Style ''
PRP Manufacturer 'Murata'
PRP Manufacturer_Part_Number 'GRM155R61H104KE14D'
PRP Max_Operating_Temperature '85°C'
PRP Min_Operating_Temperature '-55°C'
PRP Mounting_Type 'Surface Mount, MLCC'
PRP Part_Status ''
PRP Polarization 'Non-polar'
PRP Ratings ''
PRP RoHS 'Yes'
PRP Series 'GRM155R61H'
PRP Size_/_Dimension '0.039_ L x 0.020_ W (1.00mm x 0.50mm)'
PRP Supplier_1 'Digikey'
PRP Supplier_Part_Number_1 '490-10697-1-ND'
PRP Temperature_Coefficient 'X5R'
PRP Thickness_(Max) ''
PRP Tolerance '±10%'
PRP Type ''
PRP Voltage_-_Rated ''
PRP Voltage_Rating '50V'
PRP Voltage_Rating_-_AC ''
PRP Voltage_Rating_-_DC ''
TOP 0 23.87500178 12.29000082 180 N 16 3 1
TOP 1 22.95500362 12.29000082 180 N 14 13 2
#
# CMP 21
CMP 5 17.16499996 17.96500344 180 N U3 DiodesInc_AP63356QZV-7 ;0=1,1=0.9000
PRP ComponentLink1Description 'Datasheet'
PRP ComponentLink1URL ''
PRP Manufacturer 'Diodes Incorporated'
PRP Manufacturer_Part_Number 'AP63356QZV-7'
PRP Supplier_1 ''
PRP Supplier_Part_Number_1 ''
PRP System 'connector'
TOP 0 16.41500146 16.99000158 0 N 15 5 1
TOP 1 16.31500166 18.04000202 0 N 15 6 2
TOP 2 16.31500166 18.49000112 0 N 3 2 3
TOP 3 16.31500166 18.94000276 0 N 1 1 4
TOP 4 18.0150008 18.94000276 0 N 0 17 5
TOP 5 18.0150008 18.49000112 0 N 5 1 6
TOP 6 18.0150008 18.04000202 0 N 4 2 7
TOP 7 17.915001 16.99000158 0 N 14 17 8
TOP 8 17.1650025 16.85250122 0 N 4 3 9
#
# CMP 22
CMP 13 33.7400011 7.6400025 180 N R3 Yageo_RC1206JR-070RL ;0=1,1=0.7000
PRP Case/Package '1206 (3216 Metric)'
PRP Category 'Chip Resistor - Surface Mount'
PRP Composition 'Thick Film'
PRP Datasheet_URL 'https://www.digikey.com/en/products/detail/yageo/RC1206JR-070RL/729184?s=N4IgTCBcDaIEoGECMYAMA2AUnAtKg7KnADIgC6AvkA'
PRP Features 'Moisture Resistant'
PRP Height '0.026_ (0.65mm)'
PRP Manufacturer 'Yageo'
PRP Manufacturer_Part_Number 'RC1206JR-070RL'
PRP Max_Operating_Temperature '155°C'
PRP Min_Operating_Temperature '-55°C'
PRP Mounting_Type ''
PRP Part_Status ''
PRP Power_(Watts) '250mW'
PRP Ratings ''
PRP Resistance '0'
PRP RoHS 'Yes'
PRP Series 'RC_L'
PRP Size_/_Dimension '0.122_ L x 0.063_ W (3.10mm x 1.60mm)'
PRP Supplier_1 'Digikey'
PRP Supplier_Part_Number_1 '311-0.0ERCT-ND'
PRP Temperature_Coefficient ''
PRP Termination_Style ''
PRP Tolerance 'Jumper'
TOP 0 32.24000156 7.63999996 0 N 16 7 1
TOP 1 35.24000064 7.63999996 0 N 6 3 2
#
# CMP 23
CMP 12 39.78999916 15.24 270 N R1 100k ;0=1,1=0.5500
PRP Manufacturer 'Panasonic'
PRP Manufacturer_Part_Number 'ERJ-3EKF1003V'
TOP 0 39.78999916 14.51500018 0 N 14 19 1
TOP 1 39.78999916 15.96499982 0 N 13 0 2
#
# CMP 24
CMP 1 18.68000074 21.17499956 180 N C3 Murata_GRM155R61H104KE14D ;0=1,1=0.5500
PRP Applications 'General Purpose'
PRP Capacitance '0.1µF'
PRP Case/Package '0402 (1005 Metric)'
PRP Category 'Ceramic Capacitors'
PRP Composition 'Ceramic'
PRP Datasheet_URL 'https://www.digikey.com/en/products/detail/murata-electronics/GRM155R61H104KE14D/4905152?s=N4IgTCBcDaIOICUCyBGArGhA2FAJFADACwDSAoikQCIgC6AvkA'
PRP Dielectric_Material ''
PRP ESR_(Equivalent_Series_Resistance) ''
PRP Failure_Rate ''
PRP Features ''
PRP Height '0.022_ (0.55mm)'
PRP Impedance ''
PRP Lead_Spacing ''
PRP Lead_Style ''
PRP Manufacturer 'Murata'
PRP Manufacturer_Part_Number 'GRM155R61H104KE14D'
PRP Max_Operating_Temperature '85°C'
PRP Min_Operating_Temperature '-55°C'
PRP Mounting_Type 'Surface Mount, MLCC'
PRP Part_Status ''
PRP Polarization 'Non-polar'
PRP Ratings ''
PRP RoHS 'Yes'
PRP Series 'GRM155R61H'
PRP Size_/_Dimension '0.039_ L x 0.020_ W (1.00mm x 0.50mm)'
PRP Supplier_1 'Digikey'
PRP Supplier_Part_Number_1 '490-10697-1-ND'
PRP Temperature_Coefficient 'X5R'
PRP Thickness_(Max) ''
PRP Tolerance '±10%'
PRP Type ''
PRP Voltage_-_Rated ''
PRP Voltage_Rating '50V'
PRP Voltage_Rating_-_AC ''
PRP Voltage_Rating_-_DC ''
TOP 0 18.22000166 21.17499956 0 N 5 0 1
TOP 1 19.13999982 21.17499956 0 N 4 1 2
#
# CMP 25
CMP 4 16.81500066 9.79000074 180 N C5 Murata_GRM21BR6YA106KE43L ;0=1,1=1.4500
PRP Applications 'General Purpose'
PRP Capacitance '10µF'
PRP Case/Package '0805 (2013 Metric)'
PRP Category 'Ceramic Capacitors'
PRP Composition 'Ceramic'
PRP Datasheet_URL 'https://www.digikey.com/en/products/detail/murata-electronics/GRM21BR6YA106KE43L/5027598?s=N4IgTCBcDaIOICUCyYCMAhBA2AmgQVQAYsBpAUQBYBmAGRAF0BfIA'
PRP Dielectric_Material ''
PRP ESR_(Equivalent_Series_Resistance) ''
PRP Failure_Rate ''
PRP Features ''
PRP Height '0.057_ (1.45mm)'
PRP Impedance ''
PRP Lead_Spacing ''
PRP Lead_Style ''
PRP Manufacturer 'Murata'
PRP Manufacturer_Part_Number 'GRM21BR6YA106KE43L'
PRP Max_Operating_Temperature '85°C'
PRP Min_Operating_Temperature '-55°C'
PRP Mounting_Type 'Surface Mount, MLCC'
PRP Part_Status ''
PRP Polarization 'Non-polar'
PRP Ratings ''
PRP RoHS 'Yes'
PRP Series 'GRM21BR6YA'
PRP Size_/_Dimension '0.079_ L x 0.049_ W (2.00mm x 1.25mm)'
PRP Supplier_1 'Digikey'
PRP Supplier_Part_Number_1 '490-10514-1-ND'
PRP Temperature_Coefficient 'X5R'
PRP Thickness_(Max) ''
PRP Tolerance '±10%'
PRP Type ''
PRP Voltage_-_Rated ''
PRP Voltage_Rating '35V'
PRP Voltage_Rating_-_AC ''
PRP Voltage_Rating_-_DC ''
TOP 0 15.91499992 9.7899982 0 N 15 4 1
TOP 1 17.7150014 9.7899982 0 N 14 16 2
#
# CMP 26
CMP 1 40.0900011 8.09999904 270 N C2 Murata_GRM155R61H104KE14D ;0=1,1=0.5500
PRP Applications 'General Purpose'
PRP Capacitance '0.1µF'
PRP Case/Package '0402 (1005 Metric)'
PRP Category 'Ceramic Capacitors'
PRP Composition 'Ceramic'
PRP Datasheet_URL 'https://www.digikey.com/en/products/detail/murata-electronics/GRM155R61H104KE14D/4905152?s=N4IgTCBcDaIOICUCyBGArGhA2FAJFADACwDSAoikQCIgC6AvkA'
PRP Dielectric_Material ''
PRP ESR_(Equivalent_Series_Resistance) ''
PRP Failure_Rate ''
PRP Features ''
PRP Height '0.022_ (0.55mm)'
PRP Impedance ''
PRP Lead_Spacing ''
PRP Lead_Style ''
PRP Manufacturer 'Murata'
PRP Manufacturer_Part_Number 'GRM155R61H104KE14D'
PRP Max_Operating_Temperature '85°C'
PRP Min_Operating_Temperature '-55°C'
PRP Mounting_Type 'Surface Mount, MLCC'
PRP Part_Status ''
PRP Polarization 'Non-polar'
PRP Ratings ''
PRP RoHS 'Yes'
PRP Series 'GRM155R61H'
PRP Size_/_Dimension '0.039_ L x 0.020_ W (1.00mm x 0.50mm)'
PRP Supplier_1 'Digikey'
PRP Supplier_Part_Number_1 '490-10697-1-ND'
PRP Temperature_Coefficient 'X5R'
PRP Thickness_(Max) ''
PRP Tolerance '±10%'
PRP Type ''
PRP Voltage_-_Rated ''
PRP Voltage_Rating '50V'
PRP Voltage_Rating_-_AC ''
PRP Voltage_Rating_-_DC ''
TOP 0 40.0900011 7.63999996 270 N 6 1 1
TOP 1 40.0900011 8.55999812 270 N 14 7 2
#
# CMP 27
CMP 2 38.30999958 9.94000044 180 N C1 Murata_GRM155R6YA105KE11D ;0=1,1=0.6100
PRP Applications 'General Purpose'
PRP Capacitance '1µF'
PRP Case/Package '0402 (1005 Metric)'
PRP Category 'Ceramic Capacitors'
PRP Composition 'Ceramic'
PRP Datasheet_URL 'https://www.digikey.com/en/products/detail/murata-electronics/GRM155R6YA105KE11D/4905162?s=N4IgTCBcDaIOICUCyBGArGhA2AmgQRQAY0BpAURRQBEQBdAXyA'
PRP Dielectric_Material ''
PRP ESR_(Equivalent_Series_Resistance) ''
PRP Failure_Rate ''
PRP Features ''
PRP Height '0.024_ (0.60mm)'
PRP Impedance ''
PRP Lead_Spacing ''
PRP Lead_Style ''
PRP Manufacturer 'Murata'
PRP Manufacturer_Part_Number 'GRM155R6YA105KE11D'
PRP Max_Operating_Temperature '85°C'
PRP Min_Operating_Temperature '-55°C'
PRP Mounting_Type 'Surface Mount, MLCC'
PRP Part_Status ''
PRP Polarization 'Non-polar'
PRP Ratings ''
PRP RoHS 'Yes'
PRP Series 'GRM155R6YA'
PRP Size_/_Dimension '0.039_ L x 0.020_ W (1.00mm x 0.50mm)'
PRP Supplier_1 'Digikey'
PRP Supplier_Part_Number_1 '490-10019-1-ND'
PRP Temperature_Coefficient 'X5R'
PRP Thickness_(Max) ''
PRP Tolerance '±10%'
PRP Type ''
PRP Voltage_-_Rated ''
PRP Voltage_Rating '35V'
PRP Voltage_Rating_-_AC ''
PRP Voltage_Rating_-_DC ''
TOP 0 37.8500005 9.94000044 0 N 6 2 1
TOP 1 38.76999866 9.94000044 0 N 14 14 2
#
# CMP 28
CMP 0 14.86499948 20.54500082 90 N C4 Murata_GRM0335C1E330JA01D ;0=1,1=0.3300
PRP Applications 'General Purpose'
PRP Capacitance '33pF'
PRP Case/Package '0201 (0603 Metric)'
PRP Category 'Ceramic Capacitors'
PRP Composition 'Ceramic'
PRP Datasheet_URL 'https://www.digikey.com/en/products/detail/murata-electronics/GRM0335C1E330JA01D/4358214?s=N4IgTCBcDaIOICUCyAGAzGgrAYQIwFEMUApAQRVwBEQBdAXyA'
PRP Dielectric_Material ''
PRP ESR_(Equivalent_Series_Resistance) ''
PRP Failure_Rate ''
PRP Features ''
PRP Height '0.013_ (0.33mm)'
PRP Impedance ''
PRP Lead_Spacing ''
PRP Lead_Style ''
PRP Manufacturer 'Murata'
PRP Manufacturer_Part_Number 'GRM0335C1E330JA01D'
PRP Max_Operating_Temperature '125°C'
PRP Min_Operating_Temperature '-55°C'
PRP Mounting_Type 'Surface Mount, MLCC'
PRP Part_Status ''
PRP Polarization 'Non-polar'
PRP Ratings ''
PRP RoHS 'Yes'
PRP Series 'GRM0335C1E'
PRP Size_/_Dimension '0.024_ L x 0.012_ W (0.60mm x 0.30mm)'
PRP Supplier_1 'Digikey'
PRP Supplier_Part_Number_1 '490-10678-1-ND'
PRP Temperature_Coefficient 'C0G, NP0'
PRP Thickness_(Max) ''
PRP Tolerance '±5%'
PRP Type ''
PRP Voltage_-_Rated ''
PRP Voltage_Rating '25V'
PRP Voltage_Rating_-_AC ''
PRP Voltage_Rating_-_DC ''
TOP 0 14.86499948 20.87500016 90 N 16 1 1
TOP 1 14.86499948 20.21500148 90 N 3 1 2
#
# CMP 29
CMP 14 20.24000016 42.13999954 0 N J2 Wurth_9774040243R ;0=2,1=4.0000
PRP Actual_Diameter ''
PRP Applications ''
PRP Board_Thickness ''
PRP Cable_End_Type ''
PRP Category 'Board Spacers, Standoffs'
PRP Color ''
PRP Connector_Style ''
PRP Connector_Type ''
PRP Contact_Finish ''
PRP Contact_Material 'Steel'
PRP Contact_Shape ''
PRP Contact_Type ''
PRP Current_Rating ''
PRP Datasheet_URL 'https://www.digikey.com/en/products/detail/w%C3%BCrth-elektronik/9774040243R/5320633?s=N4IgTCBcDaIJwHYEBYAMazIMwCUQF0BfIA'
PRP Fastening_Type ''
PRP Features ''
PRP FFC__FCB_Thickness ''
PRP Flange_Diameter ''
PRP Flat_Flex_Type ''
PRP Frequency_-_Max ''
PRP Height '0.157_ (4.00mm)'
PRP Impedance ''
PRP Includes ''
PRP Industry_Recognized_Mating_Diameter ''
PRP Insulation ''
PRP Internal_Switch(s) ''
PRP Length_-_Above_Flange ''
PRP Length_-_Below_Flange ''
PRP Length_-_Overall ''
PRP Locking_Feature ''
PRP Manufacturer 'Wurth Elektronik'
PRP Manufacturer_Part_Number '9774040243R'
PRP Mated_Stacking_Heights ''
PRP Mating_Length/Depth ''
PRP Mating_Orientation ''
PRP Max_Operating_Temperature '150°C'
PRP Min_Operating_Temperature '-55°C'
PRP Mounting__Pins ''
PRP Mounting_Feature ''
PRP Mounting_Hole_Diameter ''
PRP Mounting_Type 'Through Hole, Vertical'
PRP Number_of_Levels ''
PRP Number_of_Ports ''
PRP Number_of_Positions/Contacts ''
PRP Part_Status ''
PRP Pin_Size_-_Above_Flange ''
PRP Pin_Size_-_Below_Flange ''
PRP Pitch ''
PRP Positions_Per_Level ''
PRP RoHS 'Yes'
PRP Rows ''
PRP Screw_Thread 'M2x0.4'
PRP Series 'WA-SMSI'
PRP Shielding ''
PRP Shrouded ''
PRP Signal_Lines ''
PRP Signal_Pins ''
PRP Size_/_Dimension ''
PRP Special_Notes ''
PRP Specifications ''
PRP Style ''
PRP Supplier_1 'Digikey'
PRP Supplier_Part_Number_1 '732-7090-1-ND'
PRP System 'connector'
PRP Terminal_Style ''
PRP Terminal_Type ''
PRP Termination ''
PRP Torque_-_Screw ''
PRP Type 'Round Standoff'
PRP Voltage_Rating ''
PRP Wire_Gauge ''
PRP Wire_Termination ''
TOP 0 20.24000016 42.13999954 180 N 0 28 MT1
#
# CMP 30
CMP 14 20.43999976 -1.26000002 0 N J1 Wurth_9774040243R ;0=2,1=4.0000
PRP Actual_Diameter ''
PRP Applications ''
PRP Board_Thickness ''
PRP Cable_End_Type ''
PRP Category 'Board Spacers, Standoffs'
PRP Color ''
PRP Connector_Style ''
PRP Connector_Type ''
PRP Contact_Finish ''
PRP Contact_Material 'Steel'
PRP Contact_Shape ''
PRP Contact_Type ''
PRP Current_Rating ''
PRP Datasheet_URL 'https://www.digikey.com/en/products/detail/w%C3%BCrth-elektronik/9774040243R/5320633?s=N4IgTCBcDaIJwHYEBYAMazIMwCUQF0BfIA'
PRP Fastening_Type ''
PRP Features ''
PRP FFC__FCB_Thickness ''
PRP Flange_Diameter ''
PRP Flat_Flex_Type ''
PRP Frequency_-_Max ''
PRP Height '0.157_ (4.00mm)'
PRP Impedance ''
PRP Includes ''
PRP Industry_Recognized_Mating_Diameter ''
PRP Insulation ''
PRP Internal_Switch(s) ''
PRP Length_-_Above_Flange ''
PRP Length_-_Below_Flange ''
PRP Length_-_Overall ''
PRP Locking_Feature ''
PRP Manufacturer 'Wurth Elektronik'
PRP Manufacturer_Part_Number '9774040243R'
PRP Mated_Stacking_Heights ''
PRP Mating_Length/Depth ''
PRP Mating_Orientation ''
PRP Max_Operating_Temperature '150°C'
PRP Min_Operating_Temperature '-55°C'
PRP Mounting__Pins ''
PRP Mounting_Feature ''
PRP Mounting_Hole_Diameter ''
PRP Mounting_Type 'Through Hole, Vertical'
PRP Number_of_Levels ''
PRP Number_of_Ports ''
PRP Number_of_Positions/Contacts ''
PRP Part_Status ''
PRP Pin_Size_-_Above_Flange ''
PRP Pin_Size_-_Below_Flange ''
PRP Pitch ''
PRP Positions_Per_Level ''
PRP RoHS 'Yes'
PRP Rows ''
PRP Screw_Thread 'M2x0.4'
PRP Series 'WA-SMSI'
PRP Shielding ''
PRP Shrouded ''
PRP Signal_Lines ''
PRP Signal_Pins ''
PRP Size_/_Dimension ''
PRP Special_Notes ''
PRP Specifications ''
PRP Style ''
PRP Supplier_1 'Digikey'
PRP Supplier_Part_Number_1 '732-7090-1-ND'
PRP System 'connector'
PRP Terminal_Style ''
PRP Terminal_Type ''
PRP Termination ''
PRP Torque_-_Screw ''
PRP Type 'Round Standoff'
PRP Voltage_Rating ''
PRP Wire_Gauge ''
PRP Wire_Termination ''
TOP 0 20.43999976 -1.26000002 180 N 0 22 MT1
#
# CMP 31
CMP 3 23.3150029 7.78999966 0 N C11 Murata_GRM21BR61A226ME51L ;0=1,1=1.4000
PRP Applications 'General Purpose'
PRP Capacitance '22µF'
PRP Case/Package '0805 (2013 Metric)'
PRP Category 'Ceramic Capacitors'
PRP Composition 'Ceramic'
PRP Datasheet_URL 'https://www.digikey.com/en/products/detail/murata-electronics/GRM21BR61A226ME51L/5027595?s=N4IgTCBcDaIOICUCyYCMAhBA2VBBMYWSAogKyoAyIAugL5A'
PRP Dielectric_Material ''
PRP ESR_(Equivalent_Series_Resistance) ''
PRP Failure_Rate ''
PRP Features ''
PRP Height '0.055_ (1.40mm)'
PRP Impedance ''
PRP Lead_Spacing ''
PRP Lead_Style ''
PRP Manufacturer 'Murata'
PRP Manufacturer_Part_Number 'GRM21BR61A226ME51L'
PRP Max_Operating_Temperature '85°C'
PRP Min_Operating_Temperature '-55°C'
PRP Mounting_Type 'Surface Mount, MLCC'
PRP Part_Status ''
PRP Polarization 'Non-polar'
PRP Ratings ''
PRP RoHS 'Yes'
PRP Series 'GRM21BR61A'
PRP Size_/_Dimension '0.079_ L x 0.049_ W (2.00mm x 1.25mm)'
PRP Supplier_1 'Digikey'
PRP Supplier_Part_Number_1 '490-10511-1-ND'
PRP Temperature_Coefficient 'X5R'
PRP Thickness_(Max) ''
PRP Tolerance '±20%'
PRP Type ''
PRP Voltage_-_Rated ''
PRP Voltage_Rating '10V'
PRP Voltage_Rating_-_AC ''
PRP Voltage_Rating_-_DC ''
TOP 0 24.21500364 7.7900022 180 N 16 4 1
TOP 1 22.41500216 7.7900022 180 N 14 15 2
#
# CMP 32
CMP 3 23.3150029 10.28999974 0 N C10 Murata_GRM21BR61A226ME51L ;0=1,1=1.4000
PRP Applications 'General Purpose'
PRP Capacitance '22µF'
PRP Case/Package '0805 (2013 Metric)'
PRP Category 'Ceramic Capacitors'
PRP Composition 'Ceramic'
PRP Datasheet_URL 'https://www.digikey.com/en/products/detail/murata-electronics/GRM21BR61A226ME51L/5027595?s=N4IgTCBcDaIOICUCyYCMAhBA2VBBMYWSAogKyoAyIAugL5A'
PRP Dielectric_Material ''
PRP ESR_(Equivalent_Series_Resistance) ''
PRP Failure_Rate ''
PRP Features ''
PRP Height '0.055_ (1.40mm)'
PRP Impedance ''
PRP Lead_Spacing ''
PRP Lead_Style ''
PRP Manufacturer 'Murata'
PRP Manufacturer_Part_Number 'GRM21BR61A226ME51L'
PRP Max_Operating_Temperature '85°C'
PRP Min_Operating_Temperature '-55°C'
PRP Mounting_Type 'Surface Mount, MLCC'
PRP Part_Status ''
PRP Polarization 'Non-polar'
PRP Ratings ''
PRP RoHS 'Yes'
PRP Series 'GRM21BR61A'
PRP Size_/_Dimension '0.079_ L x 0.049_ W (2.00mm x 1.25mm)'
PRP Supplier_1 'Digikey'
PRP Supplier_Part_Number_1 '490-10511-1-ND'
PRP Temperature_Coefficient 'X5R'
PRP Thickness_(Max) ''
PRP Tolerance '±20%'
PRP Type ''
PRP Voltage_-_Rated ''
PRP Voltage_Rating '10V'
PRP Voltage_Rating_-_AC ''
PRP Voltage_Rating_-_DC ''
TOP 0 24.21500364 10.29000228 180 N 16 2 1
TOP 1 22.41500216 10.29000228 180 N 14 8 2
#
# CMP 33
CMP 1 17.1150026 14.7900009 180 N C6 Murata_GRM155R61H104KE14D ;0=1,1=0.5500
PRP Applications 'General Purpose'
PRP Capacitance '0.1µF'
PRP Case/Package '0402 (1005 Metric)'
PRP Category 'Ceramic Capacitors'
PRP Composition 'Ceramic'
PRP Datasheet_URL 'https://www.digikey.com/en/products/detail/murata-electronics/GRM155R61H104KE14D/4905152?s=N4IgTCBcDaIOICUCyBGArGhA2FAJFADACwDSAoikQCIgC6AvkA'
PRP Dielectric_Material ''
PRP ESR_(Equivalent_Series_Resistance) ''
PRP Failure_Rate ''
PRP Features ''
PRP Height '0.022_ (0.55mm)'
PRP Impedance ''
PRP Lead_Spacing ''
PRP Lead_Style ''
PRP Manufacturer 'Murata'
PRP Manufacturer_Part_Number 'GRM155R61H104KE14D'
PRP Max_Operating_Temperature '85°C'
PRP Min_Operating_Temperature '-55°C'
PRP Mounting_Type 'Surface Mount, MLCC'
PRP Part_Status ''
PRP Polarization 'Non-polar'
PRP Ratings ''
PRP RoHS 'Yes'
PRP Series 'GRM155R61H'
PRP Size_/_Dimension '0.039_ L x 0.020_ W (1.00mm x 0.50mm)'
PRP Supplier_1 'Digikey'
PRP Supplier_Part_Number_1 '490-10697-1-ND'
PRP Temperature_Coefficient 'X5R'
PRP Thickness_(Max) ''
PRP Tolerance '±10%'
PRP Type ''
PRP Voltage_-_Rated ''
PRP Voltage_Rating '50V'
PRP Voltage_Rating_-_AC ''
PRP Voltage_Rating_-_DC ''
TOP 0 16.65500352 14.7900009 0 N 15 1 1
TOP 1 17.57500168 14.7900009 0 N 14 9 2
#
# CMP 34
CMP 3 16.81500066 7.39000046 180 N C8 Murata_GRM21BR61A226ME51L ;0=1,1=1.4000
PRP Applications 'General Purpose'
PRP Capacitance '22µF'
PRP Case/Package '0805 (2013 Metric)'
PRP Category 'Ceramic Capacitors'
PRP Composition 'Ceramic'
PRP Datasheet_URL 'https://www.digikey.com/en/products/detail/murata-electronics/GRM21BR61A226ME51L/5027595?s=N4IgTCBcDaIOICUCyYCMAhBA2VBBMYWSAogKyoAyIAugL5A'
PRP Dielectric_Material ''
PRP ESR_(Equivalent_Series_Resistance) ''
PRP Failure_Rate ''
PRP Features ''
PRP Height '0.055_ (1.40mm)'
PRP Impedance ''
PRP Lead_Spacing ''
PRP Lead_Style ''
PRP Manufacturer 'Murata'
PRP Manufacturer_Part_Number 'GRM21BR61A226ME51L'
PRP Max_Operating_Temperature '85°C'
PRP Min_Operating_Temperature '-55°C'
PRP Mounting_Type 'Surface Mount, MLCC'
PRP Part_Status ''
PRP Polarization 'Non-polar'
PRP Ratings ''
PRP RoHS 'Yes'
PRP Series 'GRM21BR61A'
PRP Size_/_Dimension '0.079_ L x 0.049_ W (2.00mm x 1.25mm)'
PRP Supplier_1 'Digikey'
PRP Supplier_Part_Number_1 '490-10511-1-ND'
PRP Temperature_Coefficient 'X5R'
PRP Thickness_(Max) ''
PRP Tolerance '±20%'
PRP Type ''
PRP Voltage_-_Rated ''
PRP Voltage_Rating '10V'
PRP Voltage_Rating_-_AC ''
PRP Voltage_Rating_-_DC ''
TOP 0 15.91499992 7.38999792 0 N 15 2 1
TOP 1 17.7150014 7.38999792 0 N 14 10 2
#
# CMP 35
CMP 4 16.81500066 12.39000316 180 N C7 Murata_GRM21BR6YA106KE43L ;0=1,1=1.4500
PRP Applications 'General Purpose'
PRP Capacitance '10µF'
PRP Case/Package '0805 (2013 Metric)'
PRP Category 'Ceramic Capacitors'
PRP Composition 'Ceramic'
PRP Datasheet_URL 'https://www.digikey.com/en/products/detail/murata-electronics/GRM21BR6YA106KE43L/5027598?s=N4IgTCBcDaIOICUCyYCMAhBA2AmgQVQAYsBpAUQBYBmAGRAF0BfIA'
PRP Dielectric_Material ''
PRP ESR_(Equivalent_Series_Resistance) ''
PRP Failure_Rate ''
PRP Features ''
PRP Height '0.057_ (1.45mm)'
PRP Impedance ''
PRP Lead_Spacing ''
PRP Lead_Style ''
PRP Manufacturer 'Murata'
PRP Manufacturer_Part_Number 'GRM21BR6YA106KE43L'
PRP Max_Operating_Temperature '85°C'
PRP Min_Operating_Temperature '-55°C'
PRP Mounting_Type 'Surface Mount, MLCC'
PRP Part_Status ''
PRP Polarization 'Non-polar'
PRP Ratings ''
PRP RoHS 'Yes'
PRP Series 'GRM21BR6YA'
PRP Size_/_Dimension '0.079_ L x 0.049_ W (2.00mm x 1.25mm)'
PRP Supplier_1 'Digikey'
PRP Supplier_Part_Number_1 '490-10514-1-ND'
PRP Temperature_Coefficient 'X5R'
PRP Thickness_(Max) ''
PRP Tolerance '±10%'
PRP Type ''
PRP Voltage_-_Rated ''
PRP Voltage_Rating '35V'
PRP Voltage_Rating_-_AC ''
PRP Voltage_Rating_-_DC ''
TOP 0 15.91499992 12.39000062 0 N 15 3 1
TOP 1 17.7150014 12.39000062 0 N 14 11 2
#

### steps/pcb/layers/comp_+_top/components
UNITS=MM
#
#Component attribute names
#
@0 .comp_mount_type
@1 .comp_height

# CMP 0
CMP 7 21.3400005 20.33999996 180 N U2 IQD_ICPT-1 ;0=2,1=14.5000
PRP ComponentLink1Description 'Datasheet'
PRP ComponentLink1URL ''
PRP Manufacturer 'IQD'
PRP Manufacturer_Part_Number 'IQD-ICPT-1'
PRP Supplier_1 ''
PRP Supplier_Part_Number_1 ''
TOP 0 4.8300005 33.03999996 90 N 0 23 1
TOP 1 4.8300005 17.79999996 90 N 0 24 2
TOP 2 4.8300005 12.71999996 90 N 7 1 3
TOP 3 4.8300005 7.63999996 90 N 8 1 4
TOP 4 37.8500005 7.63999996 90 N 6 4 5
TOP 5 37.8500005 12.71999996 90 N 14 21 6
TOP 6 37.8500005 17.79999996 90 N 13 2 7
TOP 7 37.8500005 22.87999996 90 N 12 0 8
TOP 8 37.8500005 33.03999996 180 N 9 0 9
#
# CMP 1
CMP 9 21.3400005 20.33999996 180 N U1 Microchip_SA45 ;0=2,1=11.4300
PRP ComponentLink1Description 'Datasheet'
PRP ComponentLink1URL ''
PRP Manufacturer 'Microchip'
PRP Manufacturer_Part_Number '090-02984-001'
PRP Supplier_1 ''
PRP Supplier_Part_Number_1 ''
PRP System 'connector'
TOP 0 4.8300005 33.03999996 90 N 0 27 1
TOP 1 4.8300005 17.79999996 90 N 0 26 4
TOP 2 4.8300005 12.71999996 90 N 7 2 5
TOP 3 4.8300005 7.63999996 90 N 8 2 6
TOP 4 37.8500005 7.63999996 90 N 6 5 7
TOP 5 37.8500005 12.71999996 90 N 14 22 8
TOP 6 37.8500005 17.79999996 90 N 13 3 9
TOP 7 37.8500005 22.87999996 90 N 12 1 10
TOP 8 37.8500005 33.03999996 180 N 9 1 12
#

### steps/pcb/layers/drill_non-plated_bottom-top/tools
UNITS=MM
THICKNESS=0
USER_PARAMS=

TOOLS {
    NUM=1
    TYPE=NON_PLATED
    MIN_TOL=50.8
    MAX_TOL=50.8
    BIT=
    FINISH_SIZE=2999.99908
    DRILL_SIZE=2999.99908
}

### steps/pcb/layers/drill_plated_bottom-top/tools
UNITS=MM
THICKNESS=0
USER_PARAMS=

TOOLS {
    NUM=1
    TYPE=VIA
    MIN_TOL=299.9994
    MAX_TOL=0
    BIT=
    FINISH_SIZE=299.9994
    DRILL_SIZE=299.9994
}

TOOLS {
    NUM=2
    TYPE=PLATED
    MIN_TOL=0
    MAX_TOL=0
    BIT=
    FINISH_SIZE=762
    DRILL_SIZE=762
}

TOOLS {
    NUM=3
    TYPE=PLATED
    MIN_TOL=0
    MAX_TOL=0
    BIT=
    FINISH_SIZE=961.9996
    DRILL_SIZE=961.9996
}

TOOLS {
    NUM=4
    TYPE=PLATED
    MIN_TOL=76.2
    MAX_TOL=76.2
    BIT=
    FINISH_SIZE=1090.00036
    DRILL_SIZE=1090.00036
}

TOOLS {
    NUM=5
    TYPE=PLATED
    MIN_TOL=75.00112
    MAX_TOL=75.00112
    BIT=
    FINISH_SIZE=1200.00014
    DRILL_SIZE=1200.00014
}

TOOLS {
    NUM=6
    TYPE=PLATED
    MIN_TOL=75.00112
    MAX_TOL=75.00112
    BIT=
    FINISH_SIZE=3700.00022
    DRILL_SIZE=3700.00022
}

